G04 ================== begin FILE IDENTIFICATION RECORD ==================*
G04 Layout Name:  x887571-005_osp.brd*
G04 Film Name:    fab-sh2_8-layer*
G04 File Format:  Gerber RS274X*
G04 File Origin:  Cadence Allegro 16.3-S036*
G04 Origin Date:  Thu Jul 03 00:06:56 2014*
G04 *
G04 Layer:  MANUFACTURING/NCDRILL_FIGURE*
G04 Layer:  MANUFACTURING/NCLEGEND-1-8*
G04 Layer:  DRAWING FORMAT/OUTLINE*
G04 Layer:  DRAWING FORMAT/FAB-SHT2_8-LAYER*
G04 Layer:  DRAWING FORMAT/FAB-SHT2*
G04 Layer:  BOARD GEOMETRY/OUTLINE*
G04 Layer:  BOARD GEOMETRY/DIMENSION*
G04 *
G04 Offset:    (0.0000 0.0000)*
G04 Mirror:    No*
G04 Mode:      Positive*
G04 Rotation:  0*
G04 FullContactRelief:  No*
G04 UndefLineWidth:     4.0000*
G04 ================== end FILE IDENTIFICATION RECORD ====================*
%FSLAX25Y25*MOIN*%
%IR0*IPPOS*OFA0.00000B0.00000*MIA0B0*SFA1.00000B1.00000*%
%AMMACRO29*
1,1,.004,.0125,0.0*
20,1,.004,.0125,0.0,-.0125,0.0,0.0*
1,1,.004,-.0125,0.0*
1,1,.004,0.0,.0125*
20,1,.004,0.0,.0125,0.0,-.0125,0.0*
1,1,.004,0.0,-.0125*
%
%ADD29MACRO29*%
%AMMACRO24*
1,1,.004,.015,0.0*
20,1,.004,.015,0.0,.014772,-.002605,0.0*
1,1,.004,.014772,-.002605*
20,1,.004,.014772,-.002605,.014095,-.00513,0.0*
1,1,.004,.014095,-.00513*
20,1,.004,.014095,-.00513,.01299,-.0075,0.0*
1,1,.004,.01299,-.0075*
20,1,.004,.01299,-.0075,.011491,-.009642,0.0*
1,1,.004,.011491,-.009642*
20,1,.004,.011491,-.009642,.009642,-.011491,0.0*
1,1,.004,.009642,-.011491*
20,1,.004,.009642,-.011491,.0075,-.01299,0.0*
1,1,.004,.0075,-.01299*
20,1,.004,.0075,-.01299,.00513,-.014095,0.0*
1,1,.004,.00513,-.014095*
20,1,.004,.00513,-.014095,.002605,-.014772,0.0*
1,1,.004,.002605,-.014772*
20,1,.004,.002605,-.014772,0.0,-.015,0.0*
1,1,.004,0.0,-.015*
20,1,.004,0.0,-.015,-.002605,-.014772,0.0*
1,1,.004,-.002605,-.014772*
20,1,.004,-.002605,-.014772,-.00513,-.014095,0.0*
1,1,.004,-.00513,-.014095*
20,1,.004,-.00513,-.014095,-.0075,-.01299,0.0*
1,1,.004,-.0075,-.01299*
20,1,.004,-.0075,-.01299,-.009642,-.011491,0.0*
1,1,.004,-.009642,-.011491*
20,1,.004,-.009642,-.011491,-.011491,-.009642,0.0*
1,1,.004,-.011491,-.009642*
20,1,.004,-.011491,-.009642,-.01299,-.0075,0.0*
1,1,.004,-.01299,-.0075*
20,1,.004,-.01299,-.0075,-.014095,-.00513,0.0*
1,1,.004,-.014095,-.00513*
20,1,.004,-.014095,-.00513,-.014772,-.002605,0.0*
1,1,.004,-.014772,-.002605*
20,1,.004,-.014772,-.002605,-.015,0.0,0.0*
1,1,.004,-.015,0.0*
20,1,.004,-.015,0.0,-.014772,.002605,0.0*
1,1,.004,-.014772,.002605*
20,1,.004,-.014772,.002605,-.014095,.00513,0.0*
1,1,.004,-.014095,.00513*
20,1,.004,-.014095,.00513,-.01299,.0075,0.0*
1,1,.004,-.01299,.0075*
20,1,.004,-.01299,.0075,-.011491,.009642,0.0*
1,1,.004,-.011491,.009642*
20,1,.004,-.011491,.009642,-.009642,.011491,0.0*
1,1,.004,-.009642,.011491*
20,1,.004,-.009642,.011491,-.0075,.01299,0.0*
1,1,.004,-.0075,.01299*
20,1,.004,-.0075,.01299,-.00513,.014095,0.0*
1,1,.004,-.00513,.014095*
20,1,.004,-.00513,.014095,-.002605,.014772,0.0*
1,1,.004,-.002605,.014772*
20,1,.004,-.002605,.014772,0.0,.015,0.0*
1,1,.004,0.0,.015*
20,1,.004,0.0,.015,.002605,.014772,0.0*
1,1,.004,.002605,.014772*
20,1,.004,.002605,.014772,.00513,.014095,0.0*
1,1,.004,.00513,.014095*
20,1,.004,.00513,.014095,.0075,.01299,0.0*
1,1,.004,.0075,.01299*
20,1,.004,.0075,.01299,.009642,.011491,0.0*
1,1,.004,.009642,.011491*
20,1,.004,.009642,.011491,.011491,.009642,0.0*
1,1,.004,.011491,.009642*
20,1,.004,.011491,.009642,.01299,.0075,0.0*
1,1,.004,.01299,.0075*
20,1,.004,.01299,.0075,.014095,.00513,0.0*
1,1,.004,.014095,.00513*
20,1,.004,.014095,.00513,.014772,.002605,0.0*
1,1,.004,.014772,.002605*
20,1,.004,.014772,.002605,.015,0.0,0.0*
1,1,.004,.015,0.0*
1,1,.004,.0075,0.0*
20,1,.004,.0075,0.0,-.0075,0.0,0.0*
1,1,.004,-.0075,0.0*
1,1,.004,0.0,.0075*
20,1,.004,0.0,.0075,0.0,-.0075,0.0*
1,1,.004,0.0,-.0075*
%
%ADD24MACRO24*%
%AMMACRO28*
1,1,.004,.0125,0.0*
20,1,.004,.0125,0.0,0.0,-.0125,0.0*
1,1,.004,0.0,-.0125*
20,1,.004,0.0,-.0125,-.0125,0.0,0.0*
1,1,.004,-.0125,0.0*
20,1,.004,-.0125,0.0,0.0,.0125,0.0*
1,1,.004,0.0,.0125*
20,1,.004,0.0,.0125,.0125,0.0,0.0*
1,1,.004,.0125,0.0*
%
%ADD28MACRO28*%
%AMMACRO21*
1,1,.004,.02,0.0*
20,1,.004,.02,0.0,.019696,-.003473,0.0*
1,1,.004,.019696,-.003473*
20,1,.004,.019696,-.003473,.018794,-.00684,0.0*
1,1,.004,.018794,-.00684*
20,1,.004,.018794,-.00684,.017321,-.01,0.0*
1,1,.004,.017321,-.01*
20,1,.004,.017321,-.01,.015321,-.012856,0.0*
1,1,.004,.015321,-.012856*
20,1,.004,.015321,-.012856,.012856,-.015321,0.0*
1,1,.004,.012856,-.015321*
20,1,.004,.012856,-.015321,.01,-.017321,0.0*
1,1,.004,.01,-.017321*
20,1,.004,.01,-.017321,.00684,-.018794,0.0*
1,1,.004,.00684,-.018794*
20,1,.004,.00684,-.018794,.003473,-.019696,0.0*
1,1,.004,.003473,-.019696*
20,1,.004,.003473,-.019696,0.0,-.02,0.0*
1,1,.004,0.0,-.02*
20,1,.004,0.0,-.02,-.003473,-.019696,0.0*
1,1,.004,-.003473,-.019696*
20,1,.004,-.003473,-.019696,-.00684,-.018794,0.0*
1,1,.004,-.00684,-.018794*
20,1,.004,-.00684,-.018794,-.01,-.017321,0.0*
1,1,.004,-.01,-.017321*
20,1,.004,-.01,-.017321,-.012856,-.015321,0.0*
1,1,.004,-.012856,-.015321*
20,1,.004,-.012856,-.015321,-.015321,-.012856,0.0*
1,1,.004,-.015321,-.012856*
20,1,.004,-.015321,-.012856,-.017321,-.01,0.0*
1,1,.004,-.017321,-.01*
20,1,.004,-.017321,-.01,-.018794,-.00684,0.0*
1,1,.004,-.018794,-.00684*
20,1,.004,-.018794,-.00684,-.019696,-.003473,0.0*
1,1,.004,-.019696,-.003473*
20,1,.004,-.019696,-.003473,-.02,0.0,0.0*
1,1,.004,-.02,0.0*
20,1,.004,-.02,0.0,-.019696,.003473,0.0*
1,1,.004,-.019696,.003473*
20,1,.004,-.019696,.003473,-.018794,.00684,0.0*
1,1,.004,-.018794,.00684*
20,1,.004,-.018794,.00684,-.017321,.01,0.0*
1,1,.004,-.017321,.01*
20,1,.004,-.017321,.01,-.015321,.012856,0.0*
1,1,.004,-.015321,.012856*
20,1,.004,-.015321,.012856,-.012856,.015321,0.0*
1,1,.004,-.012856,.015321*
20,1,.004,-.012856,.015321,-.01,.017321,0.0*
1,1,.004,-.01,.017321*
20,1,.004,-.01,.017321,-.00684,.018794,0.0*
1,1,.004,-.00684,.018794*
20,1,.004,-.00684,.018794,-.003473,.019696,0.0*
1,1,.004,-.003473,.019696*
20,1,.004,-.003473,.019696,0.0,.02,0.0*
1,1,.004,0.0,.02*
20,1,.004,0.0,.02,.003473,.019696,0.0*
1,1,.004,.003473,.019696*
20,1,.004,.003473,.019696,.00684,.018794,0.0*
1,1,.004,.00684,.018794*
20,1,.004,.00684,.018794,.01,.017321,0.0*
1,1,.004,.01,.017321*
20,1,.004,.01,.017321,.012856,.015321,0.0*
1,1,.004,.012856,.015321*
20,1,.004,.012856,.015321,.015321,.012856,0.0*
1,1,.004,.015321,.012856*
20,1,.004,.015321,.012856,.017321,.01,0.0*
1,1,.004,.017321,.01*
20,1,.004,.017321,.01,.018794,.00684,0.0*
1,1,.004,.018794,.00684*
20,1,.004,.018794,.00684,.019696,.003473,0.0*
1,1,.004,.019696,.003473*
20,1,.004,.019696,.003473,.02,0.0,0.0*
1,1,.004,.02,0.0*
1,1,.004,-.004333,-.003334*
20,1,.004,-.004333,-.003334,.004333,-.003334,0.0*
1,1,.004,.004333,-.003334*
%
%ADD21MACRO21*%
%AMMACRO20*
1,1,.004,.02,.02*
20,1,.004,.02,.02,.02,-.02,0.0*
1,1,.004,.02,-.02*
20,1,.004,.02,-.02,-.02,-.02,0.0*
1,1,.004,-.02,-.02*
20,1,.004,-.02,-.02,-.02,.02,0.0*
1,1,.004,-.02,.02*
20,1,.004,-.02,.02,.02,.02,0.0*
1,1,.004,.02,.02*
1,1,.004,-.004333,-.003334*
20,1,.004,-.004333,-.003334,.004333,-.003334,0.0*
1,1,.004,.004333,-.003334*
%
%ADD20MACRO20*%
%AMMACRO11*
1,1,.004,.0625,0.0*
20,1,.004,.0625,0.0,0.0,-.0625,0.0*
1,1,.004,0.0,-.0625*
20,1,.004,0.0,-.0625,-.0625,0.0,0.0*
1,1,.004,-.0625,0.0*
20,1,.004,-.0625,0.0,0.0,.0625,0.0*
1,1,.004,0.0,.0625*
20,1,.004,0.0,.0625,.0625,0.0,0.0*
1,1,.004,.0625,0.0*
1,1,.004,.03125,0.0*
20,1,.004,.03125,0.0,-.03125,0.0,0.0*
1,1,.004,-.03125,0.0*
1,1,.004,0.0,.03125*
20,1,.004,0.0,.03125,0.0,-.03125,0.0*
1,1,.004,0.0,-.03125*
%
%ADD11MACRO11*%
%AMMACRO15*
1,1,.004,.025,0.0*
20,1,.004,.025,0.0,0.0,-.025,0.0*
1,1,.004,0.0,-.025*
20,1,.004,0.0,-.025,-.025,0.0,0.0*
1,1,.004,-.025,0.0*
20,1,.004,-.025,0.0,0.0,.025,0.0*
1,1,.004,0.0,.025*
20,1,.004,0.0,.025,.025,0.0,0.0*
1,1,.004,.025,0.0*
1,1,.004,-.0075,-.013333*
20,1,.004,-.0075,-.013333,.0075,.0125,0.0*
1,1,.004,.0075,.0125*
%
%ADD15MACRO15*%
%AMMACRO23*
1,1,.004,.0175,0.0*
20,1,.004,.0175,0.0,.017234,-.003039,0.0*
1,1,.004,.017234,-.003039*
20,1,.004,.017234,-.003039,.016445,-.005985,0.0*
1,1,.004,.016445,-.005985*
20,1,.004,.016445,-.005985,.015155,-.00875,0.0*
1,1,.004,.015155,-.00875*
20,1,.004,.015155,-.00875,.013406,-.011249,0.0*
1,1,.004,.013406,-.011249*
20,1,.004,.013406,-.011249,.011249,-.013406,0.0*
1,1,.004,.011249,-.013406*
20,1,.004,.011249,-.013406,.00875,-.015155,0.0*
1,1,.004,.00875,-.015155*
20,1,.004,.00875,-.015155,.005985,-.016445,0.0*
1,1,.004,.005985,-.016445*
20,1,.004,.005985,-.016445,.003039,-.017234,0.0*
1,1,.004,.003039,-.017234*
20,1,.004,.003039,-.017234,0.0,-.0175,0.0*
1,1,.004,0.0,-.0175*
20,1,.004,0.0,-.0175,-.003039,-.017234,0.0*
1,1,.004,-.003039,-.017234*
20,1,.004,-.003039,-.017234,-.005985,-.016445,0.0*
1,1,.004,-.005985,-.016445*
20,1,.004,-.005985,-.016445,-.00875,-.015155,0.0*
1,1,.004,-.00875,-.015155*
20,1,.004,-.00875,-.015155,-.011249,-.013406,0.0*
1,1,.004,-.011249,-.013406*
20,1,.004,-.011249,-.013406,-.013406,-.011249,0.0*
1,1,.004,-.013406,-.011249*
20,1,.004,-.013406,-.011249,-.015155,-.00875,0.0*
1,1,.004,-.015155,-.00875*
20,1,.004,-.015155,-.00875,-.016445,-.005985,0.0*
1,1,.004,-.016445,-.005985*
20,1,.004,-.016445,-.005985,-.017234,-.003039,0.0*
1,1,.004,-.017234,-.003039*
20,1,.004,-.017234,-.003039,-.0175,0.0,0.0*
1,1,.004,-.0175,0.0*
20,1,.004,-.0175,0.0,-.017234,.003039,0.0*
1,1,.004,-.017234,.003039*
20,1,.004,-.017234,.003039,-.016445,.005985,0.0*
1,1,.004,-.016445,.005985*
20,1,.004,-.016445,.005985,-.015155,.00875,0.0*
1,1,.004,-.015155,.00875*
20,1,.004,-.015155,.00875,-.013406,.011249,0.0*
1,1,.004,-.013406,.011249*
20,1,.004,-.013406,.011249,-.011249,.013406,0.0*
1,1,.004,-.011249,.013406*
20,1,.004,-.011249,.013406,-.00875,.015155,0.0*
1,1,.004,-.00875,.015155*
20,1,.004,-.00875,.015155,-.005985,.016445,0.0*
1,1,.004,-.005985,.016445*
20,1,.004,-.005985,.016445,-.003039,.017234,0.0*
1,1,.004,-.003039,.017234*
20,1,.004,-.003039,.017234,0.0,.0175,0.0*
1,1,.004,0.0,.0175*
20,1,.004,0.0,.0175,.003039,.017234,0.0*
1,1,.004,.003039,.017234*
20,1,.004,.003039,.017234,.005985,.016445,0.0*
1,1,.004,.005985,.016445*
20,1,.004,.005985,.016445,.00875,.015155,0.0*
1,1,.004,.00875,.015155*
20,1,.004,.00875,.015155,.011249,.013406,0.0*
1,1,.004,.011249,.013406*
20,1,.004,.011249,.013406,.013406,.011249,0.0*
1,1,.004,.013406,.011249*
20,1,.004,.013406,.011249,.015155,.00875,0.0*
1,1,.004,.015155,.00875*
20,1,.004,.015155,.00875,.016445,.005985,0.0*
1,1,.004,.016445,.005985*
20,1,.004,.016445,.005985,.017234,.003039,0.0*
1,1,.004,.017234,.003039*
20,1,.004,.017234,.003039,.0175,0.0,0.0*
1,1,.004,.0175,0.0*
1,1,.004,-.00525,-.009333*
20,1,.004,-.00525,-.009333,.00525,.00875,0.0*
1,1,.004,.00525,.00875*
%
%ADD23MACRO23*%
%AMMACRO19*
1,1,.004,.0275,.0275*
20,1,.004,.0275,.0275,.0275,-.0275,0.0*
1,1,.004,.0275,-.0275*
20,1,.004,.0275,-.0275,-.0275,-.0275,0.0*
1,1,.004,-.0275,-.0275*
20,1,.004,-.0275,-.0275,-.0275,.0275,0.0*
1,1,.004,-.0275,.0275*
20,1,.004,-.0275,.0275,.0275,.0275,0.0*
1,1,.004,.0275,.0275*
1,1,.004,.01375,0.0*
20,1,.004,.01375,0.0,-.01375,0.0,0.0*
1,1,.004,-.01375,0.0*
1,1,.004,0.0,.01375*
20,1,.004,0.0,.01375,0.0,-.01375,0.0*
1,1,.004,0.0,-.01375*
%
%ADD19MACRO19*%
%AMMACRO10*
1,1,.004,.078,0.0*
20,1,.004,.078,0.0,0.0,-.078,0.0*
1,1,.004,0.0,-.078*
20,1,.004,0.0,-.078,-.078,0.0,0.0*
1,1,.004,-.078,0.0*
20,1,.004,-.078,0.0,0.0,.078,0.0*
1,1,.004,0.0,.078*
20,1,.004,0.0,.078,.078,0.0,0.0*
1,1,.004,.078,0.0*
1,1,.004,-.0169,-.013001*
20,1,.004,-.0169,-.013001,.0169,-.013001,0.0*
1,1,.004,.0169,-.013001*
%
%ADD10MACRO10*%
%AMMACRO18*
1,1,.004,.0435,.0435*
20,1,.004,.0435,.0435,.0435,-.0435,0.0*
1,1,.004,.0435,-.0435*
20,1,.004,.0435,-.0435,-.0435,-.0435,0.0*
1,1,.004,-.0435,-.0435*
20,1,.004,-.0435,-.0435,-.0435,.0435,0.0*
1,1,.004,-.0435,.0435*
20,1,.004,-.0435,.0435,.0435,.0435,0.0*
1,1,.004,.0435,.0435*
1,1,.004,-.013051,-.0232*
20,1,.004,-.013051,-.0232,.013051,.02175,0.0*
1,1,.004,.013051,.02175*
%
%ADD18MACRO18*%
%AMMACRO27*
1,1,.004,0.0,.0125*
20,1,.004,0.0,.0125,.0125,-.0125,0.0*
1,1,.004,.0125,-.0125*
20,1,.004,.0125,-.0125,-.0125,-.0125,0.0*
1,1,.004,-.0125,-.0125*
20,1,.004,-.0125,-.0125,0.0,.0125,0.0*
1,1,.004,0.0,.0125*
%
%ADD27MACRO27*%
%AMMACRO13*
1,1,.004,.03,0.0*
20,1,.004,.03,0.0,0.0,-.03,0.0*
1,1,.004,0.0,-.03*
20,1,.004,0.0,-.03,-.03,0.0,0.0*
1,1,.004,-.03,0.0*
20,1,.004,-.03,0.0,0.0,.03,0.0*
1,1,.004,0.0,.03*
20,1,.004,0.0,.03,.03,0.0,0.0*
1,1,.004,.03,0.0*
1,1,.004,-.012501,.015*
20,1,.004,-.012501,.015,0.0,-.015,0.0*
1,1,.004,0.0,-.015*
20,1,.004,0.0,-.015,.012501,.015,0.0*
1,1,.004,.012501,.015*
%
%ADD13MACRO13*%
%AMMACRO14*
1,1,.004,.03,0.0*
20,1,.004,.03,0.0,0.0,-.03,0.0*
1,1,.004,0.0,-.03*
20,1,.004,0.0,-.03,-.03,0.0,0.0*
1,1,.004,-.03,0.0*
20,1,.004,-.03,0.0,0.0,.03,0.0*
1,1,.004,0.0,.03*
20,1,.004,0.0,.03,.03,0.0,0.0*
1,1,.004,.03,0.0*
1,1,.004,-.0105,-.015*
20,1,.004,-.0105,-.015,.0105,.015,0.0*
1,1,.004,.0105,.015*
1,1,.004,-.0105,.015*
20,1,.004,-.0105,.015,.0105,-.015,0.0*
1,1,.004,.0105,-.015*
%
%ADD14MACRO14*%
%AMMACRO12*
1,1,.004,.043,0.0*
20,1,.004,.043,0.0,0.0,-.043,0.0*
1,1,.004,0.0,-.043*
20,1,.004,0.0,-.043,-.043,0.0,0.0*
1,1,.004,-.043,0.0*
20,1,.004,-.043,0.0,0.0,.043,0.0*
1,1,.004,0.0,.043*
20,1,.004,0.0,.043,.043,0.0,0.0*
1,1,.004,.043,0.0*
1,1,.004,-.000001,.0215*
20,1,.004,-.000001,.0215,-.000001,-.0215,0.0*
1,1,.004,-.000001,-.0215*
1,1,.004,-.016483,.0215*
20,1,.004,-.016483,.0215,.016483,.0215,0.0*
1,1,.004,.016483,.0215*
%
%ADD12MACRO12*%
%AMMACRO16*
1,1,.004,.078,.078*
20,1,.004,.078,.078,.078,-.078,0.0*
1,1,.004,.078,-.078*
20,1,.004,.078,-.078,-.078,-.078,0.0*
1,1,.004,-.078,-.078*
20,1,.004,-.078,-.078,-.078,.078,0.0*
1,1,.004,-.078,.078*
20,1,.004,-.078,.078,.078,.078,0.0*
1,1,.004,.078,.078*
1,1,.004,-.000001,-.039*
20,1,.004,-.000001,-.039,-.000001,.039,0.0*
1,1,.004,-.000001,.039*
%
%ADD16MACRO16*%
%AMMACRO22*
1,1,.004,.0175,0.0*
20,1,.004,.0175,0.0,.017234,-.003039,0.0*
1,1,.004,.017234,-.003039*
20,1,.004,.017234,-.003039,.016445,-.005985,0.0*
1,1,.004,.016445,-.005985*
20,1,.004,.016445,-.005985,.015155,-.00875,0.0*
1,1,.004,.015155,-.00875*
20,1,.004,.015155,-.00875,.013406,-.011249,0.0*
1,1,.004,.013406,-.011249*
20,1,.004,.013406,-.011249,.011249,-.013406,0.0*
1,1,.004,.011249,-.013406*
20,1,.004,.011249,-.013406,.00875,-.015155,0.0*
1,1,.004,.00875,-.015155*
20,1,.004,.00875,-.015155,.005985,-.016445,0.0*
1,1,.004,.005985,-.016445*
20,1,.004,.005985,-.016445,.003039,-.017234,0.0*
1,1,.004,.003039,-.017234*
20,1,.004,.003039,-.017234,0.0,-.0175,0.0*
1,1,.004,0.0,-.0175*
20,1,.004,0.0,-.0175,-.003039,-.017234,0.0*
1,1,.004,-.003039,-.017234*
20,1,.004,-.003039,-.017234,-.005985,-.016445,0.0*
1,1,.004,-.005985,-.016445*
20,1,.004,-.005985,-.016445,-.00875,-.015155,0.0*
1,1,.004,-.00875,-.015155*
20,1,.004,-.00875,-.015155,-.011249,-.013406,0.0*
1,1,.004,-.011249,-.013406*
20,1,.004,-.011249,-.013406,-.013406,-.011249,0.0*
1,1,.004,-.013406,-.011249*
20,1,.004,-.013406,-.011249,-.015155,-.00875,0.0*
1,1,.004,-.015155,-.00875*
20,1,.004,-.015155,-.00875,-.016445,-.005985,0.0*
1,1,.004,-.016445,-.005985*
20,1,.004,-.016445,-.005985,-.017234,-.003039,0.0*
1,1,.004,-.017234,-.003039*
20,1,.004,-.017234,-.003039,-.0175,0.0,0.0*
1,1,.004,-.0175,0.0*
20,1,.004,-.0175,0.0,-.017234,.003039,0.0*
1,1,.004,-.017234,.003039*
20,1,.004,-.017234,.003039,-.016445,.005985,0.0*
1,1,.004,-.016445,.005985*
20,1,.004,-.016445,.005985,-.015155,.00875,0.0*
1,1,.004,-.015155,.00875*
20,1,.004,-.015155,.00875,-.013406,.011249,0.0*
1,1,.004,-.013406,.011249*
20,1,.004,-.013406,.011249,-.011249,.013406,0.0*
1,1,.004,-.011249,.013406*
20,1,.004,-.011249,.013406,-.00875,.015155,0.0*
1,1,.004,-.00875,.015155*
20,1,.004,-.00875,.015155,-.005985,.016445,0.0*
1,1,.004,-.005985,.016445*
20,1,.004,-.005985,.016445,-.003039,.017234,0.0*
1,1,.004,-.003039,.017234*
20,1,.004,-.003039,.017234,0.0,.0175,0.0*
1,1,.004,0.0,.0175*
20,1,.004,0.0,.0175,.003039,.017234,0.0*
1,1,.004,.003039,.017234*
20,1,.004,.003039,.017234,.005985,.016445,0.0*
1,1,.004,.005985,.016445*
20,1,.004,.005985,.016445,.00875,.015155,0.0*
1,1,.004,.00875,.015155*
20,1,.004,.00875,.015155,.011249,.013406,0.0*
1,1,.004,.011249,.013406*
20,1,.004,.011249,.013406,.013406,.011249,0.0*
1,1,.004,.013406,.011249*
20,1,.004,.013406,.011249,.015155,.00875,0.0*
1,1,.004,.015155,.00875*
20,1,.004,.015155,.00875,.016445,.005985,0.0*
1,1,.004,.016445,.005985*
20,1,.004,.016445,.005985,.017234,.003039,0.0*
1,1,.004,.017234,.003039*
20,1,.004,.017234,.003039,.0175,0.0,0.0*
1,1,.004,.0175,0.0*
1,1,.004,-.00525,.002916*
20,1,.004,-.00525,.002916,0.0,-.00875,0.0*
1,1,.004,0.0,-.00875*
20,1,.004,0.0,-.00875,.00525,.002916,0.0*
1,1,.004,.00525,.002916*
%
%ADD22MACRO22*%
%AMMACRO25*
1,1,.004,.015,0.0*
20,1,.004,.015,0.0,.014772,-.002605,0.0*
1,1,.004,.014772,-.002605*
20,1,.004,.014772,-.002605,.014095,-.00513,0.0*
1,1,.004,.014095,-.00513*
20,1,.004,.014095,-.00513,.01299,-.0075,0.0*
1,1,.004,.01299,-.0075*
20,1,.004,.01299,-.0075,.011491,-.009642,0.0*
1,1,.004,.011491,-.009642*
20,1,.004,.011491,-.009642,.009642,-.011491,0.0*
1,1,.004,.009642,-.011491*
20,1,.004,.009642,-.011491,.0075,-.01299,0.0*
1,1,.004,.0075,-.01299*
20,1,.004,.0075,-.01299,.00513,-.014095,0.0*
1,1,.004,.00513,-.014095*
20,1,.004,.00513,-.014095,.002605,-.014772,0.0*
1,1,.004,.002605,-.014772*
20,1,.004,.002605,-.014772,0.0,-.015,0.0*
1,1,.004,0.0,-.015*
20,1,.004,0.0,-.015,-.002605,-.014772,0.0*
1,1,.004,-.002605,-.014772*
20,1,.004,-.002605,-.014772,-.00513,-.014095,0.0*
1,1,.004,-.00513,-.014095*
20,1,.004,-.00513,-.014095,-.0075,-.01299,0.0*
1,1,.004,-.0075,-.01299*
20,1,.004,-.0075,-.01299,-.009642,-.011491,0.0*
1,1,.004,-.009642,-.011491*
20,1,.004,-.009642,-.011491,-.011491,-.009642,0.0*
1,1,.004,-.011491,-.009642*
20,1,.004,-.011491,-.009642,-.01299,-.0075,0.0*
1,1,.004,-.01299,-.0075*
20,1,.004,-.01299,-.0075,-.014095,-.00513,0.0*
1,1,.004,-.014095,-.00513*
20,1,.004,-.014095,-.00513,-.014772,-.002605,0.0*
1,1,.004,-.014772,-.002605*
20,1,.004,-.014772,-.002605,-.015,0.0,0.0*
1,1,.004,-.015,0.0*
20,1,.004,-.015,0.0,-.014772,.002605,0.0*
1,1,.004,-.014772,.002605*
20,1,.004,-.014772,.002605,-.014095,.00513,0.0*
1,1,.004,-.014095,.00513*
20,1,.004,-.014095,.00513,-.01299,.0075,0.0*
1,1,.004,-.01299,.0075*
20,1,.004,-.01299,.0075,-.011491,.009642,0.0*
1,1,.004,-.011491,.009642*
20,1,.004,-.011491,.009642,-.009642,.011491,0.0*
1,1,.004,-.009642,.011491*
20,1,.004,-.009642,.011491,-.0075,.01299,0.0*
1,1,.004,-.0075,.01299*
20,1,.004,-.0075,.01299,-.00513,.014095,0.0*
1,1,.004,-.00513,.014095*
20,1,.004,-.00513,.014095,-.002605,.014772,0.0*
1,1,.004,-.002605,.014772*
20,1,.004,-.002605,.014772,0.0,.015,0.0*
1,1,.004,0.0,.015*
20,1,.004,0.0,.015,.002605,.014772,0.0*
1,1,.004,.002605,.014772*
20,1,.004,.002605,.014772,.00513,.014095,0.0*
1,1,.004,.00513,.014095*
20,1,.004,.00513,.014095,.0075,.01299,0.0*
1,1,.004,.0075,.01299*
20,1,.004,.0075,.01299,.009642,.011491,0.0*
1,1,.004,.009642,.011491*
20,1,.004,.009642,.011491,.011491,.009642,0.0*
1,1,.004,.011491,.009642*
20,1,.004,.011491,.009642,.01299,.0075,0.0*
1,1,.004,.01299,.0075*
20,1,.004,.01299,.0075,.014095,.00513,0.0*
1,1,.004,.014095,.00513*
20,1,.004,.014095,.00513,.014772,.002605,0.0*
1,1,.004,.014772,.002605*
20,1,.004,.014772,.002605,.015,0.0,0.0*
1,1,.004,.015,0.0*
%
%ADD25MACRO25*%
%AMMACRO26*
1,1,.004,.015,.015*
20,1,.004,.015,.015,.015,-.015,0.0*
1,1,.004,.015,-.015*
20,1,.004,.015,-.015,-.015,-.015,0.0*
1,1,.004,-.015,-.015*
20,1,.004,-.015,-.015,-.015,.015,0.0*
1,1,.004,-.015,.015*
20,1,.004,-.015,.015,.015,.015,0.0*
1,1,.004,.015,.015*
%
%ADD26MACRO26*%
%AMMACRO17*
1,1,.004,.069,.069*
20,1,.004,.069,.069,.069,-.069,0.0*
1,1,.004,.069,-.069*
20,1,.004,.069,-.069,-.069,-.069,0.0*
1,1,.004,-.069,-.069*
20,1,.004,-.069,-.069,-.069,.069,0.0*
1,1,.004,-.069,.069*
20,1,.004,-.069,.069,.069,.069,0.0*
1,1,.004,.069,.069*
1,1,.004,-.01725,.011499*
20,1,.004,-.01725,.011499,.01725,-.0345,0.0*
1,1,.004,.01725,-.0345*
1,1,.004,.01725,.011499*
20,1,.004,.01725,.011499,-.01725,-.0345,0.0*
1,1,.004,-.01725,-.0345*
%
%ADD17MACRO17*%
%ADD30C,.01*%
%ADD31C,.02*%
%ADD32C,.021*%
%ADD33C,.013*%
%ADD34C,.05*%
%ADD35C,.015*%
%ADD36C,.025*%
%ADD37C,.018*%
%ADD38C,.006*%
%ADD39C,.007*%
%ADD40C,.008*%
%ADD41C,.009*%
%ADD42C,.004*%
G75*
%LPD*%
G75*
G36*
G01X425500Y655600D02*
X655500D01*
Y665600D01*
X425500D01*
Y655600D01*
G37*
G36*
G01Y705600D02*
X655500D01*
Y715600D01*
X425500D01*
Y705600D01*
G37*
G36*
G01Y755600D02*
X655500D01*
Y765600D01*
X425500D01*
Y755600D01*
G37*
G36*
G01Y805600D02*
X655500D01*
Y815600D01*
X425500D01*
Y805600D01*
G37*
G36*
G01X425000Y862600D02*
X655000D01*
Y872600D01*
X425000D01*
Y862600D01*
G37*
G36*
G01Y912600D02*
X655000D01*
Y922600D01*
X425000D01*
Y912600D01*
G37*
G36*
G01Y962600D02*
X655000D01*
Y972600D01*
X425000D01*
Y962600D01*
G37*
G36*
G01Y1012600D02*
X655000D01*
Y1022600D01*
X425000D01*
Y1012600D01*
G37*
G54D10*
X-1670620Y340670D03*
X-1356889Y-167165D03*
Y-118937D03*
X-1051613Y-167165D03*
Y-118937D03*
X-486810Y-167165D03*
Y-118937D03*
X-181534Y-167165D03*
Y-118937D03*
G54D11*
X-1670620Y364070D03*
X-1410000Y0D03*
X0Y-136453D03*
X0Y0D03*
G54D20*
X-1670620Y574670D03*
X-1282480Y-172283D03*
Y-130157D03*
Y-94724D03*
Y-59291D03*
Y-23858D03*
X-1253740Y-184094D03*
X-1225394D03*
X-1207677Y-154567D03*
Y-112441D03*
Y-77008D03*
Y-41575D03*
Y-6142D03*
X-1141240Y-142362D03*
Y-102992D03*
Y-63622D03*
Y-24252D03*
X-1128760Y-83307D03*
X-1118917Y-4567D03*
X-1107500Y-83307D03*
X-1085138D03*
Y-43937D03*
Y-4567D03*
X-412402Y-172283D03*
Y-130157D03*
Y-94724D03*
Y-59291D03*
Y-23858D03*
X-383661Y-184094D03*
X-355315D03*
X-337598Y-154567D03*
Y-112441D03*
Y-77008D03*
Y-41575D03*
Y-6142D03*
X-271161Y-142362D03*
Y-102992D03*
Y-63622D03*
Y-24252D03*
X-258681Y-83307D03*
X-237421D03*
X-248839Y-4567D03*
X-215059Y-83307D03*
Y-43937D03*
Y-4567D03*
G54D30*
G01X881367Y300900D02*
Y290900D01*
X886033D01*
G01X891800Y300900D02*
X894600D01*
G01X893200D02*
Y290900D01*
G01X891800D02*
X894600D01*
G01X900017D02*
Y300900D01*
X905383Y290900D01*
Y300900D01*
G01X914533Y290900D02*
X909867D01*
Y300900D01*
X914533D01*
G01X912667Y296067D02*
X909867D01*
G01X920183Y294233D02*
X923217D01*
G01X928750Y292233D02*
X929683Y291400D01*
X930733Y290900D01*
X931667D01*
X932600Y291400D01*
X933300Y292233D01*
X933650Y293400D01*
X933417Y294566D01*
X932833Y295567D01*
X931783Y296233D01*
X930383Y296567D01*
X929567Y297233D01*
X929217Y298400D01*
X929450Y299567D01*
X930033Y300400D01*
X930850Y300900D01*
X931667D01*
X932483Y300567D01*
X933183Y299733D01*
G01X938367Y290900D02*
Y300900D01*
X941167D01*
X942100Y300400D01*
X942800Y299233D01*
X943033Y297900D01*
X942800Y296567D01*
X942217Y295567D01*
X941167Y295066D01*
X938367D01*
G01X947283Y290900D02*
X950200Y300900D01*
X953117Y290900D01*
G01X952067Y294400D02*
X948333D01*
G01X962267Y300067D02*
X961567Y300567D01*
X960750Y300900D01*
X959817D01*
X958767Y300400D01*
X957950Y299567D01*
X957367Y298567D01*
X956900Y296900D01*
X956783Y295400D01*
X957017Y293900D01*
X957367Y292900D01*
X958067Y291900D01*
X958883Y291233D01*
X959700Y290900D01*
X960517D01*
X961333Y291233D01*
X962033Y291733D01*
X962617Y292400D01*
G01X971533Y290900D02*
X966867D01*
Y300900D01*
X971533D01*
G01X969667Y296067D02*
X966867D01*
G01X977183Y294233D02*
X980217D01*
G01X985867Y300900D02*
Y290900D01*
X990533D01*
G01X996300Y300900D02*
X999100D01*
G01X997700D02*
Y290900D01*
G01X996300D02*
X999100D01*
G01X1004517D02*
Y300900D01*
X1009883Y290900D01*
Y300900D01*
G01X1019033Y290900D02*
X1014367D01*
Y300900D01*
X1019033D01*
G01X1017167Y296067D02*
X1014367D01*
G01X1006050Y-758667D02*
X1006983Y-759500D01*
X1008033Y-760000D01*
X1008967D01*
X1009900Y-759500D01*
X1010600Y-758667D01*
X1010950Y-757500D01*
X1010717Y-756334D01*
X1010133Y-755333D01*
X1009083Y-754667D01*
X1007683Y-754333D01*
X1006867Y-753667D01*
X1006517Y-752500D01*
X1006750Y-751333D01*
X1007333Y-750500D01*
X1008150Y-750000D01*
X1008967D01*
X1009783Y-750333D01*
X1010483Y-751167D01*
G01X1016600Y-750000D02*
X1019400D01*
G01X1018000D02*
Y-760000D01*
G01X1016600D02*
X1019400D01*
G01X1025283Y-750000D02*
X1029717D01*
X1025283Y-760000D01*
X1029717D01*
G01X1039333D02*
X1034667D01*
Y-750000D01*
X1039333D01*
G01X1037467Y-754833D02*
X1034667D01*
G01X1010920Y-635040D02*
Y-645040D01*
G01X1008237Y-635040D02*
X1013603D01*
G01X1019020D02*
X1021820D01*
G01X1020420D02*
Y-645040D01*
G01X1019020D02*
X1021820D01*
G01X1029920Y-635040D02*
Y-645040D01*
G01X1027237Y-635040D02*
X1032603D01*
G01X1037087D02*
Y-645040D01*
X1041753D01*
G01X1051253D02*
X1046587D01*
Y-635040D01*
X1051253D01*
G01X1049387Y-639873D02*
X1046587D01*
G01X1058420Y-645373D02*
X1058187Y-645207D01*
Y-644873D01*
X1058420Y-644707D01*
X1058653Y-644873D01*
Y-645207D01*
X1058420Y-645373D01*
G01Y-640874D02*
X1058187Y-640707D01*
Y-640373D01*
X1058420Y-640207D01*
X1058653Y-640373D01*
Y-640707D01*
X1058420Y-640874D01*
G01X1075247Y-607940D02*
Y-597940D01*
X1078280Y-606273D01*
X1081313Y-597940D01*
Y-607940D01*
G01X1085330Y-606607D02*
X1086263Y-607440D01*
X1087313Y-607940D01*
X1088247D01*
X1089180Y-607440D01*
X1089880Y-606607D01*
X1090230Y-605440D01*
X1089997Y-604274D01*
X1089413Y-603273D01*
X1088363Y-602607D01*
X1086963Y-602273D01*
X1086147Y-601607D01*
X1085797Y-600440D01*
X1086030Y-599273D01*
X1086613Y-598440D01*
X1087430Y-597940D01*
X1088247D01*
X1089063Y-598273D01*
X1089763Y-599107D01*
G01X1104447Y-607940D02*
Y-597940D01*
X1107247D01*
X1108180Y-598440D01*
X1108880Y-599607D01*
X1109113Y-600940D01*
X1108880Y-602273D01*
X1108297Y-603273D01*
X1107247Y-603774D01*
X1104447D01*
G01X1113713Y-607940D02*
Y-597940D01*
X1116047D01*
X1116980Y-598440D01*
X1117680Y-599107D01*
X1118263Y-600107D01*
X1118730Y-601274D01*
X1118847Y-602940D01*
X1118730Y-604607D01*
X1118263Y-605773D01*
X1117680Y-606774D01*
X1116980Y-607440D01*
X1116047Y-607940D01*
X1113713D01*
G01X1122747D02*
Y-597940D01*
X1125780Y-606273D01*
X1128813Y-597940D01*
Y-607940D01*
G01X1141863Y-597940D02*
X1144780Y-607940D01*
X1147697Y-597940D01*
G01X1156613Y-607940D02*
X1151947D01*
Y-597940D01*
X1156613D01*
G01X1154747Y-602773D02*
X1151947D01*
G01X1161447Y-607940D02*
Y-597940D01*
X1164363D01*
X1165297Y-598440D01*
X1165880Y-599107D01*
X1166113Y-600440D01*
X1165880Y-601773D01*
X1165180Y-602607D01*
X1164363Y-603107D01*
X1161447D01*
G01X1164363D02*
X1166113Y-607940D01*
G01X1173280Y-608273D02*
X1173047Y-608107D01*
Y-607773D01*
X1173280Y-607607D01*
X1173513Y-607773D01*
Y-608107D01*
X1173280Y-608273D01*
G01Y-603774D02*
X1173047Y-603607D01*
Y-603273D01*
X1173280Y-603107D01*
X1173513Y-603273D01*
Y-603607D01*
X1173280Y-603774D01*
G01X1189363Y-607940D02*
X1192280Y-597940D01*
X1195197Y-607940D01*
G01X1194147Y-604440D02*
X1190413D01*
G01X1201780Y-608273D02*
X1201547Y-608107D01*
Y-607773D01*
X1201780Y-607607D01*
X1202013Y-607773D01*
Y-608107D01*
X1201780Y-608273D01*
G01X1211280Y-607940D02*
Y-597940D01*
X1209880Y-599940D01*
G01Y-607940D02*
X1212680D01*
G01X1075467Y-587630D02*
Y-577630D01*
X1078500Y-585963D01*
X1081533Y-577630D01*
Y-587630D01*
G01X1085550Y-586297D02*
X1086483Y-587130D01*
X1087533Y-587630D01*
X1088467D01*
X1089400Y-587130D01*
X1090100Y-586297D01*
X1090450Y-585130D01*
X1090217Y-583964D01*
X1089633Y-582963D01*
X1088583Y-582297D01*
X1087183Y-581963D01*
X1086367Y-581297D01*
X1086017Y-580130D01*
X1086250Y-578963D01*
X1086833Y-578130D01*
X1087650Y-577630D01*
X1088467D01*
X1089283Y-577963D01*
X1089983Y-578797D01*
G01X1104667Y-587630D02*
Y-577630D01*
X1107467D01*
X1108400Y-578130D01*
X1109100Y-579297D01*
X1109333Y-580630D01*
X1109100Y-581963D01*
X1108517Y-582963D01*
X1107467Y-583464D01*
X1104667D01*
G01X1113583Y-587630D02*
X1116500Y-577630D01*
X1119417Y-587630D01*
G01X1118367Y-584130D02*
X1114633D01*
G01X1123667Y-587630D02*
Y-577630D01*
X1126583D01*
X1127517Y-578130D01*
X1128100Y-578797D01*
X1128333Y-580130D01*
X1128100Y-581463D01*
X1127400Y-582297D01*
X1126583Y-582797D01*
X1123667D01*
G01X1126583D02*
X1128333Y-587630D01*
G01X1135500Y-577630D02*
Y-587630D01*
G01X1132817Y-577630D02*
X1138183D01*
G01X1151817Y-587630D02*
Y-577630D01*
X1157183Y-587630D01*
Y-577630D01*
G01X1164000Y-587630D02*
X1163067Y-587463D01*
X1162250Y-586797D01*
X1161550Y-585797D01*
X1161083Y-584630D01*
X1160850Y-583297D01*
Y-581963D01*
X1161083Y-580630D01*
X1161550Y-579463D01*
X1162250Y-578463D01*
X1163067Y-577797D01*
X1164000Y-577630D01*
X1164933Y-577797D01*
X1165750Y-578463D01*
X1166450Y-579463D01*
X1166917Y-580630D01*
X1167150Y-581963D01*
Y-583297D01*
X1166917Y-584630D01*
X1166450Y-585797D01*
X1165750Y-586797D01*
X1164933Y-587463D01*
X1164000Y-587630D01*
G01X1173500Y-587963D02*
X1173267Y-587797D01*
Y-587463D01*
X1173500Y-587297D01*
X1173733Y-587463D01*
Y-587797D01*
X1173500Y-587963D01*
G01Y-583464D02*
X1173267Y-583297D01*
Y-582963D01*
X1173500Y-582797D01*
X1173733Y-582963D01*
Y-583297D01*
X1173500Y-583464D01*
G01X1190050Y-587630D02*
X1194950Y-577630D01*
G01X1190050D02*
X1194950Y-587630D01*
G01X1202000D02*
X1202817Y-587463D01*
X1203750Y-586963D01*
X1204333Y-586130D01*
X1204567Y-584963D01*
X1204333Y-583797D01*
X1203633Y-582797D01*
X1202583Y-582297D01*
X1201417D01*
X1200717Y-581963D01*
X1200133Y-581130D01*
X1199900Y-579963D01*
X1200250Y-578797D01*
X1201067Y-577963D01*
X1202000Y-577630D01*
X1202933Y-577963D01*
X1203750Y-578797D01*
X1204100Y-579963D01*
X1203867Y-581130D01*
X1203283Y-581963D01*
X1202583Y-582297D01*
X1201417D01*
X1200367Y-582797D01*
X1199667Y-583797D01*
X1199433Y-584963D01*
X1199667Y-586130D01*
X1200250Y-586963D01*
X1201183Y-587463D01*
X1202000Y-587630D01*
G01X1211500D02*
X1212317Y-587463D01*
X1213250Y-586963D01*
X1213833Y-586130D01*
X1214067Y-584963D01*
X1213833Y-583797D01*
X1213133Y-582797D01*
X1212083Y-582297D01*
X1210917D01*
X1210217Y-581963D01*
X1209633Y-581130D01*
X1209400Y-579963D01*
X1209750Y-578797D01*
X1210567Y-577963D01*
X1211500Y-577630D01*
X1212433Y-577963D01*
X1213250Y-578797D01*
X1213600Y-579963D01*
X1213367Y-581130D01*
X1212783Y-581963D01*
X1212083Y-582297D01*
X1210917D01*
X1209867Y-582797D01*
X1209167Y-583797D01*
X1208933Y-584963D01*
X1209167Y-586130D01*
X1209750Y-586963D01*
X1210683Y-587463D01*
X1211500Y-587630D01*
G01X1220767D02*
X1221000Y-585463D01*
X1221350Y-583630D01*
X1221817Y-581963D01*
X1222400Y-580130D01*
X1223333Y-577630D01*
X1218667D01*
G01X1227933Y-586130D02*
X1228633Y-586963D01*
X1229450Y-587463D01*
X1230500Y-587630D01*
X1231550Y-587297D01*
X1232367Y-586630D01*
X1232950Y-585463D01*
X1233067Y-584130D01*
X1232833Y-582797D01*
X1232250Y-581963D01*
X1231433Y-581297D01*
X1230617Y-581130D01*
X1229800Y-581297D01*
X1228750Y-581963D01*
X1229100Y-577630D01*
X1232250D01*
G01X1239767Y-587630D02*
X1240000Y-585463D01*
X1240350Y-583630D01*
X1240817Y-581963D01*
X1241400Y-580130D01*
X1242333Y-577630D01*
X1237667D01*
G01X1249500Y-587630D02*
Y-577630D01*
X1248100Y-579630D01*
G01Y-587630D02*
X1250900D01*
G01X1257483Y-584297D02*
X1260517D01*
G01X1268500Y-577630D02*
X1267567Y-577963D01*
X1266867Y-578797D01*
X1266400Y-579797D01*
X1266050Y-581130D01*
X1265933Y-582630D01*
X1266050Y-584130D01*
X1266400Y-585463D01*
X1266867Y-586464D01*
X1267567Y-587297D01*
X1268500Y-587630D01*
X1269433Y-587297D01*
X1270133Y-586464D01*
X1270600Y-585463D01*
X1270950Y-584130D01*
X1271067Y-582630D01*
X1270950Y-581130D01*
X1270600Y-579797D01*
X1270133Y-578797D01*
X1269433Y-577963D01*
X1268500Y-577630D01*
G01X1278000D02*
X1277067Y-577963D01*
X1276367Y-578797D01*
X1275900Y-579797D01*
X1275550Y-581130D01*
X1275433Y-582630D01*
X1275550Y-584130D01*
X1275900Y-585463D01*
X1276367Y-586464D01*
X1277067Y-587297D01*
X1278000Y-587630D01*
X1278933Y-587297D01*
X1279633Y-586464D01*
X1280100Y-585463D01*
X1280450Y-584130D01*
X1280567Y-582630D01*
X1280450Y-581130D01*
X1280100Y-579797D01*
X1279633Y-578797D01*
X1278933Y-577963D01*
X1278000Y-577630D01*
G01X1284933Y-586130D02*
X1285633Y-586963D01*
X1286450Y-587463D01*
X1287500Y-587630D01*
X1288550Y-587297D01*
X1289367Y-586630D01*
X1289950Y-585463D01*
X1290067Y-584130D01*
X1289833Y-582797D01*
X1289250Y-581963D01*
X1288433Y-581297D01*
X1287617Y-581130D01*
X1286800Y-581297D01*
X1285750Y-581963D01*
X1286100Y-577630D01*
X1289250D01*
G01X1102933Y-760000D02*
Y-750000D01*
X1105267D01*
X1106200Y-750500D01*
X1106900Y-751167D01*
X1107483Y-752167D01*
X1107950Y-753334D01*
X1108067Y-755000D01*
X1107950Y-756667D01*
X1107483Y-757833D01*
X1106900Y-758834D01*
X1106200Y-759500D01*
X1105267Y-760000D01*
X1102933D01*
G01X1115000D02*
X1114067Y-759833D01*
X1113250Y-759167D01*
X1112550Y-758167D01*
X1112083Y-757000D01*
X1111850Y-755667D01*
Y-754333D01*
X1112083Y-753000D01*
X1112550Y-751833D01*
X1113250Y-750833D01*
X1114067Y-750167D01*
X1115000Y-750000D01*
X1115933Y-750167D01*
X1116750Y-750833D01*
X1117450Y-751833D01*
X1117917Y-753000D01*
X1118150Y-754333D01*
Y-755667D01*
X1117917Y-757000D01*
X1117450Y-758167D01*
X1116750Y-759167D01*
X1115933Y-759833D01*
X1115000Y-760000D01*
G01X1127067Y-750833D02*
X1126367Y-750333D01*
X1125550Y-750000D01*
X1124617D01*
X1123567Y-750500D01*
X1122750Y-751333D01*
X1122167Y-752333D01*
X1121700Y-754000D01*
X1121583Y-755500D01*
X1121817Y-757000D01*
X1122167Y-758000D01*
X1122867Y-759000D01*
X1123683Y-759667D01*
X1124500Y-760000D01*
X1125317D01*
X1126133Y-759667D01*
X1126833Y-759167D01*
X1127417Y-758500D01*
G01X1131433Y-750000D02*
Y-757167D01*
X1131900Y-758667D01*
X1132833Y-759667D01*
X1134000Y-760000D01*
X1135167Y-759667D01*
X1136100Y-758667D01*
X1136567Y-757167D01*
Y-750000D01*
G01X1140467Y-760000D02*
Y-750000D01*
X1143500Y-758333D01*
X1146533Y-750000D01*
Y-760000D01*
G01X1155333D02*
X1150667D01*
Y-750000D01*
X1155333D01*
G01X1153467Y-754833D02*
X1150667D01*
G01X1159817Y-760000D02*
Y-750000D01*
X1165183Y-760000D01*
Y-750000D01*
G01X1172000D02*
Y-760000D01*
G01X1169317Y-750000D02*
X1174683D01*
G01X1188317Y-760000D02*
Y-750000D01*
X1193683Y-760000D01*
Y-750000D01*
G01X1197933D02*
Y-757167D01*
X1198400Y-758667D01*
X1199333Y-759667D01*
X1200500Y-760000D01*
X1201667Y-759667D01*
X1202600Y-758667D01*
X1203067Y-757167D01*
Y-750000D01*
G01X1206967Y-760000D02*
Y-750000D01*
X1210000Y-758333D01*
X1213033Y-750000D01*
Y-760000D01*
G01X1220433Y-754667D02*
X1220900Y-754167D01*
X1221250Y-753334D01*
X1221483Y-752167D01*
X1221250Y-751167D01*
X1220783Y-750500D01*
X1219967Y-750000D01*
X1216817D01*
Y-760000D01*
X1220667D01*
X1221483Y-759333D01*
X1221950Y-758333D01*
X1222183Y-757167D01*
X1221950Y-756000D01*
X1221250Y-755000D01*
X1220433Y-754667D01*
X1216817D01*
G01X1231333Y-760000D02*
X1226667D01*
Y-750000D01*
X1231333D01*
G01X1229467Y-754833D02*
X1226667D01*
G01X1236167Y-760000D02*
Y-750000D01*
X1239083D01*
X1240017Y-750500D01*
X1240600Y-751167D01*
X1240833Y-752500D01*
X1240600Y-753833D01*
X1239900Y-754667D01*
X1239083Y-755167D01*
X1236167D01*
G01X1239083D02*
X1240833Y-760000D01*
G01X1291050Y-758667D02*
X1291983Y-759500D01*
X1293033Y-760000D01*
X1293967D01*
X1294900Y-759500D01*
X1295600Y-758667D01*
X1295950Y-757500D01*
X1295717Y-756334D01*
X1295133Y-755333D01*
X1294083Y-754667D01*
X1292683Y-754333D01*
X1291867Y-753667D01*
X1291517Y-752500D01*
X1291750Y-751333D01*
X1292333Y-750500D01*
X1293150Y-750000D01*
X1293967D01*
X1294783Y-750333D01*
X1295483Y-751167D01*
G01X1300550Y-760000D02*
Y-750000D01*
G01X1305450D02*
Y-760000D01*
G01Y-755000D02*
X1300550D01*
G01X1314833Y-760000D02*
X1310167D01*
Y-750000D01*
X1314833D01*
G01X1312967Y-754833D02*
X1310167D01*
G01X1324333Y-760000D02*
X1319667D01*
Y-750000D01*
X1324333D01*
G01X1322467Y-754833D02*
X1319667D01*
G01X1331500Y-750000D02*
Y-760000D01*
G01X1328817Y-750000D02*
X1334183D01*
G01X1361167Y-760000D02*
Y-750000D01*
X1364083D01*
X1365017Y-750500D01*
X1365600Y-751167D01*
X1365833Y-752500D01*
X1365600Y-753833D01*
X1364900Y-754667D01*
X1364083Y-755167D01*
X1361167D01*
G01X1364083D02*
X1365833Y-760000D01*
G01X1375333D02*
X1370667D01*
Y-750000D01*
X1375333D01*
G01X1373467Y-754833D02*
X1370667D01*
G01X1379583Y-750000D02*
X1382500Y-760000D01*
X1385417Y-750000D01*
G54D12*
X-1670620Y387470D03*
X-1312008Y-149449D03*
X-441929D03*
G54D21*
X-1670620Y598070D03*
X-1649000Y-121500D03*
Y-105752D03*
Y-113626D03*
Y-97878D03*
X-793728Y-161850D03*
Y-153976D03*
Y-138228D03*
Y-146102D03*
G54D40*
G01X-894650Y-235600D02*
Y-228100D01*
X-895710Y-229600D01*
G01Y-235600D02*
X-893590D01*
G01X-888952Y-234725D02*
X-888333Y-235350D01*
X-887627Y-235600D01*
X-886920Y-235350D01*
X-886302Y-234600D01*
X-885860Y-233475D01*
X-885683Y-232350D01*
Y-230975D01*
X-885860Y-229850D01*
X-886302Y-228850D01*
X-886832Y-228350D01*
X-887450Y-228100D01*
X-888157Y-228350D01*
X-888687Y-228850D01*
X-889040Y-229600D01*
X-889217Y-230600D01*
X-889040Y-231475D01*
X-888598Y-232350D01*
X-888068Y-232850D01*
X-887450Y-232975D01*
X-886743Y-232725D01*
X-886213Y-232100D01*
X-885683Y-230975D01*
G01X132850Y-79300D02*
Y-71800D01*
X131790Y-73300D01*
G01Y-79300D02*
X133910D01*
G01X138372Y-73050D02*
X138902Y-72300D01*
X139520Y-71925D01*
X140227Y-71800D01*
X141110Y-72050D01*
X141728Y-72675D01*
X141905Y-73425D01*
X141817Y-74175D01*
X141463Y-74800D01*
X139697Y-76050D01*
X138902Y-76925D01*
X138372Y-78175D01*
X138195Y-79300D01*
X141905D01*
G54D31*
G01X-950300Y482089D02*
Y502089D01*
X-945634D01*
X-943767Y501089D01*
X-942367Y499756D01*
X-941200Y497756D01*
X-940267Y495422D01*
X-940034Y492089D01*
X-940267Y488755D01*
X-941200Y486422D01*
X-942367Y484422D01*
X-943767Y483089D01*
X-945634Y482089D01*
X-950300D01*
G01X-921500D02*
X-930834D01*
Y502089D01*
X-921500D01*
G01X-925234Y492423D02*
X-930834D01*
G01X-907167Y502089D02*
Y482089D01*
G01X-912534Y502089D02*
X-901800D01*
G01X-894001Y482089D02*
X-888167Y502089D01*
X-882333Y482089D01*
G01X-884434Y489089D02*
X-891901D01*
G01X-871967Y502089D02*
X-866367D01*
G01X-869167D02*
Y482089D01*
G01X-871967D02*
X-866367D01*
G01X-854834Y502089D02*
Y482089D01*
X-845500D01*
G01X-818001D02*
X-812167Y502089D01*
X-806333Y482089D01*
G01X-808434Y489089D02*
X-815901D01*
G01X-775334Y475423D02*
X-777667Y478756D01*
X-778834Y482089D01*
Y495422D01*
X-777667Y498756D01*
X-775334Y502089D01*
G01X-759600Y490422D02*
X-757967Y492756D01*
X-756567Y494089D01*
X-754700Y494755D01*
X-753067Y494089D01*
X-751900Y492756D01*
X-750967Y490756D01*
X-750734Y488422D01*
X-750967Y486422D01*
X-751900Y484422D01*
X-753301Y482756D01*
X-754934Y482089D01*
X-756800Y482756D01*
X-758434Y484755D01*
X-759367Y487756D01*
X-759600Y491089D01*
X-759134Y495422D01*
X-758434Y497756D01*
X-757267Y500089D01*
X-755634Y501756D01*
X-754000Y502089D01*
X-752367Y501422D01*
X-751200Y499756D01*
G01X-741067Y482089D02*
X-731267Y502089D01*
G01X-741067D02*
X-731267Y482089D01*
G01X-716000Y475423D02*
X-713667Y478756D01*
X-712500Y482089D01*
Y495422D01*
X-713667Y498756D01*
X-716000Y502089D01*
G01X-261770Y598920D02*
Y618920D01*
X-270404Y604587D01*
X-258736D01*
G01X-250703Y601919D02*
X-249304Y600253D01*
X-247670Y599253D01*
X-245570Y598920D01*
X-243470Y599587D01*
X-241837Y600920D01*
X-240670Y603253D01*
X-240437Y605920D01*
X-240903Y608586D01*
X-242070Y610253D01*
X-243704Y611586D01*
X-245336Y611920D01*
X-246970Y611586D01*
X-249070Y610253D01*
X-248370Y618920D01*
X-242070D01*
G01X-226570Y598253D02*
X-227037Y598587D01*
Y599253D01*
X-226570Y599587D01*
X-226103Y599253D01*
Y598587D01*
X-226570Y598253D01*
G01X-207570Y618920D02*
X-209437Y618253D01*
X-210837Y616587D01*
X-211770Y614587D01*
X-212470Y611920D01*
X-212703Y608920D01*
X-212470Y605920D01*
X-211770Y603253D01*
X-210837Y601253D01*
X-209437Y599587D01*
X-207570Y598920D01*
X-205704Y599587D01*
X-204303Y601253D01*
X-203370Y603253D01*
X-202670Y605920D01*
X-202437Y608920D01*
X-202670Y611920D01*
X-203370Y614587D01*
X-204303Y616587D01*
X-205704Y618253D01*
X-207570Y618920D01*
G01X-188570D02*
X-190437Y618253D01*
X-191837Y616587D01*
X-192770Y614587D01*
X-193470Y611920D01*
X-193703Y608920D01*
X-193470Y605920D01*
X-192770Y603253D01*
X-191837Y601253D01*
X-190437Y599587D01*
X-188570Y598920D01*
X-186704Y599587D01*
X-185303Y601253D01*
X-184370Y603253D01*
X-183670Y605920D01*
X-183437Y608920D01*
X-183670Y611920D01*
X-184370Y614587D01*
X-185303Y616587D01*
X-186704Y618253D01*
X-188570Y618920D01*
G01X-260697Y484755D02*
X-258830Y483089D01*
X-256730Y482089D01*
X-254864D01*
X-252997Y483089D01*
X-251597Y484755D01*
X-250897Y487089D01*
X-251364Y489422D01*
X-252530Y491422D01*
X-254630Y492756D01*
X-257430Y493422D01*
X-259064Y494755D01*
X-259764Y497089D01*
X-259297Y499422D01*
X-258130Y501089D01*
X-256497Y502089D01*
X-254864D01*
X-253230Y501422D01*
X-251830Y499756D01*
G01X-232130Y482089D02*
X-241464D01*
Y502089D01*
X-232130D01*
G01X-235864Y492423D02*
X-241464D01*
G01X-212664Y500422D02*
X-214064Y501422D01*
X-215697Y502089D01*
X-217564D01*
X-219664Y501089D01*
X-221297Y499422D01*
X-222464Y497422D01*
X-223397Y494089D01*
X-223631Y491089D01*
X-223164Y488089D01*
X-222464Y486089D01*
X-221064Y484089D01*
X-219430Y482756D01*
X-217797Y482089D01*
X-216164D01*
X-214530Y482756D01*
X-213130Y483755D01*
X-211963Y485088D01*
G01X-198797Y502089D02*
Y482089D01*
G01X-204164Y502089D02*
X-193430D01*
G01X-182597D02*
X-176997D01*
G01X-179797D02*
Y482089D01*
G01X-182597D02*
X-176997D01*
G01X-160797D02*
X-162664Y482422D01*
X-164297Y483755D01*
X-165697Y485755D01*
X-166631Y488089D01*
X-167097Y490756D01*
Y493422D01*
X-166631Y496089D01*
X-165697Y498423D01*
X-164297Y500422D01*
X-162664Y501756D01*
X-160797Y502089D01*
X-158931Y501756D01*
X-157297Y500422D01*
X-155897Y498423D01*
X-154963Y496089D01*
X-154497Y493422D01*
Y490756D01*
X-154963Y488089D01*
X-155897Y485755D01*
X-157297Y483755D01*
X-158931Y482422D01*
X-160797Y482089D01*
G01X-147164D02*
Y502089D01*
X-136430Y482089D01*
Y502089D01*
G01X-109631Y482089D02*
X-103797Y502089D01*
X-97963Y482089D01*
G01X-100064Y489089D02*
X-107531D01*
G01X-84797Y481422D02*
X-85264Y481756D01*
Y482422D01*
X-84797Y482756D01*
X-84330Y482422D01*
Y481756D01*
X-84797Y481422D01*
G01Y490422D02*
X-85264Y490756D01*
Y491422D01*
X-84797Y491755D01*
X-84330Y491422D01*
Y490756D01*
X-84797Y490422D01*
G01X-71631Y482089D02*
X-65797Y502089D01*
X-59963Y482089D01*
G01X-62064Y489089D02*
X-69531D01*
G01X-28964Y475423D02*
X-31297Y478756D01*
X-32464Y482089D01*
Y495422D01*
X-31297Y498756D01*
X-28964Y502089D01*
G01X-13230Y498756D02*
X-11830Y500755D01*
X-10197Y501756D01*
X-8330Y502089D01*
X-5997Y501422D01*
X-4364Y499756D01*
X-3897Y497756D01*
X-4130Y495755D01*
X-5064Y494089D01*
X-9730Y490756D01*
X-11830Y488422D01*
X-13230Y485088D01*
X-13697Y482089D01*
X-3897D01*
G01X5303D02*
X15103Y502089D01*
G01X5303D02*
X15103Y482089D01*
G01X30370Y475423D02*
X32703Y478756D01*
X33870Y482089D01*
Y495422D01*
X32703Y498756D01*
X30370Y502089D01*
G01X-254270Y558920D02*
Y578920D01*
X-262904Y564587D01*
X-251236D01*
G01X-243203Y561919D02*
X-241804Y560253D01*
X-240170Y559253D01*
X-238070Y558920D01*
X-235970Y559587D01*
X-234337Y560920D01*
X-233170Y563253D01*
X-232937Y565920D01*
X-233403Y568586D01*
X-234570Y570253D01*
X-236204Y571586D01*
X-237836Y571920D01*
X-239470Y571586D01*
X-241570Y570253D01*
X-240870Y578920D01*
X-234570D01*
G01X-219070Y558253D02*
X-219537Y558587D01*
Y559253D01*
X-219070Y559587D01*
X-218603Y559253D01*
Y558587D01*
X-219070Y558253D01*
G01X-200070Y578920D02*
X-201937Y578253D01*
X-203337Y576587D01*
X-204270Y574587D01*
X-204970Y571920D01*
X-205203Y568920D01*
X-204970Y565920D01*
X-204270Y563253D01*
X-203337Y561253D01*
X-201937Y559587D01*
X-200070Y558920D01*
X-198204Y559587D01*
X-196803Y561253D01*
X-195870Y563253D01*
X-195170Y565920D01*
X-194937Y568920D01*
X-195170Y571920D01*
X-195870Y574587D01*
X-196803Y576587D01*
X-198204Y578253D01*
X-200070Y578920D01*
G01X-181070D02*
X-182937Y578253D01*
X-184337Y576587D01*
X-185270Y574587D01*
X-185970Y571920D01*
X-186203Y568920D01*
X-185970Y565920D01*
X-185270Y563253D01*
X-184337Y561253D01*
X-182937Y559587D01*
X-181070Y558920D01*
X-179204Y559587D01*
X-177803Y561253D01*
X-176870Y563253D01*
X-176170Y565920D01*
X-175937Y568920D01*
X-176170Y571920D01*
X-176870Y574587D01*
X-177803Y576587D01*
X-179204Y578253D01*
X-181070Y578920D01*
G01X2430Y610920D02*
X563Y610253D01*
X-837Y608587D01*
X-1770Y606587D01*
X-2470Y603920D01*
X-2703Y600920D01*
X-2470Y597920D01*
X-1770Y595253D01*
X-837Y593253D01*
X563Y591587D01*
X2430Y590920D01*
X4296Y591587D01*
X5697Y593253D01*
X6630Y595253D01*
X7330Y597920D01*
X7563Y600920D01*
X7330Y603920D01*
X6630Y606587D01*
X5697Y608587D01*
X4296Y610253D01*
X2430Y610920D01*
G01X21430Y590253D02*
X20963Y590587D01*
Y591253D01*
X21430Y591587D01*
X21897Y591253D01*
Y590587D01*
X21430Y590253D01*
G01X35297Y593919D02*
X36696Y592253D01*
X38330Y591253D01*
X40430Y590920D01*
X42530Y591587D01*
X44163Y592920D01*
X45330Y595253D01*
X45563Y597920D01*
X45097Y600586D01*
X43930Y602253D01*
X42296Y603586D01*
X40664Y603920D01*
X39030Y603586D01*
X36930Y602253D01*
X37630Y610920D01*
X43930D01*
G01X59430D02*
X57563Y610253D01*
X56163Y608587D01*
X55230Y606587D01*
X54530Y603920D01*
X54297Y600920D01*
X54530Y597920D01*
X55230Y595253D01*
X56163Y593253D01*
X57563Y591587D01*
X59430Y590920D01*
X61296Y591587D01*
X62697Y593253D01*
X63630Y595253D01*
X64330Y597920D01*
X64563Y600920D01*
X64330Y603920D01*
X63630Y606587D01*
X62697Y608587D01*
X61296Y610253D01*
X59430Y610920D01*
G01X-7570Y650920D02*
X-9437Y650253D01*
X-10837Y648587D01*
X-11770Y646587D01*
X-12470Y643920D01*
X-12703Y640920D01*
X-12470Y637920D01*
X-11770Y635253D01*
X-10837Y633253D01*
X-9437Y631587D01*
X-7570Y630920D01*
X-5704Y631587D01*
X-4303Y633253D01*
X-3370Y635253D01*
X-2670Y637920D01*
X-2437Y640920D01*
X-2670Y643920D01*
X-3370Y646587D01*
X-4303Y648587D01*
X-5704Y650253D01*
X-7570Y650920D01*
G01X11430Y630253D02*
X10963Y630587D01*
Y631253D01*
X11430Y631587D01*
X11897Y631253D01*
Y630587D01*
X11430Y630253D01*
G01X30430Y650920D02*
X28563Y650253D01*
X27163Y648587D01*
X26230Y646587D01*
X25530Y643920D01*
X25297Y640920D01*
X25530Y637920D01*
X26230Y635253D01*
X27163Y633253D01*
X28563Y631587D01*
X30430Y630920D01*
X32296Y631587D01*
X33697Y633253D01*
X34630Y635253D01*
X35330Y637920D01*
X35563Y640920D01*
X35330Y643920D01*
X34630Y646587D01*
X33697Y648587D01*
X32296Y650253D01*
X30430Y650920D01*
G01X44997Y647587D02*
X46397Y649586D01*
X48030Y650587D01*
X49897Y650920D01*
X52230Y650253D01*
X53863Y648587D01*
X54330Y646587D01*
X54097Y644586D01*
X53163Y642920D01*
X48497Y639587D01*
X46397Y637253D01*
X44997Y633919D01*
X44530Y630920D01*
X54330D01*
G01X68430Y650920D02*
X66563Y650253D01*
X65163Y648587D01*
X64230Y646587D01*
X63530Y643920D01*
X63297Y640920D01*
X63530Y637920D01*
X64230Y635253D01*
X65163Y633253D01*
X66563Y631587D01*
X68430Y630920D01*
X70296Y631587D01*
X71697Y633253D01*
X72630Y635253D01*
X73330Y637920D01*
X73563Y640920D01*
X73330Y643920D01*
X72630Y646587D01*
X71697Y648587D01*
X70296Y650253D01*
X68430Y650920D01*
G01X1019867Y-790000D02*
Y-770000D01*
X1024533D01*
X1026400Y-771000D01*
X1027800Y-772333D01*
X1028967Y-774333D01*
X1029900Y-776667D01*
X1030133Y-780000D01*
X1029900Y-783334D01*
X1028967Y-785667D01*
X1027800Y-787667D01*
X1026400Y-789000D01*
X1024533Y-790000D01*
X1019867D01*
G01X1108100Y-787000D02*
X1117900Y-767000D01*
G01X1108100D02*
X1117900Y-787000D01*
G01X1132000D02*
X1133633Y-786667D01*
X1135500Y-785667D01*
X1136667Y-784001D01*
X1137133Y-781667D01*
X1136667Y-779334D01*
X1135267Y-777334D01*
X1133167Y-776333D01*
X1130833D01*
X1129433Y-775667D01*
X1128266Y-774000D01*
X1127800Y-771667D01*
X1128500Y-769333D01*
X1130133Y-767667D01*
X1132000Y-767000D01*
X1133866Y-767667D01*
X1135500Y-769333D01*
X1136200Y-771667D01*
X1135733Y-774000D01*
X1134567Y-775667D01*
X1133167Y-776333D01*
X1130833D01*
X1128733Y-777334D01*
X1127333Y-779334D01*
X1126867Y-781667D01*
X1127333Y-784001D01*
X1128500Y-785667D01*
X1130367Y-786667D01*
X1132000Y-787000D01*
G01X1151000D02*
X1152633Y-786667D01*
X1154500Y-785667D01*
X1155667Y-784001D01*
X1156133Y-781667D01*
X1155667Y-779334D01*
X1154267Y-777334D01*
X1152167Y-776333D01*
X1149833D01*
X1148433Y-775667D01*
X1147266Y-774000D01*
X1146800Y-771667D01*
X1147500Y-769333D01*
X1149133Y-767667D01*
X1151000Y-767000D01*
X1152866Y-767667D01*
X1154500Y-769333D01*
X1155200Y-771667D01*
X1154733Y-774000D01*
X1153567Y-775667D01*
X1152167Y-776333D01*
X1149833D01*
X1147733Y-777334D01*
X1146333Y-779334D01*
X1145867Y-781667D01*
X1146333Y-784001D01*
X1147500Y-785667D01*
X1149367Y-786667D01*
X1151000Y-787000D01*
G01X1169533D02*
X1170000Y-782667D01*
X1170700Y-779000D01*
X1171633Y-775667D01*
X1172800Y-772000D01*
X1174667Y-767000D01*
X1165333D01*
G01X1183867Y-784001D02*
X1185266Y-785667D01*
X1186900Y-786667D01*
X1189000Y-787000D01*
X1191100Y-786333D01*
X1192733Y-785000D01*
X1193900Y-782667D01*
X1194133Y-780000D01*
X1193667Y-777334D01*
X1192500Y-775667D01*
X1190866Y-774334D01*
X1189234Y-774000D01*
X1187600Y-774334D01*
X1185500Y-775667D01*
X1186200Y-767000D01*
X1192500D01*
G01X1207533Y-787000D02*
X1208000Y-782667D01*
X1208700Y-779000D01*
X1209633Y-775667D01*
X1210800Y-772000D01*
X1212667Y-767000D01*
X1203333D01*
G01X1227000Y-787000D02*
Y-767000D01*
X1224200Y-771000D01*
G01Y-787000D02*
X1229800D01*
G01X1307567Y-770333D02*
X1308967Y-768334D01*
X1310600Y-767333D01*
X1312467Y-767000D01*
X1314800Y-767667D01*
X1316433Y-769333D01*
X1316900Y-771333D01*
X1316667Y-773334D01*
X1315733Y-775000D01*
X1311067Y-778333D01*
X1308967Y-780667D01*
X1307567Y-784001D01*
X1307100Y-787000D01*
X1316900D01*
G01X1375866Y-777333D02*
X1376800Y-776333D01*
X1377500Y-774667D01*
X1377967Y-772333D01*
X1377500Y-770333D01*
X1376567Y-769000D01*
X1374933Y-768000D01*
X1368633D01*
Y-788000D01*
X1376333D01*
X1377967Y-786667D01*
X1378900Y-784667D01*
X1379367Y-782333D01*
X1378900Y-780000D01*
X1377500Y-778000D01*
X1375866Y-777333D01*
X1368633D01*
G54D22*
X-1670620Y621470D03*
X-1141240Y-132520D03*
Y-112835D03*
Y-94331D03*
X-1132087Y-150630D03*
X-1113189D03*
X-1094291D03*
X-1085138Y-132520D03*
Y-112835D03*
Y-94331D03*
X-271161Y-132520D03*
Y-112835D03*
Y-94331D03*
X-262008Y-150630D03*
X-243110D03*
X-224213D03*
X-215059Y-132520D03*
Y-112835D03*
Y-94331D03*
G54D13*
X-1670620Y410870D03*
X-1132087Y-126220D03*
X-1094291D03*
X-262008D03*
X-224213D03*
G54D41*
G01X-921900Y-259600D02*
X-919400Y-268100D01*
X-916900Y-259600D01*
G01X-912500D02*
X-910100D01*
G01X-911300D02*
Y-268100D01*
G01X-912500D02*
X-910100D01*
G01X-901200D02*
X-905200D01*
Y-259600D01*
X-901200D01*
G01X-902800Y-263708D02*
X-905200D01*
G01X-898100Y-259600D02*
X-896700Y-268100D01*
X-895100Y-259600D01*
X-893500Y-268100D01*
X-892100Y-259600D01*
G01X-876900Y-268100D02*
X-880900D01*
Y-259600D01*
X-876900D01*
G01X-878500Y-263708D02*
X-880900D01*
G01X-872100Y-265267D02*
X-869500D01*
G01X-860700Y-268100D02*
X-864700D01*
Y-259600D01*
X-860700D01*
G01X-862300Y-263708D02*
X-864700D01*
G01X195445Y816000D02*
X197965D01*
G01X196600Y817950D02*
Y814050D01*
G01X203310Y812700D02*
X207090Y822000D01*
G01X212435Y816000D02*
X215165D01*
G01X228690Y814350D02*
X229320Y813600D01*
X230055Y813150D01*
X231000Y813000D01*
X231945Y813300D01*
X232680Y813900D01*
X233205Y814950D01*
X233310Y816150D01*
X233100Y817350D01*
X232575Y818100D01*
X231840Y818700D01*
X231105Y818850D01*
X230370Y818700D01*
X229425Y818100D01*
X229740Y822000D01*
X232575D01*
G01X245470Y813000D02*
Y822000D01*
X248200Y814500D01*
X250930Y822000D01*
Y813000D01*
G01X255540Y822000D02*
X258060D01*
G01X256800D02*
Y813000D01*
G01X255540D02*
X258060D01*
G01X263300Y822000D02*
Y813000D01*
X267500D01*
G01X201405Y837250D02*
X202140Y838300D01*
X202770Y838900D01*
X203610Y839200D01*
X204345Y838900D01*
X204870Y838300D01*
X205290Y837400D01*
X205395Y836350D01*
X205290Y835450D01*
X204870Y834550D01*
X204240Y833800D01*
X203505Y833500D01*
X202665Y833800D01*
X201930Y834700D01*
X201510Y836050D01*
X201405Y837550D01*
X201615Y839500D01*
X201930Y840550D01*
X202455Y841600D01*
X203190Y842350D01*
X203925Y842500D01*
X204660Y842200D01*
X205185Y841450D01*
G01X210005Y841000D02*
X210635Y841900D01*
X211370Y842350D01*
X212210Y842500D01*
X213260Y842200D01*
X213995Y841450D01*
X214205Y840550D01*
X214100Y839650D01*
X213680Y838900D01*
X211580Y837400D01*
X210635Y836350D01*
X210005Y834850D01*
X209795Y833500D01*
X214205D01*
G01X220600Y833200D02*
X220390Y833350D01*
Y833650D01*
X220600Y833800D01*
X220810Y833650D01*
Y833350D01*
X220600Y833200D01*
G01X227205Y837250D02*
X227940Y838300D01*
X228570Y838900D01*
X229410Y839200D01*
X230145Y838900D01*
X230670Y838300D01*
X231090Y837400D01*
X231195Y836350D01*
X231090Y835450D01*
X230670Y834550D01*
X230040Y833800D01*
X229305Y833500D01*
X228465Y833800D01*
X227730Y834700D01*
X227310Y836050D01*
X227205Y837550D01*
X227415Y839500D01*
X227730Y840550D01*
X228255Y841600D01*
X228990Y842350D01*
X229725Y842500D01*
X230460Y842200D01*
X230985Y841450D01*
G01X243670Y833500D02*
Y842500D01*
X246400Y835000D01*
X249130Y842500D01*
Y833500D01*
G01X253740Y842500D02*
X256260D01*
G01X255000D02*
Y833500D01*
G01X253740D02*
X256260D01*
G01X261500Y842500D02*
Y833500D01*
X265700D01*
G01X278350Y780600D02*
Y789600D01*
X277090Y787800D01*
G01Y780600D02*
X279610D01*
G01X284640Y781950D02*
X285270Y781200D01*
X286005Y780750D01*
X286950Y780600D01*
X287895Y780900D01*
X288630Y781500D01*
X289155Y782550D01*
X289260Y783750D01*
X289050Y784950D01*
X288525Y785700D01*
X287790Y786300D01*
X287055Y786450D01*
X286320Y786300D01*
X285375Y785700D01*
X285690Y789600D01*
X288525D01*
G01X295550Y780300D02*
X295340Y780450D01*
Y780750D01*
X295550Y780900D01*
X295760Y780750D01*
Y780450D01*
X295550Y780300D01*
G01X304150Y789600D02*
X303310Y789300D01*
X302680Y788550D01*
X302260Y787650D01*
X301945Y786450D01*
X301840Y785100D01*
X301945Y783750D01*
X302260Y782550D01*
X302680Y781650D01*
X303310Y780900D01*
X304150Y780600D01*
X304990Y780900D01*
X305620Y781650D01*
X306040Y782550D01*
X306355Y783750D01*
X306460Y785100D01*
X306355Y786450D01*
X306040Y787650D01*
X305620Y788550D01*
X304990Y789300D01*
X304150Y789600D01*
G01X320195Y783600D02*
X322715D01*
G01X321350Y785550D02*
Y781650D01*
G01X328060Y780300D02*
X331840Y789600D01*
G01X337185Y783600D02*
X339915D01*
G01X355750Y789600D02*
X354910Y789300D01*
X354280Y788550D01*
X353860Y787650D01*
X353545Y786450D01*
X353440Y785100D01*
X353545Y783750D01*
X353860Y782550D01*
X354280Y781650D01*
X354910Y780900D01*
X355750Y780600D01*
X356590Y780900D01*
X357220Y781650D01*
X357640Y782550D01*
X357955Y783750D01*
X358060Y785100D01*
X357955Y786450D01*
X357640Y787650D01*
X357220Y788550D01*
X356590Y789300D01*
X355750Y789600D01*
G01X364350Y780300D02*
X364140Y780450D01*
Y780750D01*
X364350Y780900D01*
X364560Y780750D01*
Y780450D01*
X364350Y780300D01*
G01X370640Y781950D02*
X371270Y781200D01*
X372005Y780750D01*
X372950Y780600D01*
X373895Y780900D01*
X374630Y781500D01*
X375155Y782550D01*
X375260Y783750D01*
X375050Y784950D01*
X374525Y785700D01*
X373790Y786300D01*
X373055Y786450D01*
X372320Y786300D01*
X371375Y785700D01*
X371690Y789600D01*
X374525D01*
G01X387420Y780600D02*
Y789600D01*
X390150Y782100D01*
X392880Y789600D01*
Y780600D01*
G01X397490Y789600D02*
X400010D01*
G01X398750D02*
Y780600D01*
G01X397490D02*
X400010D01*
G01X405250Y789600D02*
Y780600D01*
X409450D01*
G01X277850Y887600D02*
Y896600D01*
X276590Y894800D01*
G01Y887600D02*
X279110D01*
G01X284140Y888950D02*
X284770Y888200D01*
X285505Y887750D01*
X286450Y887600D01*
X287395Y887900D01*
X288130Y888500D01*
X288655Y889550D01*
X288760Y890750D01*
X288550Y891950D01*
X288025Y892700D01*
X287290Y893300D01*
X286555Y893450D01*
X285820Y893300D01*
X284875Y892700D01*
X285190Y896600D01*
X288025D01*
G01X295050Y887300D02*
X294840Y887450D01*
Y887750D01*
X295050Y887900D01*
X295260Y887750D01*
Y887450D01*
X295050Y887300D01*
G01X303650Y896600D02*
X302810Y896300D01*
X302180Y895550D01*
X301760Y894650D01*
X301445Y893450D01*
X301340Y892100D01*
X301445Y890750D01*
X301760Y889550D01*
X302180Y888650D01*
X302810Y887900D01*
X303650Y887600D01*
X304490Y887900D01*
X305120Y888650D01*
X305540Y889550D01*
X305855Y890750D01*
X305960Y892100D01*
X305855Y893450D01*
X305540Y894650D01*
X305120Y895550D01*
X304490Y896300D01*
X303650Y896600D01*
G01X319695Y890600D02*
X322215D01*
G01X320850Y892550D02*
Y888650D01*
G01X327560Y887300D02*
X331340Y896600D01*
G01X336685Y890600D02*
X339415D01*
G01X355250Y896600D02*
X354410Y896300D01*
X353780Y895550D01*
X353360Y894650D01*
X353045Y893450D01*
X352940Y892100D01*
X353045Y890750D01*
X353360Y889550D01*
X353780Y888650D01*
X354410Y887900D01*
X355250Y887600D01*
X356090Y887900D01*
X356720Y888650D01*
X357140Y889550D01*
X357455Y890750D01*
X357560Y892100D01*
X357455Y893450D01*
X357140Y894650D01*
X356720Y895550D01*
X356090Y896300D01*
X355250Y896600D01*
G01X363850Y887300D02*
X363640Y887450D01*
Y887750D01*
X363850Y887900D01*
X364060Y887750D01*
Y887450D01*
X363850Y887300D01*
G01X370140Y888950D02*
X370770Y888200D01*
X371505Y887750D01*
X372450Y887600D01*
X373395Y887900D01*
X374130Y888500D01*
X374655Y889550D01*
X374760Y890750D01*
X374550Y891950D01*
X374025Y892700D01*
X373290Y893300D01*
X372555Y893450D01*
X371820Y893300D01*
X370875Y892700D01*
X371190Y896600D01*
X374025D01*
G01X386920Y887600D02*
Y896600D01*
X389650Y889100D01*
X392380Y896600D01*
Y887600D01*
G01X396990Y896600D02*
X399510D01*
G01X398250D02*
Y887600D01*
G01X396990D02*
X399510D01*
G01X404750Y896600D02*
Y887600D01*
X408950D01*
G01X287800Y645000D02*
X286960Y644700D01*
X286330Y643950D01*
X285910Y643050D01*
X285595Y641850D01*
X285490Y640500D01*
X285595Y639150D01*
X285910Y637950D01*
X286330Y637050D01*
X286960Y636300D01*
X287800Y636000D01*
X288640Y636300D01*
X289270Y637050D01*
X289690Y637950D01*
X290005Y639150D01*
X290110Y640500D01*
X290005Y641850D01*
X289690Y643050D01*
X289270Y643950D01*
X288640Y644700D01*
X287800Y645000D01*
G01X296400Y635700D02*
X296190Y635850D01*
Y636150D01*
X296400Y636300D01*
X296610Y636150D01*
Y635850D01*
X296400Y635700D01*
G01X302690Y637350D02*
X303320Y636600D01*
X304055Y636150D01*
X305000Y636000D01*
X305945Y636300D01*
X306680Y636900D01*
X307205Y637950D01*
X307310Y639150D01*
X307100Y640350D01*
X306575Y641100D01*
X305840Y641700D01*
X305105Y641850D01*
X304370Y641700D01*
X303425Y641100D01*
X303740Y645000D01*
X306575D01*
G01X321045Y639000D02*
X323565D01*
G01X322200Y640950D02*
Y637050D01*
G01X328910Y635700D02*
X332690Y645000D01*
G01X338035Y639000D02*
X340765D01*
G01X356600Y645000D02*
X355760Y644700D01*
X355130Y643950D01*
X354710Y643050D01*
X354395Y641850D01*
X354290Y640500D01*
X354395Y639150D01*
X354710Y637950D01*
X355130Y637050D01*
X355760Y636300D01*
X356600Y636000D01*
X357440Y636300D01*
X358070Y637050D01*
X358490Y637950D01*
X358805Y639150D01*
X358910Y640500D01*
X358805Y641850D01*
X358490Y643050D01*
X358070Y643950D01*
X357440Y644700D01*
X356600Y645000D01*
G01X365200Y635700D02*
X364990Y635850D01*
Y636150D01*
X365200Y636300D01*
X365410Y636150D01*
Y635850D01*
X365200Y635700D01*
G01X373800Y636000D02*
Y645000D01*
X372540Y643200D01*
G01Y636000D02*
X375060D01*
G01X388270D02*
Y645000D01*
X391000Y637500D01*
X393730Y645000D01*
Y636000D01*
G01X398340Y645000D02*
X400860D01*
G01X399600D02*
Y636000D01*
G01X398340D02*
X400860D01*
G01X406100Y645000D02*
Y636000D01*
X410300D01*
G01X286950Y655600D02*
Y664600D01*
X285690Y662800D01*
G01Y655600D02*
X288210D01*
G01X295550Y655300D02*
X295340Y655450D01*
Y655750D01*
X295550Y655900D01*
X295760Y655750D01*
Y655450D01*
X295550Y655300D01*
G01X302365Y656650D02*
X303100Y655900D01*
X303940Y655600D01*
X304780Y655900D01*
X305515Y656800D01*
X306040Y658150D01*
X306250Y659500D01*
Y661150D01*
X306040Y662500D01*
X305515Y663700D01*
X304885Y664300D01*
X304150Y664600D01*
X303310Y664300D01*
X302680Y663700D01*
X302260Y662800D01*
X302050Y661600D01*
X302260Y660550D01*
X302785Y659500D01*
X303415Y658900D01*
X304150Y658750D01*
X304990Y659050D01*
X305620Y659800D01*
X306250Y661150D01*
G01X320195Y658600D02*
X322715D01*
G01X321350Y660550D02*
Y656650D01*
G01X328060Y655300D02*
X331840Y664600D01*
G01X337185Y658600D02*
X339915D01*
G01X355750Y664600D02*
X354910Y664300D01*
X354280Y663550D01*
X353860Y662650D01*
X353545Y661450D01*
X353440Y660100D01*
X353545Y658750D01*
X353860Y657550D01*
X354280Y656650D01*
X354910Y655900D01*
X355750Y655600D01*
X356590Y655900D01*
X357220Y656650D01*
X357640Y657550D01*
X357955Y658750D01*
X358060Y660100D01*
X357955Y661450D01*
X357640Y662650D01*
X357220Y663550D01*
X356590Y664300D01*
X355750Y664600D01*
G01X364350Y655300D02*
X364140Y655450D01*
Y655750D01*
X364350Y655900D01*
X364560Y655750D01*
Y655450D01*
X364350Y655300D01*
G01X370640Y657400D02*
X371270Y656350D01*
X372110Y655750D01*
X373055Y655600D01*
X373895Y655750D01*
X374735Y656500D01*
X375260Y657400D01*
X375365Y658300D01*
X375155Y659350D01*
X374420Y660100D01*
X373685Y660400D01*
X372740D01*
G01X373685D02*
X374315Y660850D01*
X374840Y661600D01*
X375050Y662500D01*
X374840Y663400D01*
X374315Y664150D01*
X373370Y664600D01*
X372425Y664450D01*
X371480Y663850D01*
G01X387420Y655600D02*
Y664600D01*
X390150Y657100D01*
X392880Y664600D01*
Y655600D01*
G01X397490Y664600D02*
X400010D01*
G01X398750D02*
Y655600D01*
G01X397490D02*
X400010D01*
G01X405250Y664600D02*
Y655600D01*
X409450D01*
G01X284955Y688100D02*
X285585Y689000D01*
X286320Y689450D01*
X287160Y689600D01*
X288210Y689300D01*
X288945Y688550D01*
X289155Y687650D01*
X289050Y686750D01*
X288630Y686000D01*
X286530Y684500D01*
X285585Y683450D01*
X284955Y681950D01*
X284745Y680600D01*
X289155D01*
G01X295550Y680300D02*
X295340Y680450D01*
Y680750D01*
X295550Y680900D01*
X295760Y680750D01*
Y680450D01*
X295550Y680300D01*
G01X303940Y680600D02*
X304150Y682550D01*
X304465Y684200D01*
X304885Y685700D01*
X305410Y687350D01*
X306250Y689600D01*
X302050D01*
G01X320195Y683600D02*
X322715D01*
G01X321350Y685550D02*
Y681650D01*
G01X328060Y680300D02*
X331840Y689600D01*
G01X337185Y683600D02*
X339915D01*
G01X355750Y689600D02*
X354910Y689300D01*
X354280Y688550D01*
X353860Y687650D01*
X353545Y686450D01*
X353440Y685100D01*
X353545Y683750D01*
X353860Y682550D01*
X354280Y681650D01*
X354910Y680900D01*
X355750Y680600D01*
X356590Y680900D01*
X357220Y681650D01*
X357640Y682550D01*
X357955Y683750D01*
X358060Y685100D01*
X357955Y686450D01*
X357640Y687650D01*
X357220Y688550D01*
X356590Y689300D01*
X355750Y689600D01*
G01X364350Y680300D02*
X364140Y680450D01*
Y680750D01*
X364350Y680900D01*
X364560Y680750D01*
Y680450D01*
X364350Y680300D01*
G01X370640Y681950D02*
X371270Y681200D01*
X372005Y680750D01*
X372950Y680600D01*
X373895Y680900D01*
X374630Y681500D01*
X375155Y682550D01*
X375260Y683750D01*
X375050Y684950D01*
X374525Y685700D01*
X373790Y686300D01*
X373055Y686450D01*
X372320Y686300D01*
X371375Y685700D01*
X371690Y689600D01*
X374525D01*
G01X387420Y680600D02*
Y689600D01*
X390150Y682100D01*
X392880Y689600D01*
Y680600D01*
G01X397490Y689600D02*
X400010D01*
G01X398750D02*
Y680600D01*
G01X397490D02*
X400010D01*
G01X405250Y689600D02*
Y680600D01*
X409450D01*
G01X286950Y708100D02*
Y717100D01*
X285690Y715300D01*
G01Y708100D02*
X288210D01*
G01X295550Y707800D02*
X295340Y707950D01*
Y708250D01*
X295550Y708400D01*
X295760Y708250D01*
Y707950D01*
X295550Y707800D01*
G01X301840Y709900D02*
X302470Y708850D01*
X303310Y708250D01*
X304255Y708100D01*
X305095Y708250D01*
X305935Y709000D01*
X306460Y709900D01*
X306565Y710800D01*
X306355Y711850D01*
X305620Y712600D01*
X304885Y712900D01*
X303940D01*
G01X304885D02*
X305515Y713350D01*
X306040Y714100D01*
X306250Y715000D01*
X306040Y715900D01*
X305515Y716650D01*
X304570Y717100D01*
X303625Y716950D01*
X302680Y716350D01*
G01X320195Y711100D02*
X322715D01*
G01X321350Y713050D02*
Y709150D01*
G01X328060Y707800D02*
X331840Y717100D01*
G01X337185Y711100D02*
X339915D01*
G01X355750Y717100D02*
X354910Y716800D01*
X354280Y716050D01*
X353860Y715150D01*
X353545Y713950D01*
X353440Y712600D01*
X353545Y711250D01*
X353860Y710050D01*
X354280Y709150D01*
X354910Y708400D01*
X355750Y708100D01*
X356590Y708400D01*
X357220Y709150D01*
X357640Y710050D01*
X357955Y711250D01*
X358060Y712600D01*
X357955Y713950D01*
X357640Y715150D01*
X357220Y716050D01*
X356590Y716800D01*
X355750Y717100D01*
G01X364350Y707800D02*
X364140Y707950D01*
Y708250D01*
X364350Y708400D01*
X364560Y708250D01*
Y707950D01*
X364350Y707800D01*
G01X374210Y708100D02*
Y717100D01*
X370325Y710650D01*
X375575D01*
G01X387420Y708100D02*
Y717100D01*
X390150Y709600D01*
X392880Y717100D01*
Y708100D01*
G01X397490Y717100D02*
X400010D01*
G01X398750D02*
Y708100D01*
G01X397490D02*
X400010D01*
G01X405250Y717100D02*
Y708100D01*
X409450D01*
G01X288210Y730600D02*
Y739600D01*
X284325Y733150D01*
X289575D01*
G01X295550Y730300D02*
X295340Y730450D01*
Y730750D01*
X295550Y730900D01*
X295760Y730750D01*
Y730450D01*
X295550Y730300D01*
G01X304150Y739600D02*
X303310Y739300D01*
X302680Y738550D01*
X302260Y737650D01*
X301945Y736450D01*
X301840Y735100D01*
X301945Y733750D01*
X302260Y732550D01*
X302680Y731650D01*
X303310Y730900D01*
X304150Y730600D01*
X304990Y730900D01*
X305620Y731650D01*
X306040Y732550D01*
X306355Y733750D01*
X306460Y735100D01*
X306355Y736450D01*
X306040Y737650D01*
X305620Y738550D01*
X304990Y739300D01*
X304150Y739600D01*
G01X320195Y733600D02*
X322715D01*
G01X321350Y735550D02*
Y731650D01*
G01X328060Y730300D02*
X331840Y739600D01*
G01X337185Y733600D02*
X339915D01*
G01X355750Y739600D02*
X354910Y739300D01*
X354280Y738550D01*
X353860Y737650D01*
X353545Y736450D01*
X353440Y735100D01*
X353545Y733750D01*
X353860Y732550D01*
X354280Y731650D01*
X354910Y730900D01*
X355750Y730600D01*
X356590Y730900D01*
X357220Y731650D01*
X357640Y732550D01*
X357955Y733750D01*
X358060Y735100D01*
X357955Y736450D01*
X357640Y737650D01*
X357220Y738550D01*
X356590Y739300D01*
X355750Y739600D01*
G01X364350Y730300D02*
X364140Y730450D01*
Y730750D01*
X364350Y730900D01*
X364560Y730750D01*
Y730450D01*
X364350Y730300D01*
G01X370640Y731950D02*
X371270Y731200D01*
X372005Y730750D01*
X372950Y730600D01*
X373895Y730900D01*
X374630Y731500D01*
X375155Y732550D01*
X375260Y733750D01*
X375050Y734950D01*
X374525Y735700D01*
X373790Y736300D01*
X373055Y736450D01*
X372320Y736300D01*
X371375Y735700D01*
X371690Y739600D01*
X374525D01*
G01X387420Y730600D02*
Y739600D01*
X390150Y732100D01*
X392880Y739600D01*
Y730600D01*
G01X397490Y739600D02*
X400010D01*
G01X398750D02*
Y730600D01*
G01X397490D02*
X400010D01*
G01X405250Y739600D02*
Y730600D01*
X409450D01*
G01X286950Y755600D02*
Y764600D01*
X285690Y762800D01*
G01Y755600D02*
X288210D01*
G01X295550Y755300D02*
X295340Y755450D01*
Y755750D01*
X295550Y755900D01*
X295760Y755750D01*
Y755450D01*
X295550Y755300D01*
G01X301840Y757400D02*
X302470Y756350D01*
X303310Y755750D01*
X304255Y755600D01*
X305095Y755750D01*
X305935Y756500D01*
X306460Y757400D01*
X306565Y758300D01*
X306355Y759350D01*
X305620Y760100D01*
X304885Y760400D01*
X303940D01*
G01X304885D02*
X305515Y760850D01*
X306040Y761600D01*
X306250Y762500D01*
X306040Y763400D01*
X305515Y764150D01*
X304570Y764600D01*
X303625Y764450D01*
X302680Y763850D01*
G01X320195Y758600D02*
X322715D01*
G01X321350Y760550D02*
Y756650D01*
G01X328060Y755300D02*
X331840Y764600D01*
G01X337185Y758600D02*
X339915D01*
G01X355750Y764600D02*
X354910Y764300D01*
X354280Y763550D01*
X353860Y762650D01*
X353545Y761450D01*
X353440Y760100D01*
X353545Y758750D01*
X353860Y757550D01*
X354280Y756650D01*
X354910Y755900D01*
X355750Y755600D01*
X356590Y755900D01*
X357220Y756650D01*
X357640Y757550D01*
X357955Y758750D01*
X358060Y760100D01*
X357955Y761450D01*
X357640Y762650D01*
X357220Y763550D01*
X356590Y764300D01*
X355750Y764600D01*
G01X364350Y755300D02*
X364140Y755450D01*
Y755750D01*
X364350Y755900D01*
X364560Y755750D01*
Y755450D01*
X364350Y755300D01*
G01X374210Y755600D02*
Y764600D01*
X370325Y758150D01*
X375575D01*
G01X387420Y755600D02*
Y764600D01*
X390150Y757100D01*
X392880Y764600D01*
Y755600D01*
G01X397490Y764600D02*
X400010D01*
G01X398750D02*
Y755600D01*
G01X397490D02*
X400010D01*
G01X405250Y764600D02*
Y755600D01*
X409450D01*
G01X284955Y813100D02*
X285585Y814000D01*
X286320Y814450D01*
X287160Y814600D01*
X288210Y814300D01*
X288945Y813550D01*
X289155Y812650D01*
X289050Y811750D01*
X288630Y811000D01*
X286530Y809500D01*
X285585Y808450D01*
X284955Y806950D01*
X284745Y805600D01*
X289155D01*
G01X295550Y805300D02*
X295340Y805450D01*
Y805750D01*
X295550Y805900D01*
X295760Y805750D01*
Y805450D01*
X295550Y805300D01*
G01X302155Y809350D02*
X302890Y810400D01*
X303520Y811000D01*
X304360Y811300D01*
X305095Y811000D01*
X305620Y810400D01*
X306040Y809500D01*
X306145Y808450D01*
X306040Y807550D01*
X305620Y806650D01*
X304990Y805900D01*
X304255Y805600D01*
X303415Y805900D01*
X302680Y806800D01*
X302260Y808150D01*
X302155Y809650D01*
X302365Y811600D01*
X302680Y812650D01*
X303205Y813700D01*
X303940Y814450D01*
X304675Y814600D01*
X305410Y814300D01*
X305935Y813550D01*
G01X320195Y808600D02*
X322715D01*
G01X321350Y810550D02*
Y806650D01*
G01X328060Y805300D02*
X331840Y814600D01*
G01X337185Y808600D02*
X339915D01*
G01X355750Y814600D02*
X354910Y814300D01*
X354280Y813550D01*
X353860Y812650D01*
X353545Y811450D01*
X353440Y810100D01*
X353545Y808750D01*
X353860Y807550D01*
X354280Y806650D01*
X354910Y805900D01*
X355750Y805600D01*
X356590Y805900D01*
X357220Y806650D01*
X357640Y807550D01*
X357955Y808750D01*
X358060Y810100D01*
X357955Y811450D01*
X357640Y812650D01*
X357220Y813550D01*
X356590Y814300D01*
X355750Y814600D01*
G01X364350Y805300D02*
X364140Y805450D01*
Y805750D01*
X364350Y805900D01*
X364560Y805750D01*
Y805450D01*
X364350Y805300D01*
G01X374210Y805600D02*
Y814600D01*
X370325Y808150D01*
X375575D01*
G01X387420Y805600D02*
Y814600D01*
X390150Y807100D01*
X392880Y814600D01*
Y805600D01*
G01X397490Y814600D02*
X400010D01*
G01X398750D02*
Y805600D01*
G01X397490D02*
X400010D01*
G01X405250Y814600D02*
Y805600D01*
X409450D01*
G01X287510Y833300D02*
Y842300D01*
X283625Y835850D01*
X288875D01*
G01X294850Y833000D02*
X294640Y833150D01*
Y833450D01*
X294850Y833600D01*
X295060Y833450D01*
Y833150D01*
X294850Y833000D01*
G01X303450Y842300D02*
X302610Y842000D01*
X301980Y841250D01*
X301560Y840350D01*
X301245Y839150D01*
X301140Y837800D01*
X301245Y836450D01*
X301560Y835250D01*
X301980Y834350D01*
X302610Y833600D01*
X303450Y833300D01*
X304290Y833600D01*
X304920Y834350D01*
X305340Y835250D01*
X305655Y836450D01*
X305760Y837800D01*
X305655Y839150D01*
X305340Y840350D01*
X304920Y841250D01*
X304290Y842000D01*
X303450Y842300D01*
G01X319495Y836300D02*
X322015D01*
G01X320650Y838250D02*
Y834350D01*
G01X327360Y833000D02*
X331140Y842300D01*
G01X336485Y836300D02*
X339215D01*
G01X355050Y842300D02*
X354210Y842000D01*
X353580Y841250D01*
X353160Y840350D01*
X352845Y839150D01*
X352740Y837800D01*
X352845Y836450D01*
X353160Y835250D01*
X353580Y834350D01*
X354210Y833600D01*
X355050Y833300D01*
X355890Y833600D01*
X356520Y834350D01*
X356940Y835250D01*
X357255Y836450D01*
X357360Y837800D01*
X357255Y839150D01*
X356940Y840350D01*
X356520Y841250D01*
X355890Y842000D01*
X355050Y842300D01*
G01X363650Y833000D02*
X363440Y833150D01*
Y833450D01*
X363650Y833600D01*
X363860Y833450D01*
Y833150D01*
X363650Y833000D01*
G01X369940Y834650D02*
X370570Y833900D01*
X371305Y833450D01*
X372250Y833300D01*
X373195Y833600D01*
X373930Y834200D01*
X374455Y835250D01*
X374560Y836450D01*
X374350Y837650D01*
X373825Y838400D01*
X373090Y839000D01*
X372355Y839150D01*
X371620Y839000D01*
X370675Y838400D01*
X370990Y842300D01*
X373825D01*
G01X386720Y833300D02*
Y842300D01*
X389450Y834800D01*
X392180Y842300D01*
Y833300D01*
G01X396790Y842300D02*
X399310D01*
G01X398050D02*
Y833300D01*
G01X396790D02*
X399310D01*
G01X404550Y842300D02*
Y833300D01*
X408750D01*
G01X284455Y870100D02*
X285085Y871000D01*
X285820Y871450D01*
X286660Y871600D01*
X287710Y871300D01*
X288445Y870550D01*
X288655Y869650D01*
X288550Y868750D01*
X288130Y868000D01*
X286030Y866500D01*
X285085Y865450D01*
X284455Y863950D01*
X284245Y862600D01*
X288655D01*
G01X295050Y862300D02*
X294840Y862450D01*
Y862750D01*
X295050Y862900D01*
X295260Y862750D01*
Y862450D01*
X295050Y862300D01*
G01X301655Y866350D02*
X302390Y867400D01*
X303020Y868000D01*
X303860Y868300D01*
X304595Y868000D01*
X305120Y867400D01*
X305540Y866500D01*
X305645Y865450D01*
X305540Y864550D01*
X305120Y863650D01*
X304490Y862900D01*
X303755Y862600D01*
X302915Y862900D01*
X302180Y863800D01*
X301760Y865150D01*
X301655Y866650D01*
X301865Y868600D01*
X302180Y869650D01*
X302705Y870700D01*
X303440Y871450D01*
X304175Y871600D01*
X304910Y871300D01*
X305435Y870550D01*
G01X319695Y865600D02*
X322215D01*
G01X320850Y867550D02*
Y863650D01*
G01X327560Y862300D02*
X331340Y871600D01*
G01X336685Y865600D02*
X339415D01*
G01X355250Y871600D02*
X354410Y871300D01*
X353780Y870550D01*
X353360Y869650D01*
X353045Y868450D01*
X352940Y867100D01*
X353045Y865750D01*
X353360Y864550D01*
X353780Y863650D01*
X354410Y862900D01*
X355250Y862600D01*
X356090Y862900D01*
X356720Y863650D01*
X357140Y864550D01*
X357455Y865750D01*
X357560Y867100D01*
X357455Y868450D01*
X357140Y869650D01*
X356720Y870550D01*
X356090Y871300D01*
X355250Y871600D01*
G01X363850Y862300D02*
X363640Y862450D01*
Y862750D01*
X363850Y862900D01*
X364060Y862750D01*
Y862450D01*
X363850Y862300D01*
G01X373710Y862600D02*
Y871600D01*
X369825Y865150D01*
X375075D01*
G01X386920Y862600D02*
Y871600D01*
X389650Y864100D01*
X392380Y871600D01*
Y862600D01*
G01X396990Y871600D02*
X399510D01*
G01X398250D02*
Y862600D01*
G01X396990D02*
X399510D01*
G01X404750Y871600D02*
Y862600D01*
X408950D01*
G01X286450Y912600D02*
Y921600D01*
X285190Y919800D01*
G01Y912600D02*
X287710D01*
G01X295050Y912300D02*
X294840Y912450D01*
Y912750D01*
X295050Y912900D01*
X295260Y912750D01*
Y912450D01*
X295050Y912300D01*
G01X301340Y914400D02*
X301970Y913350D01*
X302810Y912750D01*
X303755Y912600D01*
X304595Y912750D01*
X305435Y913500D01*
X305960Y914400D01*
X306065Y915300D01*
X305855Y916350D01*
X305120Y917100D01*
X304385Y917400D01*
X303440D01*
G01X304385D02*
X305015Y917850D01*
X305540Y918600D01*
X305750Y919500D01*
X305540Y920400D01*
X305015Y921150D01*
X304070Y921600D01*
X303125Y921450D01*
X302180Y920850D01*
G01X319695Y915600D02*
X322215D01*
G01X320850Y917550D02*
Y913650D01*
G01X327560Y912300D02*
X331340Y921600D01*
G01X336685Y915600D02*
X339415D01*
G01X355250Y921600D02*
X354410Y921300D01*
X353780Y920550D01*
X353360Y919650D01*
X353045Y918450D01*
X352940Y917100D01*
X353045Y915750D01*
X353360Y914550D01*
X353780Y913650D01*
X354410Y912900D01*
X355250Y912600D01*
X356090Y912900D01*
X356720Y913650D01*
X357140Y914550D01*
X357455Y915750D01*
X357560Y917100D01*
X357455Y918450D01*
X357140Y919650D01*
X356720Y920550D01*
X356090Y921300D01*
X355250Y921600D01*
G01X363850Y912300D02*
X363640Y912450D01*
Y912750D01*
X363850Y912900D01*
X364060Y912750D01*
Y912450D01*
X363850Y912300D01*
G01X373710Y912600D02*
Y921600D01*
X369825Y915150D01*
X375075D01*
G01X386920Y912600D02*
Y921600D01*
X389650Y914100D01*
X392380Y921600D01*
Y912600D01*
G01X396990Y921600D02*
X399510D01*
G01X398250D02*
Y912600D01*
G01X396990D02*
X399510D01*
G01X404750Y921600D02*
Y912600D01*
X408950D01*
G01X287710Y937600D02*
Y946600D01*
X283825Y940150D01*
X289075D01*
G01X295050Y937300D02*
X294840Y937450D01*
Y937750D01*
X295050Y937900D01*
X295260Y937750D01*
Y937450D01*
X295050Y937300D01*
G01X303650Y946600D02*
X302810Y946300D01*
X302180Y945550D01*
X301760Y944650D01*
X301445Y943450D01*
X301340Y942100D01*
X301445Y940750D01*
X301760Y939550D01*
X302180Y938650D01*
X302810Y937900D01*
X303650Y937600D01*
X304490Y937900D01*
X305120Y938650D01*
X305540Y939550D01*
X305855Y940750D01*
X305960Y942100D01*
X305855Y943450D01*
X305540Y944650D01*
X305120Y945550D01*
X304490Y946300D01*
X303650Y946600D01*
G01X319695Y940600D02*
X322215D01*
G01X320850Y942550D02*
Y938650D01*
G01X327560Y937300D02*
X331340Y946600D01*
G01X336685Y940600D02*
X339415D01*
G01X355250Y946600D02*
X354410Y946300D01*
X353780Y945550D01*
X353360Y944650D01*
X353045Y943450D01*
X352940Y942100D01*
X353045Y940750D01*
X353360Y939550D01*
X353780Y938650D01*
X354410Y937900D01*
X355250Y937600D01*
X356090Y937900D01*
X356720Y938650D01*
X357140Y939550D01*
X357455Y940750D01*
X357560Y942100D01*
X357455Y943450D01*
X357140Y944650D01*
X356720Y945550D01*
X356090Y946300D01*
X355250Y946600D01*
G01X363850Y937300D02*
X363640Y937450D01*
Y937750D01*
X363850Y937900D01*
X364060Y937750D01*
Y937450D01*
X363850Y937300D01*
G01X370140Y938950D02*
X370770Y938200D01*
X371505Y937750D01*
X372450Y937600D01*
X373395Y937900D01*
X374130Y938500D01*
X374655Y939550D01*
X374760Y940750D01*
X374550Y941950D01*
X374025Y942700D01*
X373290Y943300D01*
X372555Y943450D01*
X371820Y943300D01*
X370875Y942700D01*
X371190Y946600D01*
X374025D01*
G01X386920Y937600D02*
Y946600D01*
X389650Y939100D01*
X392380Y946600D01*
Y937600D01*
G01X396990Y946600D02*
X399510D01*
G01X398250D02*
Y937600D01*
G01X396990D02*
X399510D01*
G01X404750Y946600D02*
Y937600D01*
X408950D01*
G01X286450Y962600D02*
Y971600D01*
X285190Y969800D01*
G01Y962600D02*
X287710D01*
G01X295050Y962300D02*
X294840Y962450D01*
Y962750D01*
X295050Y962900D01*
X295260Y962750D01*
Y962450D01*
X295050Y962300D01*
G01X301340Y964400D02*
X301970Y963350D01*
X302810Y962750D01*
X303755Y962600D01*
X304595Y962750D01*
X305435Y963500D01*
X305960Y964400D01*
X306065Y965300D01*
X305855Y966350D01*
X305120Y967100D01*
X304385Y967400D01*
X303440D01*
G01X304385D02*
X305015Y967850D01*
X305540Y968600D01*
X305750Y969500D01*
X305540Y970400D01*
X305015Y971150D01*
X304070Y971600D01*
X303125Y971450D01*
X302180Y970850D01*
G01X319695Y965600D02*
X322215D01*
G01X320850Y967550D02*
Y963650D01*
G01X327560Y962300D02*
X331340Y971600D01*
G01X336685Y965600D02*
X339415D01*
G01X355250Y971600D02*
X354410Y971300D01*
X353780Y970550D01*
X353360Y969650D01*
X353045Y968450D01*
X352940Y967100D01*
X353045Y965750D01*
X353360Y964550D01*
X353780Y963650D01*
X354410Y962900D01*
X355250Y962600D01*
X356090Y962900D01*
X356720Y963650D01*
X357140Y964550D01*
X357455Y965750D01*
X357560Y967100D01*
X357455Y968450D01*
X357140Y969650D01*
X356720Y970550D01*
X356090Y971300D01*
X355250Y971600D01*
G01X363850Y962300D02*
X363640Y962450D01*
Y962750D01*
X363850Y962900D01*
X364060Y962750D01*
Y962450D01*
X363850Y962300D01*
G01X373710Y962600D02*
Y971600D01*
X369825Y965150D01*
X375075D01*
G01X386920Y962600D02*
Y971600D01*
X389650Y964100D01*
X392380Y971600D01*
Y962600D01*
G01X396990Y971600D02*
X399510D01*
G01X398250D02*
Y962600D01*
G01X396990D02*
X399510D01*
G01X404750Y971600D02*
Y962600D01*
X408950D01*
G01X284455Y995100D02*
X285085Y996000D01*
X285820Y996450D01*
X286660Y996600D01*
X287710Y996300D01*
X288445Y995550D01*
X288655Y994650D01*
X288550Y993750D01*
X288130Y993000D01*
X286030Y991500D01*
X285085Y990450D01*
X284455Y988950D01*
X284245Y987600D01*
X288655D01*
G01X295050Y987300D02*
X294840Y987450D01*
Y987750D01*
X295050Y987900D01*
X295260Y987750D01*
Y987450D01*
X295050Y987300D01*
G01X303440Y987600D02*
X303650Y989550D01*
X303965Y991200D01*
X304385Y992700D01*
X304910Y994350D01*
X305750Y996600D01*
X301550D01*
G01X319695Y990600D02*
X322215D01*
G01X320850Y992550D02*
Y988650D01*
G01X327560Y987300D02*
X331340Y996600D01*
G01X336685Y990600D02*
X339415D01*
G01X355250Y996600D02*
X354410Y996300D01*
X353780Y995550D01*
X353360Y994650D01*
X353045Y993450D01*
X352940Y992100D01*
X353045Y990750D01*
X353360Y989550D01*
X353780Y988650D01*
X354410Y987900D01*
X355250Y987600D01*
X356090Y987900D01*
X356720Y988650D01*
X357140Y989550D01*
X357455Y990750D01*
X357560Y992100D01*
X357455Y993450D01*
X357140Y994650D01*
X356720Y995550D01*
X356090Y996300D01*
X355250Y996600D01*
G01X363850Y987300D02*
X363640Y987450D01*
Y987750D01*
X363850Y987900D01*
X364060Y987750D01*
Y987450D01*
X363850Y987300D01*
G01X370140Y988950D02*
X370770Y988200D01*
X371505Y987750D01*
X372450Y987600D01*
X373395Y987900D01*
X374130Y988500D01*
X374655Y989550D01*
X374760Y990750D01*
X374550Y991950D01*
X374025Y992700D01*
X373290Y993300D01*
X372555Y993450D01*
X371820Y993300D01*
X370875Y992700D01*
X371190Y996600D01*
X374025D01*
G01X386920Y987600D02*
Y996600D01*
X389650Y989100D01*
X392380Y996600D01*
Y987600D01*
G01X396990Y996600D02*
X399510D01*
G01X398250D02*
Y987600D01*
G01X396990D02*
X399510D01*
G01X404750Y996600D02*
Y987600D01*
X408950D01*
G01X286450Y1012600D02*
Y1021600D01*
X285190Y1019800D01*
G01Y1012600D02*
X287710D01*
G01X295050Y1012300D02*
X294840Y1012450D01*
Y1012750D01*
X295050Y1012900D01*
X295260Y1012750D01*
Y1012450D01*
X295050Y1012300D01*
G01X301865Y1013650D02*
X302600Y1012900D01*
X303440Y1012600D01*
X304280Y1012900D01*
X305015Y1013800D01*
X305540Y1015150D01*
X305750Y1016500D01*
Y1018150D01*
X305540Y1019500D01*
X305015Y1020700D01*
X304385Y1021300D01*
X303650Y1021600D01*
X302810Y1021300D01*
X302180Y1020700D01*
X301760Y1019800D01*
X301550Y1018600D01*
X301760Y1017550D01*
X302285Y1016500D01*
X302915Y1015900D01*
X303650Y1015750D01*
X304490Y1016050D01*
X305120Y1016800D01*
X305750Y1018150D01*
G01X319695Y1015600D02*
X322215D01*
G01X320850Y1017550D02*
Y1013650D01*
G01X327560Y1012300D02*
X331340Y1021600D01*
G01X336685Y1015600D02*
X339415D01*
G01X355250Y1021600D02*
X354410Y1021300D01*
X353780Y1020550D01*
X353360Y1019650D01*
X353045Y1018450D01*
X352940Y1017100D01*
X353045Y1015750D01*
X353360Y1014550D01*
X353780Y1013650D01*
X354410Y1012900D01*
X355250Y1012600D01*
X356090Y1012900D01*
X356720Y1013650D01*
X357140Y1014550D01*
X357455Y1015750D01*
X357560Y1017100D01*
X357455Y1018450D01*
X357140Y1019650D01*
X356720Y1020550D01*
X356090Y1021300D01*
X355250Y1021600D01*
G01X363850Y1012300D02*
X363640Y1012450D01*
Y1012750D01*
X363850Y1012900D01*
X364060Y1012750D01*
Y1012450D01*
X363850Y1012300D01*
G01X370140Y1014400D02*
X370770Y1013350D01*
X371610Y1012750D01*
X372555Y1012600D01*
X373395Y1012750D01*
X374235Y1013500D01*
X374760Y1014400D01*
X374865Y1015300D01*
X374655Y1016350D01*
X373920Y1017100D01*
X373185Y1017400D01*
X372240D01*
G01X373185D02*
X373815Y1017850D01*
X374340Y1018600D01*
X374550Y1019500D01*
X374340Y1020400D01*
X373815Y1021150D01*
X372870Y1021600D01*
X371925Y1021450D01*
X370980Y1020850D01*
G01X386920Y1012600D02*
Y1021600D01*
X389650Y1014100D01*
X392380Y1021600D01*
Y1012600D01*
G01X396990Y1021600D02*
X399510D01*
G01X398250D02*
Y1012600D01*
G01X396990D02*
X399510D01*
G01X404750Y1021600D02*
Y1012600D01*
X408950D01*
G01X286950Y1042500D02*
X286110Y1042200D01*
X285480Y1041450D01*
X285060Y1040550D01*
X284745Y1039350D01*
X284640Y1038000D01*
X284745Y1036650D01*
X285060Y1035450D01*
X285480Y1034550D01*
X286110Y1033800D01*
X286950Y1033500D01*
X287790Y1033800D01*
X288420Y1034550D01*
X288840Y1035450D01*
X289155Y1036650D01*
X289260Y1038000D01*
X289155Y1039350D01*
X288840Y1040550D01*
X288420Y1041450D01*
X287790Y1042200D01*
X286950Y1042500D01*
G01X295550Y1033200D02*
X295340Y1033350D01*
Y1033650D01*
X295550Y1033800D01*
X295760Y1033650D01*
Y1033350D01*
X295550Y1033200D01*
G01X301840Y1034850D02*
X302470Y1034100D01*
X303205Y1033650D01*
X304150Y1033500D01*
X305095Y1033800D01*
X305830Y1034400D01*
X306355Y1035450D01*
X306460Y1036650D01*
X306250Y1037850D01*
X305725Y1038600D01*
X304990Y1039200D01*
X304255Y1039350D01*
X303520Y1039200D01*
X302575Y1038600D01*
X302890Y1042500D01*
X305725D01*
G01X320195Y1036500D02*
X322715D01*
G01X321350Y1038450D02*
Y1034550D01*
G01X328060Y1033200D02*
X331840Y1042500D01*
G01X337185Y1036500D02*
X339915D01*
G01X355750Y1042500D02*
X354910Y1042200D01*
X354280Y1041450D01*
X353860Y1040550D01*
X353545Y1039350D01*
X353440Y1038000D01*
X353545Y1036650D01*
X353860Y1035450D01*
X354280Y1034550D01*
X354910Y1033800D01*
X355750Y1033500D01*
X356590Y1033800D01*
X357220Y1034550D01*
X357640Y1035450D01*
X357955Y1036650D01*
X358060Y1038000D01*
X357955Y1039350D01*
X357640Y1040550D01*
X357220Y1041450D01*
X356590Y1042200D01*
X355750Y1042500D01*
G01X364350Y1033200D02*
X364140Y1033350D01*
Y1033650D01*
X364350Y1033800D01*
X364560Y1033650D01*
Y1033350D01*
X364350Y1033200D01*
G01X372950Y1033500D02*
Y1042500D01*
X371690Y1040700D01*
G01Y1033500D02*
X374210D01*
G01X387420D02*
Y1042500D01*
X390150Y1035000D01*
X392880Y1042500D01*
Y1033500D01*
G01X397490Y1042500D02*
X400010D01*
G01X398750D02*
Y1033500D01*
G01X397490D02*
X400010D01*
G01X405250Y1042500D02*
Y1033500D01*
X409450D01*
G01X443145Y546300D02*
X443985Y545550D01*
X444930Y545100D01*
X445770D01*
X446610Y545550D01*
X447240Y546300D01*
X447555Y547350D01*
X447345Y548400D01*
X446820Y549300D01*
X445875Y549900D01*
X444615Y550200D01*
X443880Y550800D01*
X443565Y551850D01*
X443775Y552900D01*
X444300Y553650D01*
X445035Y554100D01*
X445770D01*
X446505Y553800D01*
X447135Y553050D01*
G01X453950Y545100D02*
X453110Y545250D01*
X452375Y545850D01*
X451745Y546750D01*
X451325Y547800D01*
X451115Y549000D01*
Y550200D01*
X451325Y551400D01*
X451745Y552450D01*
X452375Y553350D01*
X453110Y553950D01*
X453950Y554100D01*
X454790Y553950D01*
X455525Y553350D01*
X456155Y552450D01*
X456575Y551400D01*
X456785Y550200D01*
Y549000D01*
X456575Y547800D01*
X456155Y546750D01*
X455525Y545850D01*
X454790Y545250D01*
X453950Y545100D01*
G01X460450Y554100D02*
Y545100D01*
X464650D01*
G01X468840D02*
Y554100D01*
X470940D01*
X471780Y553650D01*
X472410Y553050D01*
X472935Y552150D01*
X473355Y551100D01*
X473460Y549600D01*
X473355Y548100D01*
X472935Y547050D01*
X472410Y546150D01*
X471780Y545550D01*
X470940Y545100D01*
X468840D01*
G01X481850D02*
X477650D01*
Y554100D01*
X481850D01*
G01X480170Y549750D02*
X477650D01*
G01X486250Y545100D02*
Y554100D01*
X488875D01*
X489715Y553650D01*
X490240Y553050D01*
X490450Y551850D01*
X490240Y550650D01*
X489610Y549900D01*
X488875Y549450D01*
X486250D01*
G01X488875D02*
X490450Y545100D01*
G01X494220D02*
Y554100D01*
X496950Y546600D01*
X499680Y554100D01*
Y545100D01*
G01X502925D02*
X505550Y554100D01*
X508175Y545100D01*
G01X507230Y548250D02*
X503870D01*
G01X511945Y546300D02*
X512785Y545550D01*
X513730Y545100D01*
X514570D01*
X515410Y545550D01*
X516040Y546300D01*
X516355Y547350D01*
X516145Y548400D01*
X515620Y549300D01*
X514675Y549900D01*
X513415Y550200D01*
X512680Y550800D01*
X512365Y551850D01*
X512575Y552900D01*
X513100Y553650D01*
X513835Y554100D01*
X514570D01*
X515305Y553800D01*
X515935Y553050D01*
G01X520440Y545100D02*
Y554100D01*
G01X524430D02*
X520440Y548550D01*
G01X525060Y545100D02*
X522225Y551100D01*
G01X538690Y554100D02*
X541210D01*
G01X539950D02*
Y545100D01*
G01X538690D02*
X541210D01*
G01X546135D02*
Y554100D01*
X550965Y545100D01*
Y554100D01*
G01X559460Y553350D02*
X558830Y553800D01*
X558095Y554100D01*
X557255D01*
X556310Y553650D01*
X555575Y552900D01*
X555050Y552000D01*
X554630Y550500D01*
X554525Y549150D01*
X554735Y547800D01*
X555050Y546900D01*
X555680Y546000D01*
X556415Y545400D01*
X557150Y545100D01*
X557885D01*
X558620Y545400D01*
X559250Y545850D01*
X559775Y546450D01*
G01X563650Y554100D02*
Y545100D01*
X567850D01*
G01X572040Y554100D02*
Y547650D01*
X572460Y546300D01*
X573300Y545400D01*
X574350Y545100D01*
X575400Y545400D01*
X576240Y546300D01*
X576660Y547650D01*
Y554100D01*
G01X580640Y545100D02*
Y554100D01*
X582740D01*
X583580Y553650D01*
X584210Y553050D01*
X584735Y552150D01*
X585155Y551100D01*
X585260Y549600D01*
X585155Y548100D01*
X584735Y547050D01*
X584210Y546150D01*
X583580Y545550D01*
X582740Y545100D01*
X580640D01*
G01X593650D02*
X589450D01*
Y554100D01*
X593650D01*
G01X591970Y549750D02*
X589450D01*
G01X597840Y545100D02*
Y554100D01*
X599940D01*
X600780Y553650D01*
X601410Y553050D01*
X601935Y552150D01*
X602355Y551100D01*
X602460Y549600D01*
X602355Y548100D01*
X601935Y547050D01*
X601410Y546150D01*
X600780Y545550D01*
X599940Y545100D01*
X597840D01*
G01X616090Y554100D02*
X618610D01*
G01X617350D02*
Y545100D01*
G01X616090D02*
X618610D01*
G01X623535D02*
Y554100D01*
X628365Y545100D01*
Y554100D01*
G01X643150Y545100D02*
X642310Y545250D01*
X641575Y545850D01*
X640945Y546750D01*
X640525Y547800D01*
X640315Y549000D01*
Y550200D01*
X640525Y551400D01*
X640945Y552450D01*
X641575Y553350D01*
X642310Y553950D01*
X643150Y554100D01*
X643990Y553950D01*
X644725Y553350D01*
X645355Y552450D01*
X645775Y551400D01*
X645985Y550200D01*
Y549000D01*
X645775Y547800D01*
X645355Y546750D01*
X644725Y545850D01*
X643990Y545250D01*
X643150Y545100D01*
G01X649125Y554100D02*
X651750Y545100D01*
X654375Y554100D01*
G01X662450Y545100D02*
X658250D01*
Y554100D01*
X662450D01*
G01X660770Y549750D02*
X658250D01*
G01X666850Y545100D02*
Y554100D01*
X669475D01*
X670315Y553650D01*
X670840Y553050D01*
X671050Y551850D01*
X670840Y550650D01*
X670210Y549900D01*
X669475Y549450D01*
X666850D01*
G01X669475D02*
X671050Y545100D01*
G01X674925D02*
X677550Y554100D01*
X680175Y545100D01*
G01X679230Y548250D02*
X675870D01*
G01X684050Y554100D02*
Y545100D01*
X688250D01*
G01X692650Y554100D02*
Y545100D01*
X696850D01*
G01X712790Y549900D02*
X713210Y550350D01*
X713525Y551100D01*
X713735Y552150D01*
X713525Y553050D01*
X713105Y553650D01*
X712370Y554100D01*
X709535D01*
Y545100D01*
X713000D01*
X713735Y545700D01*
X714155Y546600D01*
X714365Y547650D01*
X714155Y548700D01*
X713525Y549600D01*
X712790Y549900D01*
X709535D01*
G01X720550Y545100D02*
X719710Y545250D01*
X718975Y545850D01*
X718345Y546750D01*
X717925Y547800D01*
X717715Y549000D01*
Y550200D01*
X717925Y551400D01*
X718345Y552450D01*
X718975Y553350D01*
X719710Y553950D01*
X720550Y554100D01*
X721390Y553950D01*
X722125Y553350D01*
X722755Y552450D01*
X723175Y551400D01*
X723385Y550200D01*
Y549000D01*
X723175Y547800D01*
X722755Y546750D01*
X722125Y545850D01*
X721390Y545250D01*
X720550Y545100D01*
G01X726525D02*
X729150Y554100D01*
X731775Y545100D01*
G01X730830Y548250D02*
X727470D01*
G01X735650Y545100D02*
Y554100D01*
X738275D01*
X739115Y553650D01*
X739640Y553050D01*
X739850Y551850D01*
X739640Y550650D01*
X739010Y549900D01*
X738275Y549450D01*
X735650D01*
G01X738275D02*
X739850Y545100D01*
G01X744040D02*
Y554100D01*
X746140D01*
X746980Y553650D01*
X747610Y553050D01*
X748135Y552150D01*
X748555Y551100D01*
X748660Y549600D01*
X748555Y548100D01*
X748135Y547050D01*
X747610Y546150D01*
X746980Y545550D01*
X746140Y545100D01*
X744040D01*
G01X763550Y554100D02*
Y545100D01*
G01X761135Y554100D02*
X765965D01*
G01X769945Y545100D02*
Y554100D01*
G01X774355D02*
Y545100D01*
G01Y549600D02*
X769945D01*
G01X779490Y554100D02*
X782010D01*
G01X780750D02*
Y545100D01*
G01X779490D02*
X782010D01*
G01X791660Y553350D02*
X791030Y553800D01*
X790295Y554100D01*
X789455D01*
X788510Y553650D01*
X787775Y552900D01*
X787250Y552000D01*
X786830Y550500D01*
X786725Y549150D01*
X786935Y547800D01*
X787250Y546900D01*
X787880Y546000D01*
X788615Y545400D01*
X789350Y545100D01*
X790085D01*
X790820Y545400D01*
X791450Y545850D01*
X791975Y546450D01*
G01X795640Y545100D02*
Y554100D01*
G01X799630D02*
X795640Y548550D01*
G01X800260Y545100D02*
X797425Y551100D01*
G01X804135Y545100D02*
Y554100D01*
X808965Y545100D01*
Y554100D01*
G01X817250Y545100D02*
X813050D01*
Y554100D01*
X817250D01*
G01X815570Y549750D02*
X813050D01*
G01X821545Y546300D02*
X822385Y545550D01*
X823330Y545100D01*
X824170D01*
X825010Y545550D01*
X825640Y546300D01*
X825955Y547350D01*
X825745Y548400D01*
X825220Y549300D01*
X824275Y549900D01*
X823015Y550200D01*
X822280Y550800D01*
X821965Y551850D01*
X822175Y552900D01*
X822700Y553650D01*
X823435Y554100D01*
X824170D01*
X824905Y553800D01*
X825535Y553050D01*
G01X830145Y546300D02*
X830985Y545550D01*
X831930Y545100D01*
X832770D01*
X833610Y545550D01*
X834240Y546300D01*
X834555Y547350D01*
X834345Y548400D01*
X833820Y549300D01*
X832875Y549900D01*
X831615Y550200D01*
X830880Y550800D01*
X830565Y551850D01*
X830775Y552900D01*
X831300Y553650D01*
X832035Y554100D01*
X832770D01*
X833505Y553800D01*
X834135Y553050D01*
G01X445350Y571600D02*
Y562600D01*
G01X442935Y571600D02*
X447765D01*
G01X451745Y562600D02*
Y571600D01*
G01X456155D02*
Y562600D01*
G01Y567100D02*
X451745D01*
G01X464650Y562600D02*
X460450D01*
Y571600D01*
X464650D01*
G01X462970Y567250D02*
X460450D01*
G01X477545Y563800D02*
X478385Y563050D01*
X479330Y562600D01*
X480170D01*
X481010Y563050D01*
X481640Y563800D01*
X481955Y564850D01*
X481745Y565900D01*
X481220Y566800D01*
X480275Y567400D01*
X479015Y567700D01*
X478280Y568300D01*
X477965Y569350D01*
X478175Y570400D01*
X478700Y571150D01*
X479435Y571600D01*
X480170D01*
X480905Y571300D01*
X481535Y570550D01*
G01X486040Y571600D02*
Y565150D01*
X486460Y563800D01*
X487300Y562900D01*
X488350Y562600D01*
X489400Y562900D01*
X490240Y563800D01*
X490660Y565150D01*
Y571600D01*
G01X494220Y562600D02*
Y571600D01*
X496950Y564100D01*
X499680Y571600D01*
Y562600D01*
G01X514150D02*
X513310Y562750D01*
X512575Y563350D01*
X511945Y564250D01*
X511525Y565300D01*
X511315Y566500D01*
Y567700D01*
X511525Y568900D01*
X511945Y569950D01*
X512575Y570850D01*
X513310Y571450D01*
X514150Y571600D01*
X514990Y571450D01*
X515725Y570850D01*
X516355Y569950D01*
X516775Y568900D01*
X516985Y567700D01*
Y566500D01*
X516775Y565300D01*
X516355Y564250D01*
X515725Y563350D01*
X514990Y562750D01*
X514150Y562600D01*
G01X520755D02*
Y571600D01*
X524745D01*
G01X523275Y567250D02*
X520755D01*
G01X538690Y571600D02*
X541210D01*
G01X539950D02*
Y562600D01*
G01X538690D02*
X541210D01*
G01X546135D02*
Y571600D01*
X550965Y562600D01*
Y571600D01*
G01X554840Y562600D02*
Y571600D01*
X556940D01*
X557780Y571150D01*
X558410Y570550D01*
X558935Y569650D01*
X559355Y568600D01*
X559460Y567100D01*
X559355Y565600D01*
X558935Y564550D01*
X558410Y563650D01*
X557780Y563050D01*
X556940Y562600D01*
X554840D01*
G01X564490Y571600D02*
X567010D01*
G01X565750D02*
Y562600D01*
G01X564490D02*
X567010D01*
G01X571725Y571600D02*
X574350Y562600D01*
X576975Y571600D01*
G01X581690D02*
X584210D01*
G01X582950D02*
Y562600D01*
G01X581690D02*
X584210D01*
G01X589240D02*
Y571600D01*
X591340D01*
X592180Y571150D01*
X592810Y570550D01*
X593335Y569650D01*
X593755Y568600D01*
X593860Y567100D01*
X593755Y565600D01*
X593335Y564550D01*
X592810Y563650D01*
X592180Y563050D01*
X591340Y562600D01*
X589240D01*
G01X597840Y571600D02*
Y565150D01*
X598260Y563800D01*
X599100Y562900D01*
X600150Y562600D01*
X601200Y562900D01*
X602040Y563800D01*
X602460Y565150D01*
Y571600D01*
G01X606125Y562600D02*
X608750Y571600D01*
X611375Y562600D01*
G01X610430Y565750D02*
X607070D01*
G01X615250Y571600D02*
Y562600D01*
X619450D01*
G01X632450Y571600D02*
Y562600D01*
X636650D01*
G01X640525D02*
X643150Y571600D01*
X645775Y562600D01*
G01X644830Y565750D02*
X641470D01*
G01X651750Y562600D02*
Y566650D01*
X649650Y571600D01*
G01X653850D02*
X651750Y566650D01*
G01X662450Y562600D02*
X658250D01*
Y571600D01*
X662450D01*
G01X660770Y567250D02*
X658250D01*
G01X666850Y562600D02*
Y571600D01*
X669475D01*
X670315Y571150D01*
X670840Y570550D01*
X671050Y569350D01*
X670840Y568150D01*
X670210Y567400D01*
X669475Y566950D01*
X666850D01*
G01X669475D02*
X671050Y562600D01*
G01X686150Y571600D02*
Y562600D01*
G01X683735Y571600D02*
X688565D01*
G01X694750Y562600D02*
X693910Y562750D01*
X693175Y563350D01*
X692545Y564250D01*
X692125Y565300D01*
X691915Y566500D01*
Y567700D01*
X692125Y568900D01*
X692545Y569950D01*
X693175Y570850D01*
X693910Y571450D01*
X694750Y571600D01*
X695590Y571450D01*
X696325Y570850D01*
X696955Y569950D01*
X697375Y568900D01*
X697585Y567700D01*
Y566500D01*
X697375Y565300D01*
X696955Y564250D01*
X696325Y563350D01*
X695590Y562750D01*
X694750Y562600D01*
G01X701250Y571600D02*
Y562600D01*
X705450D01*
G01X714050D02*
X709850D01*
Y571600D01*
X714050D01*
G01X712370Y567250D02*
X709850D01*
G01X718450Y562600D02*
Y571600D01*
X721075D01*
X721915Y571150D01*
X722440Y570550D01*
X722650Y569350D01*
X722440Y568150D01*
X721810Y567400D01*
X721075Y566950D01*
X718450D01*
G01X721075D02*
X722650Y562600D01*
G01X726525D02*
X729150Y571600D01*
X731775Y562600D01*
G01X730830Y565750D02*
X727470D01*
G01X735335Y562600D02*
Y571600D01*
X740165Y562600D01*
Y571600D01*
G01X748660Y570850D02*
X748030Y571300D01*
X747295Y571600D01*
X746455D01*
X745510Y571150D01*
X744775Y570400D01*
X744250Y569500D01*
X743830Y568000D01*
X743725Y566650D01*
X743935Y565300D01*
X744250Y564400D01*
X744880Y563500D01*
X745615Y562900D01*
X746350Y562600D01*
X747085D01*
X747820Y562900D01*
X748450Y563350D01*
X748975Y563950D01*
G01X757050Y562600D02*
X752850D01*
Y571600D01*
X757050D01*
G01X755370Y567250D02*
X752850D01*
G01X761345Y563800D02*
X762185Y563050D01*
X763130Y562600D01*
X763970D01*
X764810Y563050D01*
X765440Y563800D01*
X765755Y564850D01*
X765545Y565900D01*
X765020Y566800D01*
X764075Y567400D01*
X762815Y567700D01*
X762080Y568300D01*
X761765Y569350D01*
X761975Y570400D01*
X762500Y571150D01*
X763235Y571600D01*
X763970D01*
X764705Y571300D01*
X765335Y570550D01*
G01X772150Y562300D02*
X771940Y562450D01*
Y562750D01*
X772150Y562900D01*
X772360Y562750D01*
Y562450D01*
X772150Y562300D01*
G01X445350Y580100D02*
X444510Y580250D01*
X443775Y580850D01*
X443145Y581750D01*
X442725Y582800D01*
X442515Y584000D01*
Y585200D01*
X442725Y586400D01*
X443145Y587450D01*
X443775Y588350D01*
X444510Y588950D01*
X445350Y589100D01*
X446190Y588950D01*
X446925Y588350D01*
X447555Y587450D01*
X447975Y586400D01*
X448185Y585200D01*
Y584000D01*
X447975Y582800D01*
X447555Y581750D01*
X446925Y580850D01*
X446190Y580250D01*
X445350Y580100D01*
G01X451325Y589100D02*
X453950Y580100D01*
X456575Y589100D01*
G01X464650Y580100D02*
X460450D01*
Y589100D01*
X464650D01*
G01X462970Y584750D02*
X460450D01*
G01X469050Y580100D02*
Y589100D01*
X471675D01*
X472515Y588650D01*
X473040Y588050D01*
X473250Y586850D01*
X473040Y585650D01*
X472410Y584900D01*
X471675Y584450D01*
X469050D01*
G01X471675D02*
X473250Y580100D01*
G01X477125D02*
X479750Y589100D01*
X482375Y580100D01*
G01X481430Y583250D02*
X478070D01*
G01X486250Y589100D02*
Y580100D01*
X490450D01*
G01X494850Y589100D02*
Y580100D01*
X499050D01*
G01X514150Y589100D02*
Y580100D01*
G01X511735Y589100D02*
X516565D01*
G01X520545Y580100D02*
Y589100D01*
G01X524955D02*
Y580100D01*
G01Y584600D02*
X520545D01*
G01X530090Y589100D02*
X532610D01*
G01X531350D02*
Y580100D01*
G01X530090D02*
X532610D01*
G01X542260Y588350D02*
X541630Y588800D01*
X540895Y589100D01*
X540055D01*
X539110Y588650D01*
X538375Y587900D01*
X537850Y587000D01*
X537430Y585500D01*
X537325Y584150D01*
X537535Y582800D01*
X537850Y581900D01*
X538480Y581000D01*
X539215Y580400D01*
X539950Y580100D01*
X540685D01*
X541420Y580400D01*
X542050Y580850D01*
X542575Y581450D01*
G01X546240Y580100D02*
Y589100D01*
G01X550230D02*
X546240Y583550D01*
G01X550860Y580100D02*
X548025Y586100D01*
G01X554735Y580100D02*
Y589100D01*
X559565Y580100D01*
Y589100D01*
G01X567850Y580100D02*
X563650D01*
Y589100D01*
X567850D01*
G01X566170Y584750D02*
X563650D01*
G01X572145Y581300D02*
X572985Y580550D01*
X573930Y580100D01*
X574770D01*
X575610Y580550D01*
X576240Y581300D01*
X576555Y582350D01*
X576345Y583400D01*
X575820Y584300D01*
X574875Y584900D01*
X573615Y585200D01*
X572880Y585800D01*
X572565Y586850D01*
X572775Y587900D01*
X573300Y588650D01*
X574035Y589100D01*
X574770D01*
X575505Y588800D01*
X576135Y588050D01*
G01X580745Y581300D02*
X581585Y580550D01*
X582530Y580100D01*
X583370D01*
X584210Y580550D01*
X584840Y581300D01*
X585155Y582350D01*
X584945Y583400D01*
X584420Y584300D01*
X583475Y584900D01*
X582215Y585200D01*
X581480Y585800D01*
X581165Y586850D01*
X581375Y587900D01*
X581900Y588650D01*
X582635Y589100D01*
X583370D01*
X584105Y588800D01*
X584735Y588050D01*
G01X600150Y589100D02*
Y580100D01*
G01X597735Y589100D02*
X602565D01*
G01X608750Y580100D02*
X607910Y580250D01*
X607175Y580850D01*
X606545Y581750D01*
X606125Y582800D01*
X605915Y584000D01*
Y585200D01*
X606125Y586400D01*
X606545Y587450D01*
X607175Y588350D01*
X607910Y588950D01*
X608750Y589100D01*
X609590Y588950D01*
X610325Y588350D01*
X610955Y587450D01*
X611375Y586400D01*
X611585Y585200D01*
Y584000D01*
X611375Y582800D01*
X610955Y581750D01*
X610325Y580850D01*
X609590Y580250D01*
X608750Y580100D01*
G01X615250Y589100D02*
Y580100D01*
X619450D01*
G01X628050D02*
X623850D01*
Y589100D01*
X628050D01*
G01X626370Y584750D02*
X623850D01*
G01X632450Y580100D02*
Y589100D01*
X635075D01*
X635915Y588650D01*
X636440Y588050D01*
X636650Y586850D01*
X636440Y585650D01*
X635810Y584900D01*
X635075Y584450D01*
X632450D01*
G01X635075D02*
X636650Y580100D01*
G01X640525D02*
X643150Y589100D01*
X645775Y580100D01*
G01X644830Y583250D02*
X641470D01*
G01X649335Y580100D02*
Y589100D01*
X654165Y580100D01*
Y589100D01*
G01X662660Y588350D02*
X662030Y588800D01*
X661295Y589100D01*
X660455D01*
X659510Y588650D01*
X658775Y587900D01*
X658250Y587000D01*
X657830Y585500D01*
X657725Y584150D01*
X657935Y582800D01*
X658250Y581900D01*
X658880Y581000D01*
X659615Y580400D01*
X660350Y580100D01*
X661085D01*
X661820Y580400D01*
X662450Y580850D01*
X662975Y581450D01*
G01X671050Y580100D02*
X666850D01*
Y589100D01*
X671050D01*
G01X669370Y584750D02*
X666850D01*
G01X683420Y580100D02*
Y589100D01*
X686150Y581600D01*
X688880Y589100D01*
Y580100D01*
G01X692125D02*
X694750Y589100D01*
X697375Y580100D01*
G01X696430Y583250D02*
X693070D01*
G01X703350Y580100D02*
Y584150D01*
X701250Y589100D01*
G01X705450D02*
X703350Y584150D01*
G01X721390Y584900D02*
X721810Y585350D01*
X722125Y586100D01*
X722335Y587150D01*
X722125Y588050D01*
X721705Y588650D01*
X720970Y589100D01*
X718135D01*
Y580100D01*
X721600D01*
X722335Y580700D01*
X722755Y581600D01*
X722965Y582650D01*
X722755Y583700D01*
X722125Y584600D01*
X721390Y584900D01*
X718135D01*
G01X731250Y580100D02*
X727050D01*
Y589100D01*
X731250D01*
G01X729570Y584750D02*
X727050D01*
G01X744250Y589100D02*
Y580100D01*
X748450D01*
G01X757050D02*
X752850D01*
Y589100D01*
X757050D01*
G01X755370Y584750D02*
X752850D01*
G01X761345Y581300D02*
X762185Y580550D01*
X763130Y580100D01*
X763970D01*
X764810Y580550D01*
X765440Y581300D01*
X765755Y582350D01*
X765545Y583400D01*
X765020Y584300D01*
X764075Y584900D01*
X762815Y585200D01*
X762080Y585800D01*
X761765Y586850D01*
X761975Y587900D01*
X762500Y588650D01*
X763235Y589100D01*
X763970D01*
X764705Y588800D01*
X765335Y588050D01*
G01X769945Y581300D02*
X770785Y580550D01*
X771730Y580100D01*
X772570D01*
X773410Y580550D01*
X774040Y581300D01*
X774355Y582350D01*
X774145Y583400D01*
X773620Y584300D01*
X772675Y584900D01*
X771415Y585200D01*
X770680Y585800D01*
X770365Y586850D01*
X770575Y587900D01*
X771100Y588650D01*
X771835Y589100D01*
X772570D01*
X773305Y588800D01*
X773935Y588050D01*
G01X789350Y589100D02*
Y580100D01*
G01X786935Y589100D02*
X791765D01*
G01X795745Y580100D02*
Y589100D01*
G01X800155D02*
Y580100D01*
G01Y584600D02*
X795745D01*
G01X803925Y580100D02*
X806550Y589100D01*
X809175Y580100D01*
G01X808230Y583250D02*
X804870D01*
G01X812735Y580100D02*
Y589100D01*
X817565Y580100D01*
Y589100D01*
G01X425840Y597300D02*
X430460Y603900D01*
G01X428150Y605100D02*
Y596100D01*
G01X430460Y597300D02*
X425840Y603900D01*
G01X425000Y600600D02*
X431300D01*
G01X442935Y597600D02*
Y606600D01*
X447765Y597600D01*
Y606600D01*
G01X453950Y597600D02*
X453110Y597750D01*
X452375Y598350D01*
X451745Y599250D01*
X451325Y600300D01*
X451115Y601500D01*
Y602700D01*
X451325Y603900D01*
X451745Y604950D01*
X452375Y605850D01*
X453110Y606450D01*
X453950Y606600D01*
X454790Y606450D01*
X455525Y605850D01*
X456155Y604950D01*
X456575Y603900D01*
X456785Y602700D01*
Y601500D01*
X456575Y600300D01*
X456155Y599250D01*
X455525Y598350D01*
X454790Y597750D01*
X453950Y597600D01*
G01X462550Y606600D02*
Y597600D01*
G01X460135Y606600D02*
X464965D01*
G01X473250Y597600D02*
X469050D01*
Y606600D01*
X473250D01*
G01X471570Y602250D02*
X469050D01*
G01X477545Y598800D02*
X478385Y598050D01*
X479330Y597600D01*
X480170D01*
X481010Y598050D01*
X481640Y598800D01*
X481955Y599850D01*
X481745Y600900D01*
X481220Y601800D01*
X480275Y602400D01*
X479015Y602700D01*
X478280Y603300D01*
X477965Y604350D01*
X478175Y605400D01*
X478700Y606150D01*
X479435Y606600D01*
X480170D01*
X480905Y606300D01*
X481535Y605550D01*
G01X488350Y597300D02*
X488140Y597450D01*
Y597750D01*
X488350Y597900D01*
X488560Y597750D01*
Y597450D01*
X488350Y597300D01*
G01Y601350D02*
X488140Y601500D01*
Y601800D01*
X488350Y601950D01*
X488560Y601800D01*
Y601500D01*
X488350Y601350D01*
G01X671445Y637200D02*
X672285Y636450D01*
X673230Y636000D01*
X674070D01*
X674910Y636450D01*
X675540Y637200D01*
X675855Y638250D01*
X675645Y639300D01*
X675120Y640200D01*
X674175Y640800D01*
X672915Y641100D01*
X672180Y641700D01*
X671865Y642750D01*
X672075Y643800D01*
X672600Y644550D01*
X673335Y645000D01*
X674070D01*
X674805Y644700D01*
X675435Y643950D01*
G01X682250Y636000D02*
X681410Y636150D01*
X680675Y636750D01*
X680045Y637650D01*
X679625Y638700D01*
X679415Y639900D01*
Y641100D01*
X679625Y642300D01*
X680045Y643350D01*
X680675Y644250D01*
X681410Y644850D01*
X682250Y645000D01*
X683090Y644850D01*
X683825Y644250D01*
X684455Y643350D01*
X684875Y642300D01*
X685085Y641100D01*
Y639900D01*
X684875Y638700D01*
X684455Y637650D01*
X683825Y636750D01*
X683090Y636150D01*
X682250Y636000D01*
G01X688750Y645000D02*
Y636000D01*
X692950D01*
G01X697140D02*
Y645000D01*
X699240D01*
X700080Y644550D01*
X700710Y643950D01*
X701235Y643050D01*
X701655Y642000D01*
X701760Y640500D01*
X701655Y639000D01*
X701235Y637950D01*
X700710Y637050D01*
X700080Y636450D01*
X699240Y636000D01*
X697140D01*
G01X710150D02*
X705950D01*
Y645000D01*
X710150D01*
G01X708470Y640650D02*
X705950D01*
G01X714550Y636000D02*
Y645000D01*
X717175D01*
X718015Y644550D01*
X718540Y643950D01*
X718750Y642750D01*
X718540Y641550D01*
X717910Y640800D01*
X717175Y640350D01*
X714550D01*
G01X717175D02*
X718750Y636000D01*
G01X722520D02*
Y645000D01*
X725250Y637500D01*
X727980Y645000D01*
Y636000D01*
G01X731225D02*
X733850Y645000D01*
X736475Y636000D01*
G01X735530Y639150D02*
X732170D01*
G01X740245Y637200D02*
X741085Y636450D01*
X742030Y636000D01*
X742870D01*
X743710Y636450D01*
X744340Y637200D01*
X744655Y638250D01*
X744445Y639300D01*
X743920Y640200D01*
X742975Y640800D01*
X741715Y641100D01*
X740980Y641700D01*
X740665Y642750D01*
X740875Y643800D01*
X741400Y644550D01*
X742135Y645000D01*
X742870D01*
X743605Y644700D01*
X744235Y643950D01*
G01X748740Y636000D02*
Y645000D01*
G01X752730D02*
X748740Y639450D01*
G01X753360Y636000D02*
X750525Y642000D01*
G01X671550Y664600D02*
Y655600D01*
X675750D01*
G01X682250D02*
X682985Y655750D01*
X683825Y656200D01*
X684350Y656950D01*
X684560Y658000D01*
X684350Y659050D01*
X683720Y659950D01*
X682775Y660400D01*
X681725D01*
X681095Y660700D01*
X680570Y661450D01*
X680360Y662500D01*
X680675Y663550D01*
X681410Y664300D01*
X682250Y664600D01*
X683090Y664300D01*
X683825Y663550D01*
X684140Y662500D01*
X683930Y661450D01*
X683405Y660700D01*
X682775Y660400D01*
X681725D01*
X680780Y659950D01*
X680150Y659050D01*
X679940Y658000D01*
X680150Y656950D01*
X680675Y656200D01*
X681515Y655750D01*
X682250Y655600D01*
G01X697245Y656800D02*
X698085Y656050D01*
X699030Y655600D01*
X699870D01*
X700710Y656050D01*
X701340Y656800D01*
X701655Y657850D01*
X701445Y658900D01*
X700920Y659800D01*
X699975Y660400D01*
X698715Y660700D01*
X697980Y661300D01*
X697665Y662350D01*
X697875Y663400D01*
X698400Y664150D01*
X699135Y664600D01*
X699870D01*
X700605Y664300D01*
X701235Y663550D01*
G01X706790Y664600D02*
X709310D01*
G01X708050D02*
Y655600D01*
G01X706790D02*
X709310D01*
G01X717280Y660100D02*
X719380D01*
Y657400D01*
X718750Y656500D01*
X718015Y655900D01*
X716965Y655600D01*
X715915Y655900D01*
X715180Y656500D01*
X714550Y657400D01*
X714130Y658450D01*
X713920Y659650D01*
Y660700D01*
X714130Y661600D01*
X714550Y662650D01*
X715180Y663550D01*
X715810Y664150D01*
X716650Y664600D01*
X717385D01*
X718225Y664300D01*
X718855Y663700D01*
G01X722835Y655600D02*
Y664600D01*
X727665Y655600D01*
Y664600D01*
G01X731225Y655600D02*
X733850Y664600D01*
X736475Y655600D01*
G01X735530Y658750D02*
X732170D01*
G01X740350Y664600D02*
Y655600D01*
X744550D01*
G01X750840Y653950D02*
X751260Y655900D01*
G01X768250Y655300D02*
X768040Y655450D01*
Y655750D01*
X768250Y655900D01*
X768460Y655750D01*
Y655450D01*
X768250Y655300D01*
G01X774540Y657400D02*
X775170Y656350D01*
X776010Y655750D01*
X776955Y655600D01*
X777795Y655750D01*
X778635Y656500D01*
X779160Y657400D01*
X779265Y658300D01*
X779055Y659350D01*
X778320Y660100D01*
X777585Y660400D01*
X776640D01*
G01X777585D02*
X778215Y660850D01*
X778740Y661600D01*
X778950Y662500D01*
X778740Y663400D01*
X778215Y664150D01*
X777270Y664600D01*
X776325Y664450D01*
X775380Y663850D01*
G01X785450Y655600D02*
X786185Y655750D01*
X787025Y656200D01*
X787550Y656950D01*
X787760Y658000D01*
X787550Y659050D01*
X786920Y659950D01*
X785975Y660400D01*
X784925D01*
X784295Y660700D01*
X783770Y661450D01*
X783560Y662500D01*
X783875Y663550D01*
X784610Y664300D01*
X785450Y664600D01*
X786290Y664300D01*
X787025Y663550D01*
X787340Y662500D01*
X787130Y661450D01*
X786605Y660700D01*
X785975Y660400D01*
X784925D01*
X783980Y659950D01*
X783350Y659050D01*
X783140Y658000D01*
X783350Y656950D01*
X783875Y656200D01*
X784715Y655750D01*
X785450Y655600D01*
G01X802650D02*
X801810Y655750D01*
X801075Y656350D01*
X800445Y657250D01*
X800025Y658300D01*
X799815Y659500D01*
Y660700D01*
X800025Y661900D01*
X800445Y662950D01*
X801075Y663850D01*
X801810Y664450D01*
X802650Y664600D01*
X803490Y664450D01*
X804225Y663850D01*
X804855Y662950D01*
X805275Y661900D01*
X805485Y660700D01*
Y659500D01*
X805275Y658300D01*
X804855Y657250D01*
X804225Y656350D01*
X803490Y655750D01*
X802650Y655600D01*
G01X808940Y664600D02*
Y658150D01*
X809360Y656800D01*
X810200Y655900D01*
X811250Y655600D01*
X812300Y655900D01*
X813140Y656800D01*
X813560Y658150D01*
Y664600D01*
G01X817435Y655600D02*
Y664600D01*
X822265Y655600D01*
Y664600D01*
G01X830760Y663850D02*
X830130Y664300D01*
X829395Y664600D01*
X828555D01*
X827610Y664150D01*
X826875Y663400D01*
X826350Y662500D01*
X825930Y661000D01*
X825825Y659650D01*
X826035Y658300D01*
X826350Y657400D01*
X826980Y656500D01*
X827715Y655900D01*
X828450Y655600D01*
X829185D01*
X829920Y655900D01*
X830550Y656350D01*
X831075Y656950D01*
G01X839150Y655600D02*
X834950D01*
Y664600D01*
X839150D01*
G01X837470Y660250D02*
X834950D01*
G01X856560Y663850D02*
X855930Y664300D01*
X855195Y664600D01*
X854355D01*
X853410Y664150D01*
X852675Y663400D01*
X852150Y662500D01*
X851730Y661000D01*
X851625Y659650D01*
X851835Y658300D01*
X852150Y657400D01*
X852780Y656500D01*
X853515Y655900D01*
X854250Y655600D01*
X854985D01*
X855720Y655900D01*
X856350Y656350D01*
X856875Y656950D01*
G01X862850Y655600D02*
X862010Y655750D01*
X861275Y656350D01*
X860645Y657250D01*
X860225Y658300D01*
X860015Y659500D01*
Y660700D01*
X860225Y661900D01*
X860645Y662950D01*
X861275Y663850D01*
X862010Y664450D01*
X862850Y664600D01*
X863690Y664450D01*
X864425Y663850D01*
X865055Y662950D01*
X865475Y661900D01*
X865685Y660700D01*
Y659500D01*
X865475Y658300D01*
X865055Y657250D01*
X864425Y656350D01*
X863690Y655750D01*
X862850Y655600D01*
G01X869350D02*
Y664600D01*
X871870D01*
X872710Y664150D01*
X873340Y663100D01*
X873550Y661900D01*
X873340Y660700D01*
X872815Y659800D01*
X871870Y659350D01*
X869350D01*
G01X877950Y655600D02*
Y664600D01*
X880470D01*
X881310Y664150D01*
X881940Y663100D01*
X882150Y661900D01*
X881940Y660700D01*
X881415Y659800D01*
X880470Y659350D01*
X877950D01*
G01X890750Y655600D02*
X886550D01*
Y664600D01*
X890750D01*
G01X889070Y660250D02*
X886550D01*
G01X895150Y655600D02*
Y664600D01*
X897775D01*
X898615Y664150D01*
X899140Y663550D01*
X899350Y662350D01*
X899140Y661150D01*
X898510Y660400D01*
X897775Y659950D01*
X895150D01*
G01X897775D02*
X899350Y655600D01*
G01X912245Y656800D02*
X913085Y656050D01*
X914030Y655600D01*
X914870D01*
X915710Y656050D01*
X916340Y656800D01*
X916655Y657850D01*
X916445Y658900D01*
X915920Y659800D01*
X914975Y660400D01*
X913715Y660700D01*
X912980Y661300D01*
X912665Y662350D01*
X912875Y663400D01*
X913400Y664150D01*
X914135Y664600D01*
X914870D01*
X915605Y664300D01*
X916235Y663550D01*
G01X923050Y664600D02*
Y655600D01*
G01X920635Y664600D02*
X925465D01*
G01X929025Y655600D02*
X931650Y664600D01*
X934275Y655600D01*
G01X933330Y658750D02*
X929970D01*
G01X938150Y655600D02*
Y664600D01*
X940775D01*
X941615Y664150D01*
X942140Y663550D01*
X942350Y662350D01*
X942140Y661150D01*
X941510Y660400D01*
X940775Y659950D01*
X938150D01*
G01X940775D02*
X942350Y655600D01*
G01X948850Y664600D02*
Y655600D01*
G01X946435Y664600D02*
X951265D01*
G01X671340Y680600D02*
Y689600D01*
X673440D01*
X674280Y689150D01*
X674910Y688550D01*
X675435Y687650D01*
X675855Y686600D01*
X675960Y685100D01*
X675855Y683600D01*
X675435Y682550D01*
X674910Y681650D01*
X674280Y681050D01*
X673440Y680600D01*
X671340D01*
G01X680990Y689600D02*
X683510D01*
G01X682250D02*
Y680600D01*
G01X680990D02*
X683510D01*
G01X692950D02*
X688750D01*
Y689600D01*
X692950D01*
G01X691270Y685250D02*
X688750D01*
G01X697350Y689600D02*
Y680600D01*
X701550D01*
G01X710150D02*
X705950D01*
Y689600D01*
X710150D01*
G01X708470Y685250D02*
X705950D01*
G01X718960Y688850D02*
X718330Y689300D01*
X717595Y689600D01*
X716755D01*
X715810Y689150D01*
X715075Y688400D01*
X714550Y687500D01*
X714130Y686000D01*
X714025Y684650D01*
X714235Y683300D01*
X714550Y682400D01*
X715180Y681500D01*
X715915Y680900D01*
X716650Y680600D01*
X717385D01*
X718120Y680900D01*
X718750Y681350D01*
X719275Y681950D01*
G01X725250Y689600D02*
Y680600D01*
G01X722835Y689600D02*
X727665D01*
G01X731750Y680600D02*
Y689600D01*
X734375D01*
X735215Y689150D01*
X735740Y688550D01*
X735950Y687350D01*
X735740Y686150D01*
X735110Y685400D01*
X734375Y684950D01*
X731750D01*
G01X734375D02*
X735950Y680600D01*
G01X741190Y689600D02*
X743710D01*
G01X742450D02*
Y680600D01*
G01X741190D02*
X743710D01*
G01X753360Y688850D02*
X752730Y689300D01*
X751995Y689600D01*
X751155D01*
X750210Y689150D01*
X749475Y688400D01*
X748950Y687500D01*
X748530Y686000D01*
X748425Y684650D01*
X748635Y683300D01*
X748950Y682400D01*
X749580Y681500D01*
X750315Y680900D01*
X751050Y680600D01*
X751785D01*
X752520Y680900D01*
X753150Y681350D01*
X753675Y681950D01*
G01X671550Y714600D02*
Y705600D01*
X675750D01*
G01X682040D02*
X682250Y707550D01*
X682565Y709200D01*
X682985Y710700D01*
X683510Y712350D01*
X684350Y714600D01*
X680150D01*
G01X700080Y710100D02*
X702180D01*
Y707400D01*
X701550Y706500D01*
X700815Y705900D01*
X699765Y705600D01*
X698715Y705900D01*
X697980Y706500D01*
X697350Y707400D01*
X696930Y708450D01*
X696720Y709650D01*
Y710700D01*
X696930Y711600D01*
X697350Y712650D01*
X697980Y713550D01*
X698610Y714150D01*
X699450Y714600D01*
X700185D01*
X701025Y714300D01*
X701655Y713700D01*
G01X705950Y705600D02*
Y714600D01*
X708575D01*
X709415Y714150D01*
X709940Y713550D01*
X710150Y712350D01*
X709940Y711150D01*
X709310Y710400D01*
X708575Y709950D01*
X705950D01*
G01X708575D02*
X710150Y705600D01*
G01X716650D02*
X715810Y705750D01*
X715075Y706350D01*
X714445Y707250D01*
X714025Y708300D01*
X713815Y709500D01*
Y710700D01*
X714025Y711900D01*
X714445Y712950D01*
X715075Y713850D01*
X715810Y714450D01*
X716650Y714600D01*
X717490Y714450D01*
X718225Y713850D01*
X718855Y712950D01*
X719275Y711900D01*
X719485Y710700D01*
Y709500D01*
X719275Y708300D01*
X718855Y707250D01*
X718225Y706350D01*
X717490Y705750D01*
X716650Y705600D01*
G01X722940Y714600D02*
Y708150D01*
X723360Y706800D01*
X724200Y705900D01*
X725250Y705600D01*
X726300Y705900D01*
X727140Y706800D01*
X727560Y708150D01*
Y714600D01*
G01X731435Y705600D02*
Y714600D01*
X736265Y705600D01*
Y714600D01*
G01X740140Y705600D02*
Y714600D01*
X742240D01*
X743080Y714150D01*
X743710Y713550D01*
X744235Y712650D01*
X744655Y711600D01*
X744760Y710100D01*
X744655Y708600D01*
X744235Y707550D01*
X743710Y706650D01*
X743080Y706050D01*
X742240Y705600D01*
X740140D01*
G01X750840Y703950D02*
X751260Y705900D01*
G01X768250Y705600D02*
Y714600D01*
X766990Y712800D01*
G01Y705600D02*
X769510D01*
G01X785450D02*
X784610Y705750D01*
X783875Y706350D01*
X783245Y707250D01*
X782825Y708300D01*
X782615Y709500D01*
Y710700D01*
X782825Y711900D01*
X783245Y712950D01*
X783875Y713850D01*
X784610Y714450D01*
X785450Y714600D01*
X786290Y714450D01*
X787025Y713850D01*
X787655Y712950D01*
X788075Y711900D01*
X788285Y710700D01*
Y709500D01*
X788075Y708300D01*
X787655Y707250D01*
X787025Y706350D01*
X786290Y705750D01*
X785450Y705600D01*
G01X791740Y714600D02*
Y708150D01*
X792160Y706800D01*
X793000Y705900D01*
X794050Y705600D01*
X795100Y705900D01*
X795940Y706800D01*
X796360Y708150D01*
Y714600D01*
G01X800235Y705600D02*
Y714600D01*
X805065Y705600D01*
Y714600D01*
G01X813560Y713850D02*
X812930Y714300D01*
X812195Y714600D01*
X811355D01*
X810410Y714150D01*
X809675Y713400D01*
X809150Y712500D01*
X808730Y711000D01*
X808625Y709650D01*
X808835Y708300D01*
X809150Y707400D01*
X809780Y706500D01*
X810515Y705900D01*
X811250Y705600D01*
X811985D01*
X812720Y705900D01*
X813350Y706350D01*
X813875Y706950D01*
G01X821950Y705600D02*
X817750D01*
Y714600D01*
X821950D01*
G01X820270Y710250D02*
X817750D01*
G01X839360Y713850D02*
X838730Y714300D01*
X837995Y714600D01*
X837155D01*
X836210Y714150D01*
X835475Y713400D01*
X834950Y712500D01*
X834530Y711000D01*
X834425Y709650D01*
X834635Y708300D01*
X834950Y707400D01*
X835580Y706500D01*
X836315Y705900D01*
X837050Y705600D01*
X837785D01*
X838520Y705900D01*
X839150Y706350D01*
X839675Y706950D01*
G01X845650Y705600D02*
X844810Y705750D01*
X844075Y706350D01*
X843445Y707250D01*
X843025Y708300D01*
X842815Y709500D01*
Y710700D01*
X843025Y711900D01*
X843445Y712950D01*
X844075Y713850D01*
X844810Y714450D01*
X845650Y714600D01*
X846490Y714450D01*
X847225Y713850D01*
X847855Y712950D01*
X848275Y711900D01*
X848485Y710700D01*
Y709500D01*
X848275Y708300D01*
X847855Y707250D01*
X847225Y706350D01*
X846490Y705750D01*
X845650Y705600D01*
G01X852150D02*
Y714600D01*
X854670D01*
X855510Y714150D01*
X856140Y713100D01*
X856350Y711900D01*
X856140Y710700D01*
X855615Y709800D01*
X854670Y709350D01*
X852150D01*
G01X860750Y705600D02*
Y714600D01*
X863270D01*
X864110Y714150D01*
X864740Y713100D01*
X864950Y711900D01*
X864740Y710700D01*
X864215Y709800D01*
X863270Y709350D01*
X860750D01*
G01X873550Y705600D02*
X869350D01*
Y714600D01*
X873550D01*
G01X871870Y710250D02*
X869350D01*
G01X877950Y705600D02*
Y714600D01*
X880575D01*
X881415Y714150D01*
X881940Y713550D01*
X882150Y712350D01*
X881940Y711150D01*
X881310Y710400D01*
X880575Y709950D01*
X877950D01*
G01X880575D02*
X882150Y705600D01*
G01X671340Y730600D02*
Y739600D01*
X673440D01*
X674280Y739150D01*
X674910Y738550D01*
X675435Y737650D01*
X675855Y736600D01*
X675960Y735100D01*
X675855Y733600D01*
X675435Y732550D01*
X674910Y731650D01*
X674280Y731050D01*
X673440Y730600D01*
X671340D01*
G01X680990Y739600D02*
X683510D01*
G01X682250D02*
Y730600D01*
G01X680990D02*
X683510D01*
G01X692950D02*
X688750D01*
Y739600D01*
X692950D01*
G01X691270Y735250D02*
X688750D01*
G01X697350Y739600D02*
Y730600D01*
X701550D01*
G01X710150D02*
X705950D01*
Y739600D01*
X710150D01*
G01X708470Y735250D02*
X705950D01*
G01X718960Y738850D02*
X718330Y739300D01*
X717595Y739600D01*
X716755D01*
X715810Y739150D01*
X715075Y738400D01*
X714550Y737500D01*
X714130Y736000D01*
X714025Y734650D01*
X714235Y733300D01*
X714550Y732400D01*
X715180Y731500D01*
X715915Y730900D01*
X716650Y730600D01*
X717385D01*
X718120Y730900D01*
X718750Y731350D01*
X719275Y731950D01*
G01X725250Y739600D02*
Y730600D01*
G01X722835Y739600D02*
X727665D01*
G01X731750Y730600D02*
Y739600D01*
X734375D01*
X735215Y739150D01*
X735740Y738550D01*
X735950Y737350D01*
X735740Y736150D01*
X735110Y735400D01*
X734375Y734950D01*
X731750D01*
G01X734375D02*
X735950Y730600D01*
G01X741190Y739600D02*
X743710D01*
G01X742450D02*
Y730600D01*
G01X741190D02*
X743710D01*
G01X753360Y738850D02*
X752730Y739300D01*
X751995Y739600D01*
X751155D01*
X750210Y739150D01*
X749475Y738400D01*
X748950Y737500D01*
X748530Y736000D01*
X748425Y734650D01*
X748635Y733300D01*
X748950Y732400D01*
X749580Y731500D01*
X750315Y730900D01*
X751050Y730600D01*
X751785D01*
X752520Y730900D01*
X753150Y731350D01*
X753675Y731950D01*
G01X671550Y764600D02*
Y755600D01*
X675750D01*
G01X680255Y759350D02*
X680990Y760400D01*
X681620Y761000D01*
X682460Y761300D01*
X683195Y761000D01*
X683720Y760400D01*
X684140Y759500D01*
X684245Y758450D01*
X684140Y757550D01*
X683720Y756650D01*
X683090Y755900D01*
X682355Y755600D01*
X681515Y755900D01*
X680780Y756800D01*
X680360Y758150D01*
X680255Y759650D01*
X680465Y761600D01*
X680780Y762650D01*
X681305Y763700D01*
X682040Y764450D01*
X682775Y764600D01*
X683510Y764300D01*
X684035Y763550D01*
G01X697245Y756800D02*
X698085Y756050D01*
X699030Y755600D01*
X699870D01*
X700710Y756050D01*
X701340Y756800D01*
X701655Y757850D01*
X701445Y758900D01*
X700920Y759800D01*
X699975Y760400D01*
X698715Y760700D01*
X697980Y761300D01*
X697665Y762350D01*
X697875Y763400D01*
X698400Y764150D01*
X699135Y764600D01*
X699870D01*
X700605Y764300D01*
X701235Y763550D01*
G01X706790Y764600D02*
X709310D01*
G01X708050D02*
Y755600D01*
G01X706790D02*
X709310D01*
G01X717280Y760100D02*
X719380D01*
Y757400D01*
X718750Y756500D01*
X718015Y755900D01*
X716965Y755600D01*
X715915Y755900D01*
X715180Y756500D01*
X714550Y757400D01*
X714130Y758450D01*
X713920Y759650D01*
Y760700D01*
X714130Y761600D01*
X714550Y762650D01*
X715180Y763550D01*
X715810Y764150D01*
X716650Y764600D01*
X717385D01*
X718225Y764300D01*
X718855Y763700D01*
G01X722835Y755600D02*
Y764600D01*
X727665Y755600D01*
Y764600D01*
G01X731225Y755600D02*
X733850Y764600D01*
X736475Y755600D01*
G01X735530Y758750D02*
X732170D01*
G01X740350Y764600D02*
Y755600D01*
X744550D01*
G01X750840Y753950D02*
X751260Y755900D01*
G01X768250Y755600D02*
Y764600D01*
X766990Y762800D01*
G01Y755600D02*
X769510D01*
G01X785450D02*
X784610Y755750D01*
X783875Y756350D01*
X783245Y757250D01*
X782825Y758300D01*
X782615Y759500D01*
Y760700D01*
X782825Y761900D01*
X783245Y762950D01*
X783875Y763850D01*
X784610Y764450D01*
X785450Y764600D01*
X786290Y764450D01*
X787025Y763850D01*
X787655Y762950D01*
X788075Y761900D01*
X788285Y760700D01*
Y759500D01*
X788075Y758300D01*
X787655Y757250D01*
X787025Y756350D01*
X786290Y755750D01*
X785450Y755600D01*
G01X791740Y764600D02*
Y758150D01*
X792160Y756800D01*
X793000Y755900D01*
X794050Y755600D01*
X795100Y755900D01*
X795940Y756800D01*
X796360Y758150D01*
Y764600D01*
G01X800235Y755600D02*
Y764600D01*
X805065Y755600D01*
Y764600D01*
G01X813560Y763850D02*
X812930Y764300D01*
X812195Y764600D01*
X811355D01*
X810410Y764150D01*
X809675Y763400D01*
X809150Y762500D01*
X808730Y761000D01*
X808625Y759650D01*
X808835Y758300D01*
X809150Y757400D01*
X809780Y756500D01*
X810515Y755900D01*
X811250Y755600D01*
X811985D01*
X812720Y755900D01*
X813350Y756350D01*
X813875Y756950D01*
G01X821950Y755600D02*
X817750D01*
Y764600D01*
X821950D01*
G01X820270Y760250D02*
X817750D01*
G01X839360Y763850D02*
X838730Y764300D01*
X837995Y764600D01*
X837155D01*
X836210Y764150D01*
X835475Y763400D01*
X834950Y762500D01*
X834530Y761000D01*
X834425Y759650D01*
X834635Y758300D01*
X834950Y757400D01*
X835580Y756500D01*
X836315Y755900D01*
X837050Y755600D01*
X837785D01*
X838520Y755900D01*
X839150Y756350D01*
X839675Y756950D01*
G01X845650Y755600D02*
X844810Y755750D01*
X844075Y756350D01*
X843445Y757250D01*
X843025Y758300D01*
X842815Y759500D01*
Y760700D01*
X843025Y761900D01*
X843445Y762950D01*
X844075Y763850D01*
X844810Y764450D01*
X845650Y764600D01*
X846490Y764450D01*
X847225Y763850D01*
X847855Y762950D01*
X848275Y761900D01*
X848485Y760700D01*
Y759500D01*
X848275Y758300D01*
X847855Y757250D01*
X847225Y756350D01*
X846490Y755750D01*
X845650Y755600D01*
G01X852150D02*
Y764600D01*
X854670D01*
X855510Y764150D01*
X856140Y763100D01*
X856350Y761900D01*
X856140Y760700D01*
X855615Y759800D01*
X854670Y759350D01*
X852150D01*
G01X860750Y755600D02*
Y764600D01*
X863270D01*
X864110Y764150D01*
X864740Y763100D01*
X864950Y761900D01*
X864740Y760700D01*
X864215Y759800D01*
X863270Y759350D01*
X860750D01*
G01X873550Y755600D02*
X869350D01*
Y764600D01*
X873550D01*
G01X871870Y760250D02*
X869350D01*
G01X877950Y755600D02*
Y764600D01*
X880575D01*
X881415Y764150D01*
X881940Y763550D01*
X882150Y762350D01*
X881940Y761150D01*
X881310Y760400D01*
X880575Y759950D01*
X877950D01*
G01X880575D02*
X882150Y755600D01*
G01X671340Y780600D02*
Y789600D01*
X673440D01*
X674280Y789150D01*
X674910Y788550D01*
X675435Y787650D01*
X675855Y786600D01*
X675960Y785100D01*
X675855Y783600D01*
X675435Y782550D01*
X674910Y781650D01*
X674280Y781050D01*
X673440Y780600D01*
X671340D01*
G01X680990Y789600D02*
X683510D01*
G01X682250D02*
Y780600D01*
G01X680990D02*
X683510D01*
G01X692950D02*
X688750D01*
Y789600D01*
X692950D01*
G01X691270Y785250D02*
X688750D01*
G01X697350Y789600D02*
Y780600D01*
X701550D01*
G01X710150D02*
X705950D01*
Y789600D01*
X710150D01*
G01X708470Y785250D02*
X705950D01*
G01X718960Y788850D02*
X718330Y789300D01*
X717595Y789600D01*
X716755D01*
X715810Y789150D01*
X715075Y788400D01*
X714550Y787500D01*
X714130Y786000D01*
X714025Y784650D01*
X714235Y783300D01*
X714550Y782400D01*
X715180Y781500D01*
X715915Y780900D01*
X716650Y780600D01*
X717385D01*
X718120Y780900D01*
X718750Y781350D01*
X719275Y781950D01*
G01X725250Y789600D02*
Y780600D01*
G01X722835Y789600D02*
X727665D01*
G01X731750Y780600D02*
Y789600D01*
X734375D01*
X735215Y789150D01*
X735740Y788550D01*
X735950Y787350D01*
X735740Y786150D01*
X735110Y785400D01*
X734375Y784950D01*
X731750D01*
G01X734375D02*
X735950Y780600D01*
G01X741190Y789600D02*
X743710D01*
G01X742450D02*
Y780600D01*
G01X741190D02*
X743710D01*
G01X753360Y788850D02*
X752730Y789300D01*
X751995Y789600D01*
X751155D01*
X750210Y789150D01*
X749475Y788400D01*
X748950Y787500D01*
X748530Y786000D01*
X748425Y784650D01*
X748635Y783300D01*
X748950Y782400D01*
X749580Y781500D01*
X750315Y780900D01*
X751050Y780600D01*
X751785D01*
X752520Y780900D01*
X753150Y781350D01*
X753675Y781950D01*
G01X671550Y814600D02*
Y805600D01*
X675750D01*
G01X679940Y806950D02*
X680570Y806200D01*
X681305Y805750D01*
X682250Y805600D01*
X683195Y805900D01*
X683930Y806500D01*
X684455Y807550D01*
X684560Y808750D01*
X684350Y809950D01*
X683825Y810700D01*
X683090Y811300D01*
X682355Y811450D01*
X681620Y811300D01*
X680675Y810700D01*
X680990Y814600D01*
X683825D01*
G01X697350Y805600D02*
Y814600D01*
X699870D01*
X700710Y814150D01*
X701340Y813100D01*
X701550Y811900D01*
X701340Y810700D01*
X700815Y809800D01*
X699870Y809350D01*
X697350D01*
G01X708050Y805600D02*
X707210Y805750D01*
X706475Y806350D01*
X705845Y807250D01*
X705425Y808300D01*
X705215Y809500D01*
Y810700D01*
X705425Y811900D01*
X705845Y812950D01*
X706475Y813850D01*
X707210Y814450D01*
X708050Y814600D01*
X708890Y814450D01*
X709625Y813850D01*
X710255Y812950D01*
X710675Y811900D01*
X710885Y810700D01*
Y809500D01*
X710675Y808300D01*
X710255Y807250D01*
X709625Y806350D01*
X708890Y805750D01*
X708050Y805600D01*
G01X713500Y814600D02*
X714970Y805600D01*
X716650Y814600D01*
X718330Y805600D01*
X719800Y814600D01*
G01X727350Y805600D02*
X723150D01*
Y814600D01*
X727350D01*
G01X725670Y810250D02*
X723150D01*
G01X731750Y805600D02*
Y814600D01*
X734375D01*
X735215Y814150D01*
X735740Y813550D01*
X735950Y812350D01*
X735740Y811150D01*
X735110Y810400D01*
X734375Y809950D01*
X731750D01*
G01X734375D02*
X735950Y805600D01*
G01X742240Y803950D02*
X742660Y805900D01*
G01X757655Y813100D02*
X758285Y814000D01*
X759020Y814450D01*
X759860Y814600D01*
X760910Y814300D01*
X761645Y813550D01*
X761855Y812650D01*
X761750Y811750D01*
X761330Y811000D01*
X759230Y809500D01*
X758285Y808450D01*
X757655Y806950D01*
X757445Y805600D01*
X761855D01*
G01X776850D02*
X776010Y805750D01*
X775275Y806350D01*
X774645Y807250D01*
X774225Y808300D01*
X774015Y809500D01*
Y810700D01*
X774225Y811900D01*
X774645Y812950D01*
X775275Y813850D01*
X776010Y814450D01*
X776850Y814600D01*
X777690Y814450D01*
X778425Y813850D01*
X779055Y812950D01*
X779475Y811900D01*
X779685Y810700D01*
Y809500D01*
X779475Y808300D01*
X779055Y807250D01*
X778425Y806350D01*
X777690Y805750D01*
X776850Y805600D01*
G01X783140Y814600D02*
Y808150D01*
X783560Y806800D01*
X784400Y805900D01*
X785450Y805600D01*
X786500Y805900D01*
X787340Y806800D01*
X787760Y808150D01*
Y814600D01*
G01X791635Y805600D02*
Y814600D01*
X796465Y805600D01*
Y814600D01*
G01X804960Y813850D02*
X804330Y814300D01*
X803595Y814600D01*
X802755D01*
X801810Y814150D01*
X801075Y813400D01*
X800550Y812500D01*
X800130Y811000D01*
X800025Y809650D01*
X800235Y808300D01*
X800550Y807400D01*
X801180Y806500D01*
X801915Y805900D01*
X802650Y805600D01*
X803385D01*
X804120Y805900D01*
X804750Y806350D01*
X805275Y806950D01*
G01X813350Y805600D02*
X809150D01*
Y814600D01*
X813350D01*
G01X811670Y810250D02*
X809150D01*
G01X830760Y813850D02*
X830130Y814300D01*
X829395Y814600D01*
X828555D01*
X827610Y814150D01*
X826875Y813400D01*
X826350Y812500D01*
X825930Y811000D01*
X825825Y809650D01*
X826035Y808300D01*
X826350Y807400D01*
X826980Y806500D01*
X827715Y805900D01*
X828450Y805600D01*
X829185D01*
X829920Y805900D01*
X830550Y806350D01*
X831075Y806950D01*
G01X837050Y805600D02*
X836210Y805750D01*
X835475Y806350D01*
X834845Y807250D01*
X834425Y808300D01*
X834215Y809500D01*
Y810700D01*
X834425Y811900D01*
X834845Y812950D01*
X835475Y813850D01*
X836210Y814450D01*
X837050Y814600D01*
X837890Y814450D01*
X838625Y813850D01*
X839255Y812950D01*
X839675Y811900D01*
X839885Y810700D01*
Y809500D01*
X839675Y808300D01*
X839255Y807250D01*
X838625Y806350D01*
X837890Y805750D01*
X837050Y805600D01*
G01X843550D02*
Y814600D01*
X846070D01*
X846910Y814150D01*
X847540Y813100D01*
X847750Y811900D01*
X847540Y810700D01*
X847015Y809800D01*
X846070Y809350D01*
X843550D01*
G01X852150Y805600D02*
Y814600D01*
X854670D01*
X855510Y814150D01*
X856140Y813100D01*
X856350Y811900D01*
X856140Y810700D01*
X855615Y809800D01*
X854670Y809350D01*
X852150D01*
G01X864950Y805600D02*
X860750D01*
Y814600D01*
X864950D01*
G01X863270Y810250D02*
X860750D01*
G01X869350Y805600D02*
Y814600D01*
X871975D01*
X872815Y814150D01*
X873340Y813550D01*
X873550Y812350D01*
X873340Y811150D01*
X872710Y810400D01*
X871975Y809950D01*
X869350D01*
G01X871975D02*
X873550Y805600D01*
G01X670840Y833100D02*
Y842100D01*
X672940D01*
X673780Y841650D01*
X674410Y841050D01*
X674935Y840150D01*
X675355Y839100D01*
X675460Y837600D01*
X675355Y836100D01*
X674935Y835050D01*
X674410Y834150D01*
X673780Y833550D01*
X672940Y833100D01*
X670840D01*
G01X680490Y842100D02*
X683010D01*
G01X681750D02*
Y833100D01*
G01X680490D02*
X683010D01*
G01X692450D02*
X688250D01*
Y842100D01*
X692450D01*
G01X690770Y837750D02*
X688250D01*
G01X696850Y842100D02*
Y833100D01*
X701050D01*
G01X709650D02*
X705450D01*
Y842100D01*
X709650D01*
G01X707970Y837750D02*
X705450D01*
G01X718460Y841350D02*
X717830Y841800D01*
X717095Y842100D01*
X716255D01*
X715310Y841650D01*
X714575Y840900D01*
X714050Y840000D01*
X713630Y838500D01*
X713525Y837150D01*
X713735Y835800D01*
X714050Y834900D01*
X714680Y834000D01*
X715415Y833400D01*
X716150Y833100D01*
X716885D01*
X717620Y833400D01*
X718250Y833850D01*
X718775Y834450D01*
G01X724750Y842100D02*
Y833100D01*
G01X722335Y842100D02*
X727165D01*
G01X731250Y833100D02*
Y842100D01*
X733875D01*
X734715Y841650D01*
X735240Y841050D01*
X735450Y839850D01*
X735240Y838650D01*
X734610Y837900D01*
X733875Y837450D01*
X731250D01*
G01X733875D02*
X735450Y833100D01*
G01X740690Y842100D02*
X743210D01*
G01X741950D02*
Y833100D01*
G01X740690D02*
X743210D01*
G01X752860Y841350D02*
X752230Y841800D01*
X751495Y842100D01*
X750655D01*
X749710Y841650D01*
X748975Y840900D01*
X748450Y840000D01*
X748030Y838500D01*
X747925Y837150D01*
X748135Y835800D01*
X748450Y834900D01*
X749080Y834000D01*
X749815Y833400D01*
X750550Y833100D01*
X751285D01*
X752020Y833400D01*
X752650Y833850D01*
X753175Y834450D01*
G01X671050Y871600D02*
Y862600D01*
X675250D01*
G01X683010D02*
Y871600D01*
X679125Y865150D01*
X684375D01*
G01X696850Y862600D02*
Y871600D01*
X699370D01*
X700210Y871150D01*
X700840Y870100D01*
X701050Y868900D01*
X700840Y867700D01*
X700315Y866800D01*
X699370Y866350D01*
X696850D01*
G01X707550Y862600D02*
X706710Y862750D01*
X705975Y863350D01*
X705345Y864250D01*
X704925Y865300D01*
X704715Y866500D01*
Y867700D01*
X704925Y868900D01*
X705345Y869950D01*
X705975Y870850D01*
X706710Y871450D01*
X707550Y871600D01*
X708390Y871450D01*
X709125Y870850D01*
X709755Y869950D01*
X710175Y868900D01*
X710385Y867700D01*
Y866500D01*
X710175Y865300D01*
X709755Y864250D01*
X709125Y863350D01*
X708390Y862750D01*
X707550Y862600D01*
G01X713000Y871600D02*
X714470Y862600D01*
X716150Y871600D01*
X717830Y862600D01*
X719300Y871600D01*
G01X726850Y862600D02*
X722650D01*
Y871600D01*
X726850D01*
G01X725170Y867250D02*
X722650D01*
G01X731250Y862600D02*
Y871600D01*
X733875D01*
X734715Y871150D01*
X735240Y870550D01*
X735450Y869350D01*
X735240Y868150D01*
X734610Y867400D01*
X733875Y866950D01*
X731250D01*
G01X733875D02*
X735450Y862600D01*
G01X741740Y860950D02*
X742160Y862900D01*
G01X757155Y870100D02*
X757785Y871000D01*
X758520Y871450D01*
X759360Y871600D01*
X760410Y871300D01*
X761145Y870550D01*
X761355Y869650D01*
X761250Y868750D01*
X760830Y868000D01*
X758730Y866500D01*
X757785Y865450D01*
X757155Y863950D01*
X756945Y862600D01*
X761355D01*
G01X776350D02*
X775510Y862750D01*
X774775Y863350D01*
X774145Y864250D01*
X773725Y865300D01*
X773515Y866500D01*
Y867700D01*
X773725Y868900D01*
X774145Y869950D01*
X774775Y870850D01*
X775510Y871450D01*
X776350Y871600D01*
X777190Y871450D01*
X777925Y870850D01*
X778555Y869950D01*
X778975Y868900D01*
X779185Y867700D01*
Y866500D01*
X778975Y865300D01*
X778555Y864250D01*
X777925Y863350D01*
X777190Y862750D01*
X776350Y862600D01*
G01X782640Y871600D02*
Y865150D01*
X783060Y863800D01*
X783900Y862900D01*
X784950Y862600D01*
X786000Y862900D01*
X786840Y863800D01*
X787260Y865150D01*
Y871600D01*
G01X791135Y862600D02*
Y871600D01*
X795965Y862600D01*
Y871600D01*
G01X804460Y870850D02*
X803830Y871300D01*
X803095Y871600D01*
X802255D01*
X801310Y871150D01*
X800575Y870400D01*
X800050Y869500D01*
X799630Y868000D01*
X799525Y866650D01*
X799735Y865300D01*
X800050Y864400D01*
X800680Y863500D01*
X801415Y862900D01*
X802150Y862600D01*
X802885D01*
X803620Y862900D01*
X804250Y863350D01*
X804775Y863950D01*
G01X812850Y862600D02*
X808650D01*
Y871600D01*
X812850D01*
G01X811170Y867250D02*
X808650D01*
G01X830260Y870850D02*
X829630Y871300D01*
X828895Y871600D01*
X828055D01*
X827110Y871150D01*
X826375Y870400D01*
X825850Y869500D01*
X825430Y868000D01*
X825325Y866650D01*
X825535Y865300D01*
X825850Y864400D01*
X826480Y863500D01*
X827215Y862900D01*
X827950Y862600D01*
X828685D01*
X829420Y862900D01*
X830050Y863350D01*
X830575Y863950D01*
G01X836550Y862600D02*
X835710Y862750D01*
X834975Y863350D01*
X834345Y864250D01*
X833925Y865300D01*
X833715Y866500D01*
Y867700D01*
X833925Y868900D01*
X834345Y869950D01*
X834975Y870850D01*
X835710Y871450D01*
X836550Y871600D01*
X837390Y871450D01*
X838125Y870850D01*
X838755Y869950D01*
X839175Y868900D01*
X839385Y867700D01*
Y866500D01*
X839175Y865300D01*
X838755Y864250D01*
X838125Y863350D01*
X837390Y862750D01*
X836550Y862600D01*
G01X843050D02*
Y871600D01*
X845570D01*
X846410Y871150D01*
X847040Y870100D01*
X847250Y868900D01*
X847040Y867700D01*
X846515Y866800D01*
X845570Y866350D01*
X843050D01*
G01X851650Y862600D02*
Y871600D01*
X854170D01*
X855010Y871150D01*
X855640Y870100D01*
X855850Y868900D01*
X855640Y867700D01*
X855115Y866800D01*
X854170Y866350D01*
X851650D01*
G01X864450Y862600D02*
X860250D01*
Y871600D01*
X864450D01*
G01X862770Y867250D02*
X860250D01*
G01X868850Y862600D02*
Y871600D01*
X871475D01*
X872315Y871150D01*
X872840Y870550D01*
X873050Y869350D01*
X872840Y868150D01*
X872210Y867400D01*
X871475Y866950D01*
X868850D01*
G01X871475D02*
X873050Y862600D01*
G01X670840Y887600D02*
Y896600D01*
X672940D01*
X673780Y896150D01*
X674410Y895550D01*
X674935Y894650D01*
X675355Y893600D01*
X675460Y892100D01*
X675355Y890600D01*
X674935Y889550D01*
X674410Y888650D01*
X673780Y888050D01*
X672940Y887600D01*
X670840D01*
G01X680490Y896600D02*
X683010D01*
G01X681750D02*
Y887600D01*
G01X680490D02*
X683010D01*
G01X692450D02*
X688250D01*
Y896600D01*
X692450D01*
G01X690770Y892250D02*
X688250D01*
G01X696850Y896600D02*
Y887600D01*
X701050D01*
G01X709650D02*
X705450D01*
Y896600D01*
X709650D01*
G01X707970Y892250D02*
X705450D01*
G01X718460Y895850D02*
X717830Y896300D01*
X717095Y896600D01*
X716255D01*
X715310Y896150D01*
X714575Y895400D01*
X714050Y894500D01*
X713630Y893000D01*
X713525Y891650D01*
X713735Y890300D01*
X714050Y889400D01*
X714680Y888500D01*
X715415Y887900D01*
X716150Y887600D01*
X716885D01*
X717620Y887900D01*
X718250Y888350D01*
X718775Y888950D01*
G01X724750Y896600D02*
Y887600D01*
G01X722335Y896600D02*
X727165D01*
G01X731250Y887600D02*
Y896600D01*
X733875D01*
X734715Y896150D01*
X735240Y895550D01*
X735450Y894350D01*
X735240Y893150D01*
X734610Y892400D01*
X733875Y891950D01*
X731250D01*
G01X733875D02*
X735450Y887600D01*
G01X740690Y896600D02*
X743210D01*
G01X741950D02*
Y887600D01*
G01X740690D02*
X743210D01*
G01X752860Y895850D02*
X752230Y896300D01*
X751495Y896600D01*
X750655D01*
X749710Y896150D01*
X748975Y895400D01*
X748450Y894500D01*
X748030Y893000D01*
X747925Y891650D01*
X748135Y890300D01*
X748450Y889400D01*
X749080Y888500D01*
X749815Y887900D01*
X750550Y887600D01*
X751285D01*
X752020Y887900D01*
X752650Y888350D01*
X753175Y888950D01*
G01X671050Y921600D02*
Y912600D01*
X675250D01*
G01X679440Y914400D02*
X680070Y913350D01*
X680910Y912750D01*
X681855Y912600D01*
X682695Y912750D01*
X683535Y913500D01*
X684060Y914400D01*
X684165Y915300D01*
X683955Y916350D01*
X683220Y917100D01*
X682485Y917400D01*
X681540D01*
G01X682485D02*
X683115Y917850D01*
X683640Y918600D01*
X683850Y919500D01*
X683640Y920400D01*
X683115Y921150D01*
X682170Y921600D01*
X681225Y921450D01*
X680280Y920850D01*
G01X696745Y913800D02*
X697585Y913050D01*
X698530Y912600D01*
X699370D01*
X700210Y913050D01*
X700840Y913800D01*
X701155Y914850D01*
X700945Y915900D01*
X700420Y916800D01*
X699475Y917400D01*
X698215Y917700D01*
X697480Y918300D01*
X697165Y919350D01*
X697375Y920400D01*
X697900Y921150D01*
X698635Y921600D01*
X699370D01*
X700105Y921300D01*
X700735Y920550D01*
G01X706290Y921600D02*
X708810D01*
G01X707550D02*
Y912600D01*
G01X706290D02*
X708810D01*
G01X716780Y917100D02*
X718880D01*
Y914400D01*
X718250Y913500D01*
X717515Y912900D01*
X716465Y912600D01*
X715415Y912900D01*
X714680Y913500D01*
X714050Y914400D01*
X713630Y915450D01*
X713420Y916650D01*
Y917700D01*
X713630Y918600D01*
X714050Y919650D01*
X714680Y920550D01*
X715310Y921150D01*
X716150Y921600D01*
X716885D01*
X717725Y921300D01*
X718355Y920700D01*
G01X722335Y912600D02*
Y921600D01*
X727165Y912600D01*
Y921600D01*
G01X730725Y912600D02*
X733350Y921600D01*
X735975Y912600D01*
G01X735030Y915750D02*
X731670D01*
G01X739850Y921600D02*
Y912600D01*
X744050D01*
G01X750340Y910950D02*
X750760Y912900D01*
G01X767750Y912600D02*
Y921600D01*
X766490Y919800D01*
G01Y912600D02*
X769010D01*
G01X784950D02*
X784110Y912750D01*
X783375Y913350D01*
X782745Y914250D01*
X782325Y915300D01*
X782115Y916500D01*
Y917700D01*
X782325Y918900D01*
X782745Y919950D01*
X783375Y920850D01*
X784110Y921450D01*
X784950Y921600D01*
X785790Y921450D01*
X786525Y920850D01*
X787155Y919950D01*
X787575Y918900D01*
X787785Y917700D01*
Y916500D01*
X787575Y915300D01*
X787155Y914250D01*
X786525Y913350D01*
X785790Y912750D01*
X784950Y912600D01*
G01X791240Y921600D02*
Y915150D01*
X791660Y913800D01*
X792500Y912900D01*
X793550Y912600D01*
X794600Y912900D01*
X795440Y913800D01*
X795860Y915150D01*
Y921600D01*
G01X799735Y912600D02*
Y921600D01*
X804565Y912600D01*
Y921600D01*
G01X813060Y920850D02*
X812430Y921300D01*
X811695Y921600D01*
X810855D01*
X809910Y921150D01*
X809175Y920400D01*
X808650Y919500D01*
X808230Y918000D01*
X808125Y916650D01*
X808335Y915300D01*
X808650Y914400D01*
X809280Y913500D01*
X810015Y912900D01*
X810750Y912600D01*
X811485D01*
X812220Y912900D01*
X812850Y913350D01*
X813375Y913950D01*
G01X821450Y912600D02*
X817250D01*
Y921600D01*
X821450D01*
G01X819770Y917250D02*
X817250D01*
G01X838860Y920850D02*
X838230Y921300D01*
X837495Y921600D01*
X836655D01*
X835710Y921150D01*
X834975Y920400D01*
X834450Y919500D01*
X834030Y918000D01*
X833925Y916650D01*
X834135Y915300D01*
X834450Y914400D01*
X835080Y913500D01*
X835815Y912900D01*
X836550Y912600D01*
X837285D01*
X838020Y912900D01*
X838650Y913350D01*
X839175Y913950D01*
G01X845150Y912600D02*
X844310Y912750D01*
X843575Y913350D01*
X842945Y914250D01*
X842525Y915300D01*
X842315Y916500D01*
Y917700D01*
X842525Y918900D01*
X842945Y919950D01*
X843575Y920850D01*
X844310Y921450D01*
X845150Y921600D01*
X845990Y921450D01*
X846725Y920850D01*
X847355Y919950D01*
X847775Y918900D01*
X847985Y917700D01*
Y916500D01*
X847775Y915300D01*
X847355Y914250D01*
X846725Y913350D01*
X845990Y912750D01*
X845150Y912600D01*
G01X851650D02*
Y921600D01*
X854170D01*
X855010Y921150D01*
X855640Y920100D01*
X855850Y918900D01*
X855640Y917700D01*
X855115Y916800D01*
X854170Y916350D01*
X851650D01*
G01X860250Y912600D02*
Y921600D01*
X862770D01*
X863610Y921150D01*
X864240Y920100D01*
X864450Y918900D01*
X864240Y917700D01*
X863715Y916800D01*
X862770Y916350D01*
X860250D01*
G01X873050Y912600D02*
X868850D01*
Y921600D01*
X873050D01*
G01X871370Y917250D02*
X868850D01*
G01X877450Y912600D02*
Y921600D01*
X880075D01*
X880915Y921150D01*
X881440Y920550D01*
X881650Y919350D01*
X881440Y918150D01*
X880810Y917400D01*
X880075Y916950D01*
X877450D01*
G01X880075D02*
X881650Y912600D01*
G01X670840Y937600D02*
Y946600D01*
X672940D01*
X673780Y946150D01*
X674410Y945550D01*
X674935Y944650D01*
X675355Y943600D01*
X675460Y942100D01*
X675355Y940600D01*
X674935Y939550D01*
X674410Y938650D01*
X673780Y938050D01*
X672940Y937600D01*
X670840D01*
G01X680490Y946600D02*
X683010D01*
G01X681750D02*
Y937600D01*
G01X680490D02*
X683010D01*
G01X692450D02*
X688250D01*
Y946600D01*
X692450D01*
G01X690770Y942250D02*
X688250D01*
G01X696850Y946600D02*
Y937600D01*
X701050D01*
G01X709650D02*
X705450D01*
Y946600D01*
X709650D01*
G01X707970Y942250D02*
X705450D01*
G01X718460Y945850D02*
X717830Y946300D01*
X717095Y946600D01*
X716255D01*
X715310Y946150D01*
X714575Y945400D01*
X714050Y944500D01*
X713630Y943000D01*
X713525Y941650D01*
X713735Y940300D01*
X714050Y939400D01*
X714680Y938500D01*
X715415Y937900D01*
X716150Y937600D01*
X716885D01*
X717620Y937900D01*
X718250Y938350D01*
X718775Y938950D01*
G01X724750Y946600D02*
Y937600D01*
G01X722335Y946600D02*
X727165D01*
G01X731250Y937600D02*
Y946600D01*
X733875D01*
X734715Y946150D01*
X735240Y945550D01*
X735450Y944350D01*
X735240Y943150D01*
X734610Y942400D01*
X733875Y941950D01*
X731250D01*
G01X733875D02*
X735450Y937600D01*
G01X740690Y946600D02*
X743210D01*
G01X741950D02*
Y937600D01*
G01X740690D02*
X743210D01*
G01X752860Y945850D02*
X752230Y946300D01*
X751495Y946600D01*
X750655D01*
X749710Y946150D01*
X748975Y945400D01*
X748450Y944500D01*
X748030Y943000D01*
X747925Y941650D01*
X748135Y940300D01*
X748450Y939400D01*
X749080Y938500D01*
X749815Y937900D01*
X750550Y937600D01*
X751285D01*
X752020Y937900D01*
X752650Y938350D01*
X753175Y938950D01*
G01X671050Y971600D02*
Y962600D01*
X675250D01*
G01X679755Y970100D02*
X680385Y971000D01*
X681120Y971450D01*
X681960Y971600D01*
X683010Y971300D01*
X683745Y970550D01*
X683955Y969650D01*
X683850Y968750D01*
X683430Y968000D01*
X681330Y966500D01*
X680385Y965450D01*
X679755Y963950D01*
X679545Y962600D01*
X683955D01*
G01X699580Y967100D02*
X701680D01*
Y964400D01*
X701050Y963500D01*
X700315Y962900D01*
X699265Y962600D01*
X698215Y962900D01*
X697480Y963500D01*
X696850Y964400D01*
X696430Y965450D01*
X696220Y966650D01*
Y967700D01*
X696430Y968600D01*
X696850Y969650D01*
X697480Y970550D01*
X698110Y971150D01*
X698950Y971600D01*
X699685D01*
X700525Y971300D01*
X701155Y970700D01*
G01X705450Y962600D02*
Y971600D01*
X708075D01*
X708915Y971150D01*
X709440Y970550D01*
X709650Y969350D01*
X709440Y968150D01*
X708810Y967400D01*
X708075Y966950D01*
X705450D01*
G01X708075D02*
X709650Y962600D01*
G01X716150D02*
X715310Y962750D01*
X714575Y963350D01*
X713945Y964250D01*
X713525Y965300D01*
X713315Y966500D01*
Y967700D01*
X713525Y968900D01*
X713945Y969950D01*
X714575Y970850D01*
X715310Y971450D01*
X716150Y971600D01*
X716990Y971450D01*
X717725Y970850D01*
X718355Y969950D01*
X718775Y968900D01*
X718985Y967700D01*
Y966500D01*
X718775Y965300D01*
X718355Y964250D01*
X717725Y963350D01*
X716990Y962750D01*
X716150Y962600D01*
G01X722440Y971600D02*
Y965150D01*
X722860Y963800D01*
X723700Y962900D01*
X724750Y962600D01*
X725800Y962900D01*
X726640Y963800D01*
X727060Y965150D01*
Y971600D01*
G01X730935Y962600D02*
Y971600D01*
X735765Y962600D01*
Y971600D01*
G01X739640Y962600D02*
Y971600D01*
X741740D01*
X742580Y971150D01*
X743210Y970550D01*
X743735Y969650D01*
X744155Y968600D01*
X744260Y967100D01*
X744155Y965600D01*
X743735Y964550D01*
X743210Y963650D01*
X742580Y963050D01*
X741740Y962600D01*
X739640D01*
G01X750340Y960950D02*
X750760Y962900D01*
G01X767750Y962600D02*
Y971600D01*
X766490Y969800D01*
G01Y962600D02*
X769010D01*
G01X784950D02*
X784110Y962750D01*
X783375Y963350D01*
X782745Y964250D01*
X782325Y965300D01*
X782115Y966500D01*
Y967700D01*
X782325Y968900D01*
X782745Y969950D01*
X783375Y970850D01*
X784110Y971450D01*
X784950Y971600D01*
X785790Y971450D01*
X786525Y970850D01*
X787155Y969950D01*
X787575Y968900D01*
X787785Y967700D01*
Y966500D01*
X787575Y965300D01*
X787155Y964250D01*
X786525Y963350D01*
X785790Y962750D01*
X784950Y962600D01*
G01X791240Y971600D02*
Y965150D01*
X791660Y963800D01*
X792500Y962900D01*
X793550Y962600D01*
X794600Y962900D01*
X795440Y963800D01*
X795860Y965150D01*
Y971600D01*
G01X799735Y962600D02*
Y971600D01*
X804565Y962600D01*
Y971600D01*
G01X813060Y970850D02*
X812430Y971300D01*
X811695Y971600D01*
X810855D01*
X809910Y971150D01*
X809175Y970400D01*
X808650Y969500D01*
X808230Y968000D01*
X808125Y966650D01*
X808335Y965300D01*
X808650Y964400D01*
X809280Y963500D01*
X810015Y962900D01*
X810750Y962600D01*
X811485D01*
X812220Y962900D01*
X812850Y963350D01*
X813375Y963950D01*
G01X821450Y962600D02*
X817250D01*
Y971600D01*
X821450D01*
G01X819770Y967250D02*
X817250D01*
G01X838860Y970850D02*
X838230Y971300D01*
X837495Y971600D01*
X836655D01*
X835710Y971150D01*
X834975Y970400D01*
X834450Y969500D01*
X834030Y968000D01*
X833925Y966650D01*
X834135Y965300D01*
X834450Y964400D01*
X835080Y963500D01*
X835815Y962900D01*
X836550Y962600D01*
X837285D01*
X838020Y962900D01*
X838650Y963350D01*
X839175Y963950D01*
G01X845150Y962600D02*
X844310Y962750D01*
X843575Y963350D01*
X842945Y964250D01*
X842525Y965300D01*
X842315Y966500D01*
Y967700D01*
X842525Y968900D01*
X842945Y969950D01*
X843575Y970850D01*
X844310Y971450D01*
X845150Y971600D01*
X845990Y971450D01*
X846725Y970850D01*
X847355Y969950D01*
X847775Y968900D01*
X847985Y967700D01*
Y966500D01*
X847775Y965300D01*
X847355Y964250D01*
X846725Y963350D01*
X845990Y962750D01*
X845150Y962600D01*
G01X851650D02*
Y971600D01*
X854170D01*
X855010Y971150D01*
X855640Y970100D01*
X855850Y968900D01*
X855640Y967700D01*
X855115Y966800D01*
X854170Y966350D01*
X851650D01*
G01X860250Y962600D02*
Y971600D01*
X862770D01*
X863610Y971150D01*
X864240Y970100D01*
X864450Y968900D01*
X864240Y967700D01*
X863715Y966800D01*
X862770Y966350D01*
X860250D01*
G01X873050Y962600D02*
X868850D01*
Y971600D01*
X873050D01*
G01X871370Y967250D02*
X868850D01*
G01X877450Y962600D02*
Y971600D01*
X880075D01*
X880915Y971150D01*
X881440Y970550D01*
X881650Y969350D01*
X881440Y968150D01*
X880810Y967400D01*
X880075Y966950D01*
X877450D01*
G01X880075D02*
X881650Y962600D01*
G01X670840Y987600D02*
Y996600D01*
X672940D01*
X673780Y996150D01*
X674410Y995550D01*
X674935Y994650D01*
X675355Y993600D01*
X675460Y992100D01*
X675355Y990600D01*
X674935Y989550D01*
X674410Y988650D01*
X673780Y988050D01*
X672940Y987600D01*
X670840D01*
G01X680490Y996600D02*
X683010D01*
G01X681750D02*
Y987600D01*
G01X680490D02*
X683010D01*
G01X692450D02*
X688250D01*
Y996600D01*
X692450D01*
G01X690770Y992250D02*
X688250D01*
G01X696850Y996600D02*
Y987600D01*
X701050D01*
G01X709650D02*
X705450D01*
Y996600D01*
X709650D01*
G01X707970Y992250D02*
X705450D01*
G01X718460Y995850D02*
X717830Y996300D01*
X717095Y996600D01*
X716255D01*
X715310Y996150D01*
X714575Y995400D01*
X714050Y994500D01*
X713630Y993000D01*
X713525Y991650D01*
X713735Y990300D01*
X714050Y989400D01*
X714680Y988500D01*
X715415Y987900D01*
X716150Y987600D01*
X716885D01*
X717620Y987900D01*
X718250Y988350D01*
X718775Y988950D01*
G01X724750Y996600D02*
Y987600D01*
G01X722335Y996600D02*
X727165D01*
G01X731250Y987600D02*
Y996600D01*
X733875D01*
X734715Y996150D01*
X735240Y995550D01*
X735450Y994350D01*
X735240Y993150D01*
X734610Y992400D01*
X733875Y991950D01*
X731250D01*
G01X733875D02*
X735450Y987600D01*
G01X740690Y996600D02*
X743210D01*
G01X741950D02*
Y987600D01*
G01X740690D02*
X743210D01*
G01X752860Y995850D02*
X752230Y996300D01*
X751495Y996600D01*
X750655D01*
X749710Y996150D01*
X748975Y995400D01*
X748450Y994500D01*
X748030Y993000D01*
X747925Y991650D01*
X748135Y990300D01*
X748450Y989400D01*
X749080Y988500D01*
X749815Y987900D01*
X750550Y987600D01*
X751285D01*
X752020Y987900D01*
X752650Y988350D01*
X753175Y988950D01*
G01X671050Y1021600D02*
Y1012600D01*
X675250D01*
G01X681750D02*
Y1021600D01*
X680490Y1019800D01*
G01Y1012600D02*
X683010D01*
G01X696745Y1013800D02*
X697585Y1013050D01*
X698530Y1012600D01*
X699370D01*
X700210Y1013050D01*
X700840Y1013800D01*
X701155Y1014850D01*
X700945Y1015900D01*
X700420Y1016800D01*
X699475Y1017400D01*
X698215Y1017700D01*
X697480Y1018300D01*
X697165Y1019350D01*
X697375Y1020400D01*
X697900Y1021150D01*
X698635Y1021600D01*
X699370D01*
X700105Y1021300D01*
X700735Y1020550D01*
G01X706290Y1021600D02*
X708810D01*
G01X707550D02*
Y1012600D01*
G01X706290D02*
X708810D01*
G01X716780Y1017100D02*
X718880D01*
Y1014400D01*
X718250Y1013500D01*
X717515Y1012900D01*
X716465Y1012600D01*
X715415Y1012900D01*
X714680Y1013500D01*
X714050Y1014400D01*
X713630Y1015450D01*
X713420Y1016650D01*
Y1017700D01*
X713630Y1018600D01*
X714050Y1019650D01*
X714680Y1020550D01*
X715310Y1021150D01*
X716150Y1021600D01*
X716885D01*
X717725Y1021300D01*
X718355Y1020700D01*
G01X722335Y1012600D02*
Y1021600D01*
X727165Y1012600D01*
Y1021600D01*
G01X730725Y1012600D02*
X733350Y1021600D01*
X735975Y1012600D01*
G01X735030Y1015750D02*
X731670D01*
G01X739850Y1021600D02*
Y1012600D01*
X744050D01*
G01X750340Y1010950D02*
X750760Y1012900D01*
G01X767750Y1012300D02*
X767540Y1012450D01*
Y1012750D01*
X767750Y1012900D01*
X767960Y1012750D01*
Y1012450D01*
X767750Y1012300D01*
G01X774040Y1014400D02*
X774670Y1013350D01*
X775510Y1012750D01*
X776455Y1012600D01*
X777295Y1012750D01*
X778135Y1013500D01*
X778660Y1014400D01*
X778765Y1015300D01*
X778555Y1016350D01*
X777820Y1017100D01*
X777085Y1017400D01*
X776140D01*
G01X777085D02*
X777715Y1017850D01*
X778240Y1018600D01*
X778450Y1019500D01*
X778240Y1020400D01*
X777715Y1021150D01*
X776770Y1021600D01*
X775825Y1021450D01*
X774880Y1020850D01*
G01X784950Y1012600D02*
X785685Y1012750D01*
X786525Y1013200D01*
X787050Y1013950D01*
X787260Y1015000D01*
X787050Y1016050D01*
X786420Y1016950D01*
X785475Y1017400D01*
X784425D01*
X783795Y1017700D01*
X783270Y1018450D01*
X783060Y1019500D01*
X783375Y1020550D01*
X784110Y1021300D01*
X784950Y1021600D01*
X785790Y1021300D01*
X786525Y1020550D01*
X786840Y1019500D01*
X786630Y1018450D01*
X786105Y1017700D01*
X785475Y1017400D01*
X784425D01*
X783480Y1016950D01*
X782850Y1016050D01*
X782640Y1015000D01*
X782850Y1013950D01*
X783375Y1013200D01*
X784215Y1012750D01*
X784950Y1012600D01*
G01X802150D02*
X801310Y1012750D01*
X800575Y1013350D01*
X799945Y1014250D01*
X799525Y1015300D01*
X799315Y1016500D01*
Y1017700D01*
X799525Y1018900D01*
X799945Y1019950D01*
X800575Y1020850D01*
X801310Y1021450D01*
X802150Y1021600D01*
X802990Y1021450D01*
X803725Y1020850D01*
X804355Y1019950D01*
X804775Y1018900D01*
X804985Y1017700D01*
Y1016500D01*
X804775Y1015300D01*
X804355Y1014250D01*
X803725Y1013350D01*
X802990Y1012750D01*
X802150Y1012600D01*
G01X808440Y1021600D02*
Y1015150D01*
X808860Y1013800D01*
X809700Y1012900D01*
X810750Y1012600D01*
X811800Y1012900D01*
X812640Y1013800D01*
X813060Y1015150D01*
Y1021600D01*
G01X816935Y1012600D02*
Y1021600D01*
X821765Y1012600D01*
Y1021600D01*
G01X830260Y1020850D02*
X829630Y1021300D01*
X828895Y1021600D01*
X828055D01*
X827110Y1021150D01*
X826375Y1020400D01*
X825850Y1019500D01*
X825430Y1018000D01*
X825325Y1016650D01*
X825535Y1015300D01*
X825850Y1014400D01*
X826480Y1013500D01*
X827215Y1012900D01*
X827950Y1012600D01*
X828685D01*
X829420Y1012900D01*
X830050Y1013350D01*
X830575Y1013950D01*
G01X838650Y1012600D02*
X834450D01*
Y1021600D01*
X838650D01*
G01X836970Y1017250D02*
X834450D01*
G01X856060Y1020850D02*
X855430Y1021300D01*
X854695Y1021600D01*
X853855D01*
X852910Y1021150D01*
X852175Y1020400D01*
X851650Y1019500D01*
X851230Y1018000D01*
X851125Y1016650D01*
X851335Y1015300D01*
X851650Y1014400D01*
X852280Y1013500D01*
X853015Y1012900D01*
X853750Y1012600D01*
X854485D01*
X855220Y1012900D01*
X855850Y1013350D01*
X856375Y1013950D01*
G01X862350Y1012600D02*
X861510Y1012750D01*
X860775Y1013350D01*
X860145Y1014250D01*
X859725Y1015300D01*
X859515Y1016500D01*
Y1017700D01*
X859725Y1018900D01*
X860145Y1019950D01*
X860775Y1020850D01*
X861510Y1021450D01*
X862350Y1021600D01*
X863190Y1021450D01*
X863925Y1020850D01*
X864555Y1019950D01*
X864975Y1018900D01*
X865185Y1017700D01*
Y1016500D01*
X864975Y1015300D01*
X864555Y1014250D01*
X863925Y1013350D01*
X863190Y1012750D01*
X862350Y1012600D01*
G01X868850D02*
Y1021600D01*
X871370D01*
X872210Y1021150D01*
X872840Y1020100D01*
X873050Y1018900D01*
X872840Y1017700D01*
X872315Y1016800D01*
X871370Y1016350D01*
X868850D01*
G01X877450Y1012600D02*
Y1021600D01*
X879970D01*
X880810Y1021150D01*
X881440Y1020100D01*
X881650Y1018900D01*
X881440Y1017700D01*
X880915Y1016800D01*
X879970Y1016350D01*
X877450D01*
G01X890250Y1012600D02*
X886050D01*
Y1021600D01*
X890250D01*
G01X888570Y1017250D02*
X886050D01*
G01X894650Y1012600D02*
Y1021600D01*
X897275D01*
X898115Y1021150D01*
X898640Y1020550D01*
X898850Y1019350D01*
X898640Y1018150D01*
X898010Y1017400D01*
X897275Y1016950D01*
X894650D01*
G01X897275D02*
X898850Y1012600D01*
G01X911745Y1013800D02*
X912585Y1013050D01*
X913530Y1012600D01*
X914370D01*
X915210Y1013050D01*
X915840Y1013800D01*
X916155Y1014850D01*
X915945Y1015900D01*
X915420Y1016800D01*
X914475Y1017400D01*
X913215Y1017700D01*
X912480Y1018300D01*
X912165Y1019350D01*
X912375Y1020400D01*
X912900Y1021150D01*
X913635Y1021600D01*
X914370D01*
X915105Y1021300D01*
X915735Y1020550D01*
G01X922550Y1021600D02*
Y1012600D01*
G01X920135Y1021600D02*
X924965D01*
G01X928525Y1012600D02*
X931150Y1021600D01*
X933775Y1012600D01*
G01X932830Y1015750D02*
X929470D01*
G01X937650Y1012600D02*
Y1021600D01*
X940275D01*
X941115Y1021150D01*
X941640Y1020550D01*
X941850Y1019350D01*
X941640Y1018150D01*
X941010Y1017400D01*
X940275Y1016950D01*
X937650D01*
G01X940275D02*
X941850Y1012600D01*
G01X948350Y1021600D02*
Y1012600D01*
G01X945935Y1021600D02*
X950765D01*
G01X671095Y1035100D02*
X671935Y1034350D01*
X672880Y1033900D01*
X673720D01*
X674560Y1034350D01*
X675190Y1035100D01*
X675505Y1036150D01*
X675295Y1037200D01*
X674770Y1038100D01*
X673825Y1038700D01*
X672565Y1039000D01*
X671830Y1039600D01*
X671515Y1040650D01*
X671725Y1041700D01*
X672250Y1042450D01*
X672985Y1042900D01*
X673720D01*
X674455Y1042600D01*
X675085Y1041850D01*
G01X681900Y1033900D02*
X681060Y1034050D01*
X680325Y1034650D01*
X679695Y1035550D01*
X679275Y1036600D01*
X679065Y1037800D01*
Y1039000D01*
X679275Y1040200D01*
X679695Y1041250D01*
X680325Y1042150D01*
X681060Y1042750D01*
X681900Y1042900D01*
X682740Y1042750D01*
X683475Y1042150D01*
X684105Y1041250D01*
X684525Y1040200D01*
X684735Y1039000D01*
Y1037800D01*
X684525Y1036600D01*
X684105Y1035550D01*
X683475Y1034650D01*
X682740Y1034050D01*
X681900Y1033900D01*
G01X688400Y1042900D02*
Y1033900D01*
X692600D01*
G01X696790D02*
Y1042900D01*
X698890D01*
X699730Y1042450D01*
X700360Y1041850D01*
X700885Y1040950D01*
X701305Y1039900D01*
X701410Y1038400D01*
X701305Y1036900D01*
X700885Y1035850D01*
X700360Y1034950D01*
X699730Y1034350D01*
X698890Y1033900D01*
X696790D01*
G01X709800D02*
X705600D01*
Y1042900D01*
X709800D01*
G01X708120Y1038550D02*
X705600D01*
G01X714200Y1033900D02*
Y1042900D01*
X716825D01*
X717665Y1042450D01*
X718190Y1041850D01*
X718400Y1040650D01*
X718190Y1039450D01*
X717560Y1038700D01*
X716825Y1038250D01*
X714200D01*
G01X716825D02*
X718400Y1033900D01*
G01X722170D02*
Y1042900D01*
X724900Y1035400D01*
X727630Y1042900D01*
Y1033900D01*
G01X730875D02*
X733500Y1042900D01*
X736125Y1033900D01*
G01X735180Y1037050D02*
X731820D01*
G01X739895Y1035100D02*
X740735Y1034350D01*
X741680Y1033900D01*
X742520D01*
X743360Y1034350D01*
X743990Y1035100D01*
X744305Y1036150D01*
X744095Y1037200D01*
X743570Y1038100D01*
X742625Y1038700D01*
X741365Y1039000D01*
X740630Y1039600D01*
X740315Y1040650D01*
X740525Y1041700D01*
X741050Y1042450D01*
X741785Y1042900D01*
X742520D01*
X743255Y1042600D01*
X743885Y1041850D01*
G01X748390Y1033900D02*
Y1042900D01*
G01X752380D02*
X748390Y1037350D01*
G01X753010Y1033900D02*
X750175Y1039900D01*
G54D32*
G01X-1125828Y655212D02*
X-1125078Y652412D01*
G01D02*
X-1124078Y650311D01*
G01D02*
X-1122578Y648562D01*
G01D02*
X-1120578Y647862D01*
G01D02*
X-1118578Y648562D01*
G01X-1120578Y668862D02*
X-1122578Y668162D01*
G01D02*
X-1124078Y666412D01*
G01D02*
X-1125078Y664312D01*
G01D02*
X-1125828Y661512D01*
G01D02*
X-1126078Y658362D01*
G01D02*
X-1125828Y655212D01*
G01X-1118578Y668162D02*
X-1120578Y668862D01*
G01X-1106353Y608311D02*
X-1107853Y606562D01*
G01D02*
X-1109603Y605862D01*
G01D02*
X-1111603Y606562D01*
G01D02*
X-1113353Y608661D01*
G01X-1114603Y614611D02*
X-1112853Y617062D01*
G01D02*
X-1111353Y618462D01*
G01D02*
X-1109353Y619162D01*
G01D02*
X-1107603Y618462D01*
G01D02*
X-1106353Y617062D01*
G01D02*
X-1105353Y614962D01*
G01D02*
X-1105103Y612512D01*
G01D02*
X-1105353Y610412D01*
G01D02*
X-1106353Y608311D01*
G01X-1113353Y608661D02*
X-1114353Y611812D01*
G01D02*
X-1114603Y615312D01*
G01D02*
X-1114103Y619862D01*
G01D02*
X-1113353Y622312D01*
G01D02*
X-1112103Y624762D01*
G01D02*
X-1110353Y626512D01*
G01D02*
X-1108603Y626862D01*
G01D02*
X-1106853Y626162D01*
G01D02*
X-1105603Y624412D01*
G01X-1118578Y648562D02*
X-1117078Y650311D01*
G01D02*
X-1116078Y652412D01*
G01D02*
X-1115328Y655212D01*
G01D02*
X-1115078Y658362D01*
G01D02*
X-1115328Y661512D01*
G01D02*
X-1116078Y664312D01*
G01D02*
X-1117078Y666412D01*
G01D02*
X-1118578Y668162D01*
G01X-1089453Y605162D02*
X-1089953Y605512D01*
G01D02*
Y606212D01*
G01D02*
X-1089453Y606562D01*
G01D02*
X-1088953Y606212D01*
G01D02*
Y605512D01*
G01D02*
X-1089453Y605162D01*
G01X-1100178Y647162D02*
X-1100678Y647512D01*
G01D02*
Y648212D01*
G01D02*
X-1100178Y648562D01*
G01D02*
X-1099678Y648212D01*
G01D02*
Y647512D01*
G01D02*
X-1100178Y647162D01*
G01X-1072553Y624412D02*
X-1073553Y622312D01*
G01D02*
X-1074303Y619512D01*
G01D02*
X-1074553Y616362D01*
G01D02*
X-1074303Y613212D01*
G01D02*
X-1073553Y610412D01*
G01D02*
X-1072553Y608311D01*
G01D02*
X-1071053Y606562D01*
G01Y626162D02*
X-1072553Y624412D01*
G01X-1080778Y656962D02*
X-1083028Y654512D01*
G01D02*
X-1084528Y651011D01*
G01D02*
X-1085028Y647862D01*
G01D02*
X-1074528D01*
G01X-1084528Y665362D02*
X-1083028Y667462D01*
G01D02*
X-1081278Y668512D01*
G01D02*
X-1079278Y668862D01*
G01D02*
X-1076778Y668162D01*
G01D02*
X-1075028Y666412D01*
G01D02*
X-1074528Y664312D01*
G01D02*
X-1074778Y662212D01*
G01D02*
X-1075778Y660462D01*
G01D02*
X-1080778Y656962D01*
G01X-1071053Y606562D02*
X-1069053Y605862D01*
G01D02*
X-1067053Y606562D01*
G01D02*
X-1065553Y608311D01*
G01D02*
X-1064553Y610412D01*
G01D02*
X-1063803Y613212D01*
G01D02*
X-1063553Y616362D01*
G01D02*
X-1063803Y619512D01*
G01D02*
X-1064553Y622312D01*
G01D02*
X-1065553Y624412D01*
G01X-1069053Y626862D02*
X-1071053Y626162D01*
G01X-1065553Y624412D02*
X-1067053Y626162D01*
G01D02*
X-1069053Y626862D01*
G01X-1064878Y652062D02*
X-1063378Y649612D01*
G01D02*
X-1061378Y648212D01*
G01D02*
X-1059128Y647862D01*
G01D02*
X-1057128Y648212D01*
G01D02*
X-1055128Y649962D01*
G01X-1055878Y658362D02*
X-1057628Y659062D01*
G01D02*
X-1059878D01*
G01X-1057628D02*
X-1056128Y660112D01*
G01Y667812D02*
X-1058378Y668862D01*
G01D02*
X-1060628Y668512D01*
G01D02*
X-1062878Y667112D01*
G01X-1052153Y608311D02*
X-1050653Y606562D01*
G01D02*
X-1048653Y605862D01*
G01D02*
X-1046653Y606562D01*
G01D02*
X-1045153Y608311D01*
G01X-1052153Y624412D02*
X-1053153Y622312D01*
G01D02*
X-1053903Y619512D01*
G01D02*
X-1054153Y616362D01*
G01D02*
X-1053903Y613212D01*
G01D02*
X-1053153Y610412D01*
G01D02*
X-1052153Y608311D01*
G01X-1045153D02*
X-1044153Y610412D01*
G01D02*
X-1043403Y613212D01*
G01D02*
X-1043153Y616362D01*
G01D02*
X-1043403Y619512D01*
G01D02*
X-1044153Y622312D01*
G01D02*
X-1045153Y624412D01*
G01X-1048653Y626862D02*
X-1050653Y626162D01*
G01D02*
X-1052153Y624412D01*
G01X-1045153D02*
X-1046653Y626162D01*
G01D02*
X-1048653Y626862D01*
G01X-1055128Y649962D02*
X-1053878Y652062D01*
G01D02*
X-1053628Y654162D01*
G01D02*
X-1054128Y656611D01*
G01X-1038728Y647862D02*
X-1040728Y648562D01*
G01D02*
X-1042478Y650661D01*
G01D02*
X-1043478Y653812D01*
G01D02*
X-1043728Y657312D01*
G01X-1054128Y656611D02*
X-1055878Y658362D01*
G01X-1056128Y660112D02*
X-1054878Y661862D01*
G01D02*
X-1054378Y663962D01*
G01D02*
X-1054878Y666062D01*
G01D02*
X-1056128Y667812D01*
G01X-1043728Y656611D02*
X-1041978Y659062D01*
G01D02*
X-1040478Y660462D01*
G01X-1043728Y657312D02*
X-1043228Y661862D01*
G01D02*
X-1042478Y664312D01*
G01D02*
X-1041228Y666762D01*
G01D02*
X-1039478Y668512D01*
G01X-1034478Y656962D02*
X-1034228Y654512D01*
G01D02*
X-1034478Y652412D01*
G01D02*
X-1035478Y650311D01*
G01D02*
X-1036978Y648562D01*
G01D02*
X-1038728Y647862D01*
G01X-1040478Y660462D02*
X-1038478Y661162D01*
G01D02*
X-1036728Y660462D01*
G01D02*
X-1035478Y659062D01*
G01D02*
X-1034478Y656962D01*
G01X-1039478Y668512D02*
X-1037728Y668862D01*
G01D02*
X-1035978Y668162D01*
G01D02*
X-1034728Y666412D01*
G01X-815953Y646362D02*
X-814453Y643912D01*
G01D02*
X-812453Y642512D01*
G01D02*
X-810203Y642162D01*
G01D02*
X-808203Y642512D01*
G01D02*
X-806203Y644262D01*
G01D02*
X-804953Y646362D01*
G01D02*
X-804703Y648462D01*
G01D02*
X-805203Y650911D01*
G01D02*
X-806953Y652662D01*
G01D02*
X-808703Y653362D01*
G01D02*
X-810953D01*
G01X-808703D02*
X-807203Y654412D01*
G01D02*
X-805953Y656162D01*
G01D02*
X-805453Y658262D01*
G01D02*
X-805953Y660362D01*
G01D02*
X-807203Y662112D01*
G01D02*
X-809453Y663162D01*
G01D02*
X-811703Y662812D01*
G01D02*
X-813953Y661412D01*
G01X-811478Y686611D02*
X-809978Y684862D01*
G01D02*
X-807978Y684162D01*
G01D02*
X-805978Y684862D01*
G01D02*
X-804478Y686611D01*
G01X-811478Y702712D02*
X-812478Y700612D01*
G01D02*
X-813228Y697812D01*
G01D02*
X-813478Y694662D01*
G01D02*
X-813228Y691512D01*
G01D02*
X-812478Y688712D01*
G01D02*
X-811478Y686611D01*
G01X-804478D02*
X-803478Y688712D01*
G01X-807978Y705162D02*
X-809978Y704462D01*
G01D02*
X-811478Y702712D01*
G01X-803478Y700612D02*
X-804478Y702712D01*
G01D02*
X-805978Y704462D01*
G01D02*
X-807978Y705162D01*
G01X-802753Y920611D02*
X-804253Y918862D01*
G01D02*
X-806003Y918162D01*
G01D02*
X-808003Y918862D01*
G01D02*
X-809753Y920961D01*
G01D02*
X-810753Y924112D01*
G01X-811003Y926911D02*
X-809253Y929362D01*
G01D02*
X-807753Y930762D01*
G01D02*
X-805753Y931462D01*
G01D02*
X-804003Y930762D01*
G01X-810753Y924112D02*
X-811003Y927612D01*
G01D02*
X-810503Y932162D01*
G01D02*
X-809753Y934612D01*
G01D02*
X-808503Y937062D01*
G01D02*
X-806753Y938812D01*
G01D02*
X-805003Y939162D01*
G01D02*
X-803253Y938462D01*
G01X-809278Y970662D02*
X-809028Y967512D01*
G01D02*
X-808278Y964712D01*
G01D02*
X-807278Y962611D01*
G01D02*
X-805778Y960862D01*
G01D02*
X-803778Y960162D01*
G01Y981162D02*
X-805778Y980462D01*
G01D02*
X-807278Y978712D01*
G01D02*
X-808278Y976612D01*
G01D02*
X-809028Y973812D01*
G01D02*
X-809278Y970662D01*
G01X-790053Y641462D02*
X-790553Y641812D01*
G01D02*
Y642512D01*
G01D02*
X-790053Y642862D01*
G01D02*
X-789553Y642512D01*
G01D02*
Y641812D01*
G01D02*
X-790053Y641462D01*
G01X-803478Y688712D02*
X-802728Y691512D01*
G01D02*
X-802478Y694662D01*
G01D02*
X-802728Y697812D01*
G01D02*
X-803478Y700612D01*
G01X-801753Y922712D02*
X-802753Y920611D01*
G01X-804003Y930762D02*
X-802753Y929362D01*
G01D02*
X-801753Y927262D01*
G01D02*
X-801503Y924812D01*
G01D02*
X-801753Y922712D01*
G01X-803253Y938462D02*
X-802003Y936712D01*
G01X-803778Y960162D02*
X-801778Y960862D01*
G01D02*
X-800278Y962611D01*
G01D02*
X-799278Y964712D01*
G01D02*
X-798528Y967512D01*
G01D02*
X-798278Y970662D01*
G01D02*
X-798528Y973812D01*
G01D02*
X-799278Y976612D01*
G01D02*
X-800278Y978712D01*
G01D02*
X-801778Y980462D01*
G01D02*
X-803778Y981162D01*
G01X-766653Y663162D02*
X-775903Y648112D01*
G01D02*
X-763403D01*
G01X-787578Y683462D02*
X-788078Y683812D01*
G01D02*
Y684512D01*
G01D02*
X-787578Y684862D01*
G01D02*
X-787078Y684512D01*
G01D02*
Y683812D01*
G01D02*
X-787578Y683462D01*
G01X-785853Y917462D02*
X-786353Y917812D01*
G01D02*
Y918512D01*
G01D02*
X-785853Y918862D01*
G01D02*
X-785353Y918512D01*
G01D02*
Y917812D01*
G01D02*
X-785853Y917462D01*
G01X-783378Y959462D02*
X-783878Y959812D01*
G01D02*
Y960512D01*
G01D02*
X-783378Y960862D01*
G01D02*
X-782878Y960512D01*
G01D02*
Y959812D01*
G01D02*
X-783378Y959462D01*
G01X-766653Y642162D02*
Y663162D01*
G01X-767178Y684162D02*
Y705162D01*
G01X-770178Y684162D02*
X-764178D01*
G01X-767178Y705162D02*
X-770178Y700962D01*
G01X-769953Y922712D02*
X-768953Y920611D01*
G01D02*
X-767453Y918862D01*
G01D02*
X-765453Y918162D01*
G01D02*
X-763453Y918862D01*
G01D02*
X-761953Y920611D01*
G01D02*
X-760953Y922712D01*
G01X-767453Y938462D02*
X-768953Y936712D01*
G01D02*
X-769953Y934612D01*
G01D02*
X-770703Y931812D01*
G01D02*
X-770953Y928662D01*
G01D02*
X-770703Y925512D01*
G01D02*
X-769953Y922712D01*
G01X-760953D02*
X-760203Y925512D01*
G01D02*
X-759953Y928662D01*
G01D02*
X-760203Y931812D01*
G01D02*
X-760953Y934612D01*
G01D02*
X-761953Y936712D01*
G01D02*
X-763453Y938462D01*
G01X-765453Y939162D02*
X-767453Y938462D01*
G01X-763453D02*
X-765453Y939162D01*
G01X-758978Y972762D02*
X-763978Y969262D01*
G01D02*
X-766228Y966812D01*
G01D02*
X-767728Y963311D01*
G01D02*
X-768228Y960162D01*
G01D02*
X-757728D01*
G01X-767728Y977662D02*
X-766228Y979762D01*
G01D02*
X-764478Y980812D01*
G01D02*
X-762478Y981162D01*
G01D02*
X-759978Y980462D01*
G01D02*
X-758228Y978712D01*
G01D02*
X-757728Y976612D01*
G01D02*
X-757978Y974512D01*
G01D02*
X-758978Y972762D01*
G01X-754503Y655812D02*
X-754753Y652662D01*
G01D02*
X-754503Y649512D01*
G01D02*
X-753753Y646712D01*
G01D02*
X-752753Y644611D01*
G01D02*
X-751253Y642862D01*
G01D02*
X-749253Y642162D01*
G01D02*
X-747253Y642862D01*
G01D02*
X-745753Y644611D01*
G01D02*
X-744753Y646712D01*
G01D02*
X-744003Y649512D01*
G01D02*
X-743753Y652662D01*
G01D02*
X-744003Y655812D01*
G01X-749253Y663162D02*
X-751253Y662462D01*
G01D02*
X-752753Y660712D01*
G01D02*
X-753753Y658612D01*
G01D02*
X-754503Y655812D01*
G01X-744003D02*
X-744753Y658612D01*
G01D02*
X-745753Y660712D01*
G01D02*
X-747253Y662462D01*
G01D02*
X-749253Y663162D01*
G01X-752278Y688362D02*
X-750778Y685912D01*
G01D02*
X-748778Y684512D01*
G01D02*
X-746528Y684162D01*
G01D02*
X-744528Y684512D01*
G01D02*
X-742528Y686262D01*
G01D02*
X-741278Y688362D01*
G01X-741028Y690462D02*
X-741528Y692911D01*
G01D02*
X-743278Y694662D01*
G01D02*
X-745028Y695362D01*
G01D02*
X-747278D01*
G01X-745028D02*
X-743528Y696412D01*
G01D02*
X-742278Y698162D01*
G01D02*
X-741778Y700262D01*
G01D02*
X-742278Y702362D01*
G01D02*
X-743528Y704112D01*
G01D02*
X-745778Y705162D01*
G01D02*
X-748028Y704812D01*
G01D02*
X-750278Y703412D01*
G01X-749553Y922712D02*
X-748553Y920611D01*
G01D02*
X-747053Y918862D01*
G01D02*
X-745053Y918162D01*
G01D02*
X-743053Y918862D01*
G01D02*
X-741553Y920611D01*
G01D02*
X-740553Y922712D01*
G01X-747053Y938462D02*
X-748553Y936712D01*
G01D02*
X-749553Y934612D01*
G01D02*
X-750303Y931812D01*
G01D02*
X-750553Y928662D01*
G01D02*
X-750303Y925512D01*
G01D02*
X-749553Y922712D01*
G01X-740553Y934612D02*
X-741553Y936712D01*
G01D02*
X-743053Y938462D01*
G01X-745053Y939162D02*
X-747053Y938462D01*
G01X-743053D02*
X-745053Y939162D01*
G01X-748078Y964362D02*
X-746578Y961912D01*
G01D02*
X-744578Y960512D01*
G01D02*
X-742328Y960162D01*
G01D02*
X-740328Y960512D01*
G01X-740828Y971362D02*
X-743078D01*
G01X-739328Y980112D02*
X-741578Y981162D01*
G01D02*
X-743828Y980812D01*
G01D02*
X-746078Y979412D01*
G01X-741278Y688362D02*
X-741028Y690462D01*
G01X-723378Y705162D02*
X-732628Y690112D01*
G01D02*
X-720128D01*
G01X-740553Y922712D02*
X-739803Y925512D01*
G01D02*
X-739553Y928662D01*
G01D02*
X-739803Y931812D01*
G01D02*
X-740553Y934612D01*
G01X-740328Y960512D02*
X-738328Y962262D01*
G01D02*
X-737078Y964362D01*
G01D02*
X-736828Y966462D01*
G01D02*
X-737328Y968911D01*
G01D02*
X-739078Y970662D01*
G01X-726928Y968911D02*
X-725178Y971362D01*
G01X-723928Y960862D02*
X-725678Y962961D01*
G01D02*
X-726678Y966112D01*
G01D02*
X-726928Y969612D01*
G01X-739078Y970662D02*
X-740828Y971362D01*
G01D02*
X-739328Y972412D01*
G01D02*
X-738078Y974162D01*
G01D02*
X-737578Y976262D01*
G01D02*
X-738078Y978362D01*
G01D02*
X-739328Y980112D01*
G01X-726928Y969612D02*
X-726428Y974162D01*
G01D02*
X-725678Y976612D01*
G01D02*
X-724428Y979062D01*
G01X-723378Y684162D02*
Y705162D01*
G01X-718678Y971362D02*
X-717678Y969262D01*
G01D02*
X-717428Y966812D01*
G01D02*
X-717678Y964712D01*
G01D02*
X-718678Y962611D01*
G01D02*
X-720178Y960862D01*
G01D02*
X-721928Y960162D01*
G01D02*
X-723928Y960862D01*
G01X-725178Y971362D02*
X-723678Y972762D01*
G01D02*
X-721678Y973462D01*
G01D02*
X-719928Y972762D01*
G01D02*
X-718678Y971362D01*
G01X-724428Y979062D02*
X-722678Y980812D01*
G01D02*
X-720928Y981162D01*
G01D02*
X-719178Y980462D01*
G01D02*
X-717928Y978712D01*
G01X-608553Y958662D02*
Y979662D01*
G01X-611553Y958662D02*
X-605553D01*
G01X-608553Y979662D02*
X-611553Y975462D01*
G01X-612578Y1003111D02*
X-611078Y1001362D01*
G01D02*
X-609078Y1000662D01*
G01D02*
X-607078Y1001362D01*
G01D02*
X-605578Y1003111D01*
G01X-612578Y1019212D02*
X-613578Y1017112D01*
G01D02*
X-614328Y1014312D01*
G01D02*
X-614578Y1011162D01*
G01D02*
X-614328Y1008012D01*
G01D02*
X-613578Y1005212D01*
G01D02*
X-612578Y1003111D01*
G01X-605578D02*
X-604578Y1005212D01*
G01D02*
X-603828Y1008012D01*
G01D02*
X-603578Y1011162D01*
G01D02*
X-603828Y1014312D01*
G01D02*
X-604578Y1017112D01*
G01D02*
X-605578Y1019212D01*
G01X-609078Y1021662D02*
X-611078Y1020962D01*
G01D02*
X-612578Y1019212D01*
G01X-605578D02*
X-607078Y1020962D01*
G01D02*
X-609078Y1021662D01*
G01X-593403Y972312D02*
X-593653Y969162D01*
G01D02*
X-593403Y966012D01*
G01D02*
X-592653Y963212D01*
G01D02*
X-591653Y961111D01*
G01D02*
X-590153Y959362D01*
G01D02*
X-588153Y958662D01*
G01D02*
X-586153Y959362D01*
G01D02*
X-584653Y961111D01*
G01D02*
X-583653Y963212D01*
G01X-588153Y979662D02*
X-590153Y978962D01*
G01D02*
X-591653Y977212D01*
G01D02*
X-592653Y975112D01*
G01D02*
X-593403Y972312D01*
G01X-583653Y975112D02*
X-584653Y977212D01*
G01D02*
X-586153Y978962D01*
G01D02*
X-588153Y979662D01*
G01X-588678Y999962D02*
X-589178Y1000312D01*
G01D02*
Y1001012D01*
G01D02*
X-588678Y1001362D01*
G01D02*
X-588178Y1001012D01*
G01D02*
Y1000312D01*
G01D02*
X-588678Y999962D01*
G01X-583653Y963212D02*
X-582903Y966012D01*
G01D02*
X-582653Y969162D01*
G01D02*
X-582903Y972312D01*
G01X-567753Y957962D02*
X-568253Y958312D01*
G01Y959012D02*
X-567753Y959362D01*
G01X-582903Y972312D02*
X-583653Y975112D01*
G01X-565278Y1021662D02*
X-574528Y1006612D01*
G01D02*
X-562028D01*
G01X-568253Y958312D02*
Y959012D01*
G01X-567753Y959362D02*
X-567253Y959012D01*
G01D02*
Y958312D01*
G01D02*
X-567753Y957962D01*
G01X-565278Y1000662D02*
Y1021662D01*
G01X-552628Y1003811D02*
X-553128Y1000662D01*
G01D02*
X-542628D01*
G01X-551128Y1007312D02*
X-552628Y1003811D01*
G01Y1018162D02*
X-551128Y1020262D01*
G01X-552103Y967411D02*
X-550353Y969862D01*
G01D02*
X-548853Y971262D01*
G01X-545103D02*
X-543853Y969862D01*
G01D02*
X-542853Y967762D01*
G01D02*
X-542603Y965312D01*
G01D02*
X-542853Y963212D01*
G01D02*
X-543853Y961111D01*
G01D02*
X-545353Y959362D01*
G01D02*
X-547103Y958662D01*
G01D02*
X-549103Y959362D01*
G01D02*
X-550853Y961461D01*
G01D02*
X-551853Y964612D01*
G01D02*
X-552103Y968112D01*
G01D02*
X-551603Y972662D01*
G01X-548853Y971262D02*
X-546853Y971962D01*
G01D02*
X-545103Y971262D01*
G01X-551603Y972662D02*
X-550853Y975112D01*
G01D02*
X-549603Y977562D01*
G01D02*
X-547853Y979312D01*
G01D02*
X-546103Y979662D01*
G01D02*
X-544353Y978962D01*
G01D02*
X-543103Y977212D01*
G01X-542628Y1017112D02*
X-542878Y1015012D01*
G01D02*
X-543878Y1013262D01*
G01D02*
X-548878Y1009762D01*
G01D02*
X-551128Y1007312D01*
G01Y1020262D02*
X-549378Y1021312D01*
G01D02*
X-547378Y1021662D01*
G01D02*
X-544878Y1020962D01*
G01D02*
X-543128Y1019212D01*
G01D02*
X-542628Y1017112D01*
G01X-527453Y958662D02*
X-526953Y963212D01*
G01D02*
X-526203Y967061D01*
G01D02*
X-525203Y970562D01*
G01D02*
X-523953Y974412D01*
G01D02*
X-521953Y979662D01*
G01D02*
X-531953D01*
G01X-530978Y1003111D02*
X-529478Y1001362D01*
G01D02*
X-527478Y1000662D01*
G01D02*
X-525478Y1001362D01*
G01D02*
X-523978Y1003111D01*
G01X-530978Y1019212D02*
X-531978Y1017112D01*
G01D02*
X-532728Y1014312D01*
G01D02*
X-532978Y1011162D01*
G01D02*
X-532728Y1008012D01*
G01D02*
X-531978Y1005212D01*
G01D02*
X-530978Y1003111D01*
G01X-523978D02*
X-522978Y1005212D01*
G01D02*
X-522228Y1008012D01*
G01D02*
X-521978Y1011162D01*
G01D02*
X-522228Y1014312D01*
G01D02*
X-522978Y1017112D01*
G01D02*
X-523978Y1019212D01*
G01X-527478Y1021662D02*
X-529478Y1020962D01*
G01D02*
X-530978Y1019212D01*
G01X-523978D02*
X-525478Y1020962D01*
G01D02*
X-527478Y1021662D01*
G54D14*
X-1670620Y434270D03*
X-1278150Y-142362D03*
X-1212008D03*
X-408071D03*
X-341929D03*
G54D23*
X-1670620Y644870D03*
X-1085138Y-122677D03*
X-215059D03*
G54D42*
G01X-1781145Y60678D02*
X-1783645Y60665D01*
X-1783681Y67665D01*
X-1781181Y67678D01*
G01X-1781525Y100000D02*
X-1784025D01*
Y107000D01*
X-1781525D01*
G01X-1765228Y81760D02*
G03I-1750J-9D01*
G01X-1748500Y-168600D02*
X-1751000D01*
Y-161600D01*
X-1748500D01*
G01X-1761581Y67779D02*
G03I-1750J-9D01*
G01X-1751125Y100000D02*
X-1748625D01*
Y107000D01*
X-1751125D01*
G01X-1745100Y-140100D02*
X-1747600D01*
Y-133100D01*
X-1745100D01*
G01X-1745600Y-101000D02*
X-1748100D01*
Y-94000D01*
X-1745600D01*
G01X-1745900Y-72200D02*
X-1748400D01*
Y-65200D01*
X-1745900D01*
G01X-1744047Y-27647D02*
X-1746547D01*
Y-20647D01*
X-1744047D01*
G01X-1744108Y10524D02*
X-1746608D01*
Y17524D01*
X-1744108D01*
G01X-1620251Y-20237D02*
X-1708500Y110500D01*
X-1741400D01*
G01X-1723546Y60974D02*
X-1721046Y60987D01*
X-1721082Y67987D01*
X-1723582Y67974D01*
G01X-1711300Y-168600D02*
X-1708800D01*
Y-161600D01*
X-1711300D01*
G01X-1437000Y-122300D02*
X-1666200Y-122047D01*
X-1701500Y-157500D01*
X-1703550Y-157543D01*
G01X-1707900Y-140100D02*
X-1705400D01*
Y-133100D01*
X-1707900D01*
G01X-573700Y-92300D02*
X-1669100Y-92362D01*
X-1706600Y-129600D01*
G01X-1708400Y-101000D02*
X-1705900D01*
Y-94000D01*
X-1708400D01*
G01X-1708700Y-72200D02*
X-1706200D01*
Y-65200D01*
X-1708700D01*
G01X-1713647Y-27647D02*
X-1711147D01*
Y-20647D01*
X-1713647D01*
G01X-1630688Y-20298D02*
X-1706504D01*
G01X-1713708Y10524D02*
X-1711208D01*
Y17524D01*
X-1713708D01*
G01X-1669291Y21024D02*
X-1705958D01*
G01X-1660402Y19913D02*
X-1699402Y72299D01*
X-1715853Y72214D01*
G01X-1651000Y-68700D02*
X-1669500Y-68740D01*
X-1692000Y-91000D01*
X-1700650Y-90876D01*
G01X-1657400Y-51200D02*
X-1684700Y-51181D01*
X-1695200Y-61400D01*
X-1700950Y-61454D01*
G01X-1695320Y328970D02*
Y856970D01*
X-1312320D01*
Y328970D01*
X-1695320D01*
G01Y352370D02*
X-1312320D01*
G01X-1695320Y375770D02*
X-1312320D01*
G01X-1695320Y399170D02*
X-1312320D01*
G01X-1695320Y422570D02*
X-1312320D01*
G01X-1695320Y445970D02*
X-1312320D01*
G01X-1695320Y469370D02*
X-1312320D01*
G01X-1695320Y492770D02*
X-1312320D01*
G01X-1695320Y516170D02*
X-1312320D01*
G01X-1695320Y539570D02*
X-1312320D01*
G01X-1695320Y562970D02*
X-1312320D01*
G01X-1695320Y586370D02*
X-1312320D01*
G01X-1695320Y609770D02*
X-1312320D01*
G01X-1695320Y633170D02*
X-1312320D01*
G01X-1695320Y656570D02*
X-1312320D01*
G01X-1695320Y679970D02*
X-1312320D01*
G01X-1695320Y703370D02*
X-1312320D01*
G01X-1695320Y726770D02*
X-1312320D01*
G01X-1695320Y750170D02*
X-1312320D01*
G01X-1695320Y773570D02*
X-1312320D01*
G01X-1695320Y796970D02*
X-1312320D01*
G01X-1695320Y814470D02*
X-1312320D01*
G01X-1695320Y831970D02*
X-1312320D01*
G01X-1694692Y871696D02*
X-1682692D01*
Y883696D01*
X-1694692D01*
Y871696D01*
G01X-1651700Y-263500D02*
Y-266000D01*
X-1658700D01*
Y-263500D01*
G01X-1651700Y-219500D02*
Y-217000D01*
X-1658700D01*
Y-219500D01*
G01X-1663100Y-188300D02*
Y-210400D01*
G01X19843Y-137795D02*
X19213D01*
G02X17244Y-135827I0J1969D01*
G01Y7244D01*
G03X5433Y19055I-11811J0D01*
G01X-1432598D01*
G03X-1442441Y9213I0J-9843D01*
G01Y-14409D01*
G02X-1448346Y-20315I-5906J0D01*
G01X-1452283D01*
G02X-1458189Y-14409I0J5906D01*
G01Y17087D01*
X-1462126Y21024D01*
X-1615394D01*
X-1619331Y17087D01*
Y-18937D01*
G02X-1622087I-1378J0D01*
G01Y17087D01*
X-1626024Y21024D01*
X-1659291D01*
X-1663228Y17087D01*
Y-180945D01*
G03X-1657323Y-186850I5906J0D01*
G01X-1280807D01*
G02X-1278839Y-188819I0J-1969D01*
G01Y-194882D01*
G03X-1276870Y-196850I1969J0D01*
G01X-1209350D01*
G03X-1207382Y-194882I0J1969D01*
G01Y-188819D01*
G02X-1205413Y-186850I1969J0D01*
G01X-410728D01*
G02X-408760Y-188819I0J-1969D01*
G01Y-194882D01*
G03X-406791Y-196850I1969J0D01*
G01X-339272D01*
G03X-337303Y-194882I0J1969D01*
G01Y-188819D01*
G02X-335335Y-186850I1969J0D01*
G01X10000D01*
G03X21811Y-175039I0J11811D01*
G01Y-139764D01*
G03X19843Y-137795I-1969J0D01*
G01X-1671365Y30452D02*
X-1660402Y19913D01*
X-1667354Y33438D01*
X-1671365Y30452D01*
G01X-1643500Y-83900D02*
X-1643543Y-150965D01*
X-1610740Y-177190D01*
X-1610450Y-210817D01*
G01X-1636850Y-74803D02*
G02X-1650236I-6693J0D01*
G01Y-60913D01*
G02X-1636850I6693J9732D01*
G01Y-74803D01*
G01X-1645920Y814470D02*
Y328970D01*
G01X-1634500Y-68600D02*
X-1193800D01*
X-1193700Y-68500D01*
G01X-1630715Y-9203D02*
X-1620251Y-20237D01*
X-1626571Y-6405D01*
X-1630715Y-9203D01*
G01X-1622087Y27087D02*
Y46618D01*
X-1640187Y68474D01*
Y73147D01*
G01X-1629687Y80897D02*
Y78397D01*
X-1636687D01*
Y80897D01*
G01X-1629687Y124897D02*
Y127397D01*
X-1636687D01*
Y124897D01*
G01X-1609238Y-20298D02*
X-1461090D01*
G01X-1619331Y27087D02*
Y46345D01*
X-1604603Y67108D01*
Y75059D01*
G01X-1599694Y-262567D02*
Y-265067D01*
X-1606694D01*
Y-262567D01*
G01X-1599694Y-218567D02*
Y-216067D01*
X-1606694D01*
Y-218567D01*
G01X-1590741Y35529D02*
X-1595860Y21210D01*
X-1586374Y33095D01*
X-1590741Y35529D01*
G01X-1595860Y21210D02*
X-1481660Y226110D01*
X-1429760Y225560D01*
G01X-1594103Y82809D02*
Y80309D01*
X-1601103D01*
Y82809D01*
G01X-1594103Y126809D02*
Y129309D01*
X-1601103D01*
Y126809D01*
G01X-1544221Y65687D02*
X-1528091D01*
Y5061D01*
X-1543665D01*
G01X-1542120Y814470D02*
Y328970D01*
G01X-1440366Y15257D02*
X-1495320Y75850D01*
Y95270D01*
G01X-1483190Y106735D02*
Y104235D01*
X-1490190D01*
Y106735D01*
G01X-1483190Y137135D02*
Y139635D01*
X-1490190D01*
Y137135D01*
G01X-1447362Y-6491D02*
X-1455929Y-19056D01*
X-1443750Y-9949D01*
X-1447362Y-6491D01*
G01X-1455929Y-19056D02*
X-1348344Y93335D01*
X-1318804Y93631D01*
G01X-1458189Y27087D02*
Y85168D01*
G01X-1452295Y24688D02*
X-1440366Y15257D01*
X-1448592Y28047D01*
X-1452295Y24688D01*
G01X-1447689Y92918D02*
Y90418D01*
X-1454689D01*
Y92918D01*
G01X-1447689Y136918D02*
Y139418D01*
X-1454689D01*
Y136918D01*
G01X-1442441Y19213D02*
Y57546D01*
X-1424908Y75031D01*
X-1424960Y85168D01*
G01X-1438320Y814470D02*
Y328970D01*
G01X-1423300Y-154200D02*
X-1423500Y-222700D01*
G01X-1416378Y-145669D02*
G02X-1429764I-6693J0D01*
G01Y-131779D01*
G02X-1416378I6693J9732D01*
G01Y-145669D01*
G01X-1414613Y92918D02*
Y90418D01*
X-1421613D01*
Y92918D01*
G01X-1414613Y136918D02*
Y139418D01*
X-1421613D01*
Y136918D01*
G01X-1411800Y-261400D02*
Y-263900D01*
X-1418800D01*
Y-261400D01*
G01X-1411800Y-224200D02*
Y-221700D01*
X-1418800D01*
Y-224200D01*
G01X-1354920Y814470D02*
Y328970D01*
G01X-1308624Y83232D02*
X-1311124Y83207D01*
X-1311194Y90207D01*
X-1308694Y90232D01*
G01X-1278800Y-202800D02*
Y-226700D01*
G01X-1278226Y83537D02*
X-1275726Y83562D01*
X-1275796Y90561D01*
X-1278296Y90536D01*
G01X-1267400Y-269100D02*
Y-271600D01*
X-1274400D01*
Y-269100D01*
G01X-1267400Y-225100D02*
Y-222600D01*
X-1274400D01*
Y-225100D01*
G01X-1196100Y-269800D02*
Y-272300D01*
X-1203100D01*
Y-269800D01*
G01X-1196100Y-225800D02*
Y-223300D01*
X-1203100D01*
Y-225800D01*
G01X-1207400Y-202800D02*
Y-227000D01*
G01X-1193591Y-197427D02*
X-1205936Y-188547D01*
X-1197138Y-200951D01*
X-1193591Y-197427D01*
G01X-1205936Y-188547D02*
X-1164348Y-230411D01*
X-1141638Y-230281D01*
G01X-1172283Y-92362D02*
G02X-1185669I-6693J0D01*
G01Y-78472D01*
G02X-1172283I6693J9732D01*
G01Y-92362D01*
G01X-1179000Y-56500D02*
X-1178976Y70608D01*
G01X-1168476Y78358D02*
Y75858D01*
X-1175476D01*
Y78358D01*
G01X-1168476Y122358D02*
Y124858D01*
X-1175476D01*
Y122358D01*
G01X-1164000Y-68500D02*
X-318000D01*
G01X-1158159Y-52008D02*
X-1167891Y-63693D01*
X-1154896Y-55796D01*
X-1158159Y-52008D01*
G01X-1167400Y-63100D02*
X-1038372Y44709D01*
X-1015935Y44580D01*
G01X-1131503Y-240724D02*
X-1134003Y-240738D01*
X-1134043Y-233738D01*
X-1131543Y-233724D01*
G01X-1132353Y605862D02*
Y626862D01*
G01X-1124853Y605862D02*
X-1132353D01*
G01Y626862D02*
X-1124853D01*
G01X-991851Y779609D02*
X-1109253D01*
G01X-997953Y850362D02*
X-1109253Y850475D01*
G01X-1101103Y-240550D02*
X-1098603Y-240536D01*
X-1098643Y-233536D01*
X-1101143Y-233550D01*
G01X-1079253Y685662D02*
Y779609D01*
G01X-1086753Y734609D02*
X-1071753D01*
G01X-1079253Y779609D02*
X-1086753Y734609D01*
G01X-1071753D02*
X-1079253Y779609D01*
G01Y940475D02*
Y850475D01*
G01D02*
X-1071753Y895475D01*
G01X-1086753D02*
X-1079253Y850475D01*
G01X-1071753Y895475D02*
X-1086753D01*
G01X-1033653Y605862D02*
X-1026153D01*
G01Y626862D02*
X-1033653D01*
G01X-1026153Y605862D02*
Y626862D01*
G01X-941773Y821280D02*
G03X-981930Y821280I-20079J29195D01*
G01X-981930Y779609D02*
G03X-941772I20079J0D01*
G01X-981930D02*
Y821280D01*
G01X-952767Y467789D02*
X-708867D01*
Y467889D01*
G01X-948862Y764298D02*
X-925470Y725131D01*
G01X-914032Y734834D02*
X-948862Y764298D01*
G01D02*
X-873753Y675762D01*
G01X-941773Y821280D02*
Y779609D01*
G01X-936758Y875492D02*
X-899593Y901950D01*
G01X-910183Y912573D02*
X-936758Y875492D01*
G01D02*
X-860853Y951162D01*
G01X-855100Y-190000D02*
Y-247000D01*
X-920100D01*
Y-190000D01*
G01Y-189500D02*
X-915100Y-207500D01*
X-920100Y-203500D01*
X-925100Y-207500D01*
X-920100Y-189500D01*
G01X-925470Y725131D02*
X-914032Y734834D01*
G01X-931653Y759762D02*
X-537753D01*
G01X-918153Y886062D02*
X-537753Y885762D01*
G01X-879100Y-181100D02*
X-901100D01*
Y-191100D01*
X-876600D01*
Y-181100D01*
X-879100D01*
G01X-899593Y901950D02*
X-910183Y912573D01*
G01X-882600Y-223500D02*
Y-238500D01*
X-897600D01*
Y-223500D01*
X-882600D01*
G01X-890100D02*
Y-191000D01*
G01X-873753Y675762D02*
X-857628D01*
G01X-855100Y-189500D02*
X-850100Y-207500D01*
X-855100Y-203500D01*
X-860100Y-207500D01*
X-855100Y-189500D01*
G01X-860853Y951162D02*
X-853428Y951214D01*
G01X-820878Y710412D02*
X-841878Y678912D01*
G01X-820878Y694662D02*
G03I-10500J0D01*
G01X-816678Y970662D02*
G03I-10500J0D01*
G01Y986412D02*
X-837678Y954912D01*
G01X-832953Y642162D02*
Y663162D01*
G01X-825453Y642162D02*
X-832953D01*
G01Y663162D02*
X-825453D01*
G01X-828753Y918162D02*
Y939162D01*
G01X-821253Y918162D02*
X-828753D01*
G01Y939162D02*
X-821253D01*
G01X-734253Y642162D02*
X-726753D01*
G01Y663162D02*
X-734253D01*
G01X-730053Y918162D02*
X-722553D01*
G01Y939162D02*
X-730053D01*
G01X-726753Y642162D02*
Y663162D01*
G01X-722553Y918162D02*
Y939162D01*
G01X-631053Y958662D02*
Y979662D01*
G01X-623553Y958662D02*
X-631053D01*
G01Y979662D02*
X-623553D01*
G01X-554173Y-115984D02*
G02X-567559I-6693J0D01*
G01Y-102094D01*
G02X-554173I6693J9732D01*
G01Y-115984D01*
G01X-575253Y804762D02*
X-567753Y759762D01*
G01X-560253Y804762D02*
X-575253D01*
G01Y840762D02*
X-560253D01*
G01X-567753Y885762D02*
X-575253Y840762D01*
G01X-560900Y-79100D02*
X-560554Y69100D01*
G01X-548800Y74600D02*
Y72100D01*
X-555800D01*
Y74600D01*
G01X-548800Y111800D02*
Y114300D01*
X-555800D01*
Y111800D01*
G01X-567753Y885762D02*
Y759762D01*
G01D02*
X-560253Y804762D01*
G01Y840762D02*
X-567753Y885762D01*
G01Y941862D02*
Y885762D01*
G01X-504763Y-246236D02*
X-507263D01*
Y-239236D01*
X-504763D01*
G01X-511953Y958662D02*
X-504453D01*
G01Y979662D02*
X-511953D01*
G01X-504453Y958662D02*
Y979662D01*
G01X-474363Y-246236D02*
X-471863D01*
Y-239236D01*
X-474363D01*
G01X-409805Y-198271D02*
X-449305Y-235736D01*
X-464638D01*
G01X-418968Y-210408D02*
X-409805Y-198271D01*
X-422409Y-206780D01*
X-418968Y-210408D01*
G01X-396500Y-273900D02*
Y-276400D01*
X-403500D01*
Y-273900D01*
G01X-396500Y-229900D02*
Y-227400D01*
X-403500D01*
Y-229900D01*
G01X-408700Y-201600D02*
Y-230400D01*
G01X-337500Y-202500D02*
Y-229900D01*
G01X-334600Y-196400D02*
X-149828Y-196850D01*
X-121279Y-223574D01*
X62596Y-223693D01*
G01X-326200Y-271800D02*
Y-274300D01*
X-333200D01*
Y-271800D01*
G01X-326200Y-234600D02*
Y-232100D01*
X-333200D01*
Y-234600D01*
G01X-298268Y-92362D02*
G02X-311654I-6693J0D01*
G01Y-78472D01*
G02X-298268I6693J9732D01*
G01Y-92362D01*
G01X-304961Y-50982D02*
Y61988D01*
G01X-294461Y69738D02*
Y67238D01*
X-301461D01*
Y69738D01*
G01X-294461Y106938D02*
Y109438D01*
X-301461D01*
Y106938D01*
G01X-271070Y558920D02*
X-278070D01*
Y578920D01*
X-271070D01*
G01X-268500Y463000D02*
X48000D01*
G01X-250441Y638920D02*
G02X-224236Y746086I101371J32000D01*
G01X-256807Y686059D02*
X-255371Y670920D01*
X-251819Y685706D01*
X-256807Y686059D01*
G01X-159070Y670920D02*
X-265371D01*
G01X-232180Y733119D02*
X-224236Y746086D01*
X-235956Y736397D01*
X-232180Y733119D01*
G01X-176141Y697991D02*
X-231308Y753158D01*
G01X-166570Y618920D02*
G03I-5000J0D01*
G01X-167070Y558920D02*
X-160070D01*
Y578920D01*
X-167070D01*
G01X-169070Y1030920D02*
Y690920D01*
X-149070Y670920D01*
X-99070D01*
X-79070Y690920D01*
Y1030920D01*
X-99070Y1010920D01*
X-129070Y1050920D01*
X-159070Y1010920D01*
X-169070Y1030920D01*
G01X-129070Y620920D02*
X-99070D01*
G01X-114070Y618420D02*
X-99070Y620920D01*
X-114070Y623420D01*
Y618420D01*
G01X-99070Y660920D02*
Y600920D01*
G01X-79070Y680920D02*
Y600920D01*
G01X-64070Y623420D02*
X-79070Y620920D01*
X-64070Y618420D01*
Y623420D01*
G01X-39070Y620920D02*
X-79070D01*
G01X-26024Y-129370D02*
G02X-39409I-6693J0D01*
G01Y-115480D01*
G02X-26024I6693J9732D01*
G01Y-129370D01*
G01X-19600Y-105800D02*
X54350Y-105748D01*
G01X7400Y-63900D02*
Y-88900D01*
X-30600D01*
Y-63900D01*
X7400D01*
G01X-32400Y-92000D02*
X-32717Y59379D01*
G01X-22217Y67129D02*
Y64629D01*
X-29217D01*
Y67129D01*
G01X-22217Y97529D02*
Y100029D01*
X-29217D01*
Y97529D01*
G01X-11570Y590920D02*
X-18570D01*
Y610920D01*
X-11570D01*
G01X-5000Y66700D02*
X-7500D01*
Y73700D01*
X-5000D01*
G01X10000Y-136453D02*
X54150D01*
G01X7700Y-76800D02*
X25700Y-71800D01*
X21700Y-76800D01*
X25700Y-81800D01*
X7700Y-76800D01*
G01X9700D02*
X128700D01*
G01X10000Y0D02*
X87150D01*
G01X0Y10000D02*
Y61100D01*
G01X5000Y66700D02*
X7500D01*
Y73700D01*
X5000D01*
G01X32200Y-270289D02*
Y-272789D01*
X25200D01*
Y-270289D01*
G01X32200Y-239889D02*
Y-237389D01*
X25200D01*
Y-239889D01*
G01X21811Y-185039D02*
Y-230700D01*
G01X25906Y-186850D02*
X57815D01*
G01X33804Y-147548D02*
X21469Y-138655D01*
X30253Y-151068D01*
X33804Y-147548D01*
G01X21469Y-138655D02*
X45500Y-162900D01*
X53400D01*
G01X21969Y19055D02*
X41682D01*
G01X17244Y17244D02*
X17200Y41000D01*
X26500Y50200D01*
Y61100D01*
G01X28722Y27315D02*
X20060Y14816D01*
X32308Y23830D01*
X28722Y27315D01*
G01X20060Y14816D02*
X79380Y75850D01*
X96900Y75624D01*
G01X37800Y66400D02*
Y63900D01*
X30800D01*
Y66400D01*
G01X37800Y96800D02*
Y99300D01*
X30800D01*
Y96800D01*
G01X61900Y-146953D02*
X59400D01*
Y-139953D01*
X61900D01*
G01X62100Y-116248D02*
X59600D01*
Y-109248D01*
X62100D01*
G01X49432Y8555D02*
X46932D01*
Y15555D01*
X49432D01*
G01X70346Y-234210D02*
X67846D01*
Y-227210D01*
X70346D01*
G01X65565Y-197350D02*
X63065D01*
Y-190350D01*
X65565D01*
G01X63475Y-173400D02*
X60975D01*
Y-166400D01*
X63475D01*
G01X73430Y590920D02*
X80430D01*
Y610920D01*
X73430D01*
G01X79832Y8555D02*
X82332D01*
Y15555D01*
X79832D01*
G01X107546Y-234210D02*
X110046D01*
Y-227210D01*
X107546D01*
G01X102765Y-197350D02*
X105265D01*
Y-190350D01*
X102765D01*
G01X93875Y-173400D02*
X96375D01*
Y-166400D01*
X93875D01*
G01X99100Y-146953D02*
X101600D01*
Y-139953D01*
X99100D01*
G01X99300Y-116248D02*
X101800D01*
Y-109248D01*
X99300D01*
G01X94900Y-10500D02*
X92400D01*
Y-3500D01*
X94900D01*
G01X104900Y-10500D02*
X107400D01*
Y-3500D01*
X104900D01*
G01X106975Y64800D02*
X104475D01*
Y71800D01*
X106975D01*
G01X144000Y-67700D02*
Y-82700D01*
X129000D01*
Y-67700D01*
X144000D01*
G01X137375Y64800D02*
X139875D01*
Y71800D01*
X137375D01*
G01X275500Y635600D02*
X240500D01*
G01X243723Y635770D02*
X248723Y653770D01*
X243723Y649770D01*
X238723Y653770D01*
X243723Y635770D01*
Y780500D01*
G01Y1040714D02*
X238723Y1022714D01*
X243723Y1026714D01*
X248723Y1022714D01*
X243723Y1040714D01*
Y864614D01*
G01X275500Y1041100D02*
X240371D01*
G01X373400Y1090200D02*
Y1120200D01*
X403400D01*
Y1090200D01*
X373400D01*
G01X388090Y-343540D02*
X423090D01*
Y-308540D01*
X388090D01*
Y-343540D01*
G01X392700Y335900D02*
X427700D01*
Y370900D01*
X392700D01*
Y335900D01*
G01X435590Y-678540D02*
X835590D01*
Y-303540D01*
X435590D01*
Y-678540D01*
G01Y-353540D02*
X835590D01*
G01X425500Y675600D02*
X655500D01*
Y695600D01*
X425500D01*
Y675600D01*
G01Y685600D02*
X435500Y675600D01*
G01X425500Y695600D02*
X445500Y675600D01*
G01X435500Y695600D02*
X455500Y675600D01*
G01X425500Y725600D02*
X655500D01*
Y745600D01*
X425500D01*
Y725600D01*
G01Y735600D02*
X435500Y725600D01*
G01X425500Y745600D02*
X445500Y725600D01*
G01X435500Y745600D02*
X455500Y725600D01*
G01X425500Y775600D02*
X655500D01*
Y795600D01*
X425500D01*
Y775600D01*
G01Y785600D02*
X435500Y775600D01*
G01X425500Y795600D02*
X445500Y775600D01*
G01X435500Y795600D02*
X455500Y775600D01*
G01X425000Y828100D02*
X655000D01*
Y848100D01*
X425000D01*
Y828100D01*
G01Y838100D02*
X435000Y828100D01*
G01X425000Y848100D02*
X445000Y828100D01*
G01X435000Y848100D02*
X455000Y828100D01*
G01X425000Y882600D02*
X655000D01*
Y902600D01*
X425000D01*
Y882600D01*
G01Y892600D02*
X435000Y882600D01*
G01X425000Y902600D02*
X445000Y882600D01*
G01X435000Y902600D02*
X455000Y882600D01*
G01X425000Y932600D02*
X655000D01*
Y952600D01*
X425000D01*
Y932600D01*
G01Y942600D02*
X435000Y932600D01*
G01Y952600D02*
X455000Y932600D01*
G01X425000Y952600D02*
X445000Y932600D01*
G01X425000Y982600D02*
X655000D01*
Y1002600D01*
X425000D01*
Y982600D01*
G01Y992600D02*
X435000Y982600D01*
G01X425000Y1002600D02*
X445000Y982600D01*
G01X435000Y1002600D02*
X455000Y982600D01*
G01X1060200Y375900D02*
X440200D01*
Y-214100D01*
X1060200D01*
Y375900D01*
G01X440200Y-139100D02*
X1060200D01*
G01X440200Y-89100D02*
X1060200D01*
G01X440306Y-14154D02*
X1060200Y-14100D01*
G01X440200Y35900D02*
X1060200D01*
G01X440306Y85846D02*
X1060200Y85900D01*
G01X440200Y160900D02*
X1060200D01*
G01X440200Y210900D02*
X1060200D01*
G01X440200Y285900D02*
X1060200D01*
G01X440200Y330900D02*
X1060200D01*
G01X445500Y695600D02*
X465500Y675600D01*
G01X445500Y745600D02*
X465500Y725600D01*
G01X445500Y795600D02*
X465500Y775600D01*
G01X445000Y848100D02*
X465000Y828100D01*
G01X445000Y902600D02*
X465000Y882600D01*
G01X445000Y952600D02*
X465000Y932600D01*
G01X445000Y1002600D02*
X465000Y982600D01*
G01X455500Y695600D02*
X475500Y675600D01*
G01X465500Y695600D02*
X485500Y675600D01*
G01X455500Y745600D02*
X475500Y725600D01*
G01X465500Y745600D02*
X485500Y725600D01*
G01X455500Y795600D02*
X475500Y775600D01*
G01X465500Y795600D02*
X485500Y775600D01*
G01X455000Y848100D02*
X475000Y828100D01*
G01X465000Y848100D02*
X485000Y828100D01*
G01X455000Y902600D02*
X475000Y882600D01*
G01X465000Y902600D02*
X485000Y882600D01*
G01X465000Y952600D02*
X485000Y932600D01*
G01X455000Y952600D02*
X475000Y932600D01*
G01X455000Y1002600D02*
X475000Y982600D01*
G01X465000Y1002600D02*
X485000Y982600D01*
G01X785590Y-638540D02*
Y-478540D01*
X485590D01*
Y-638540D01*
X785590D01*
G01Y-618540D02*
X485590D01*
G01Y-598540D02*
X785590D01*
G01X785518Y-578540D02*
X485590D01*
G01Y-558540D02*
X785590D01*
G01X785518Y-538540D02*
X485590D01*
G01Y-518540D02*
X785590D01*
G01X785518Y-498540D02*
X485590D01*
G01X485500Y695600D02*
X505500Y675600D01*
G01X475500Y695600D02*
X495500Y675600D01*
G01X485500Y745600D02*
X505500Y725600D01*
G01X475500Y745600D02*
X495500Y725600D01*
G01X475500Y795600D02*
X495500Y775600D01*
G01X485500Y795600D02*
X505500Y775600D01*
G01X475000Y848100D02*
X495000Y828100D01*
G01X485000Y848100D02*
X505000Y828100D01*
G01X485000Y902600D02*
X505000Y882600D01*
G01X475000Y902600D02*
X495000Y882600D01*
G01X485000Y952600D02*
X505000Y932600D01*
G01X475000Y952600D02*
X495000Y932600D01*
G01X475000Y1002600D02*
X495000Y982600D01*
G01X485000Y1002600D02*
X505000Y982600D01*
G01X490200Y285900D02*
Y-214100D01*
G01X495500Y695600D02*
X515500Y675600D01*
G01X495500Y745600D02*
X515500Y725600D01*
G01X495500Y795600D02*
X515500Y775600D01*
G01X495000Y848100D02*
X515000Y828100D01*
G01X495000Y902600D02*
X515000Y882600D01*
G01X495000Y952600D02*
X515000Y932600D01*
G01X495000Y1002600D02*
X515000Y982600D01*
G01X505500Y695600D02*
X525500Y675600D01*
G01X515500Y695600D02*
X535500Y675600D01*
G01X515500Y745600D02*
X535500Y725600D01*
G01X505500Y745600D02*
X525500Y725600D01*
G01X515500Y795600D02*
X535500Y775600D01*
G01X505500Y795600D02*
X525500Y775600D01*
G01X505000Y848100D02*
X525000Y828100D01*
G01X515000Y848100D02*
X535000Y828100D01*
G01X515000Y902600D02*
X535000Y882600D01*
G01X505000Y902600D02*
X525000Y882600D01*
G01X515000Y952600D02*
X535000Y932600D01*
G01X505000Y952600D02*
X525000Y932600D01*
G01X505000Y1002600D02*
X525000Y982600D01*
G01X515000Y1002600D02*
X535000Y982600D01*
G01X525590Y-618540D02*
Y-638540D01*
G01Y-618540D02*
X545590Y-638540D01*
G01X525500Y695600D02*
X545500Y675600D01*
G01X525500Y745600D02*
X545500Y725600D01*
G01X525500Y795600D02*
X545500Y775600D01*
G01X525000Y848100D02*
X545000Y828100D01*
G01X525000Y902600D02*
X545000Y882600D01*
G01X525000Y952600D02*
X545000Y932600D01*
G01X525000Y1002600D02*
X545000Y982600D01*
G01X540590Y-618540D02*
X560590Y-638540D01*
G01X535500Y695600D02*
X555500Y675600D01*
G01X545500Y695600D02*
X565500Y675600D01*
G01X545500Y745600D02*
X565500Y725600D01*
G01X535500Y745600D02*
X555500Y725600D01*
G01X545500Y795600D02*
X565500Y775600D01*
G01X535500Y795600D02*
X555500Y775600D01*
G01X535000Y848100D02*
X555000Y828100D01*
G01X545000Y848100D02*
X565000Y828100D01*
G01X535000Y902600D02*
X555000Y882600D01*
G01X545000Y902600D02*
X565000Y882600D01*
G01X545000Y952600D02*
X565000Y932600D01*
G01X535000Y952600D02*
X555000Y932600D01*
G01X545000Y1002600D02*
X565000Y982600D01*
G01X535000Y1002600D02*
X555000Y982600D01*
G01X555590Y-618540D02*
X575590Y-638540D01*
G01X555590Y-603540D02*
X590590Y-638540D01*
G01X555590Y-598540D02*
Y-618540D01*
G01X555500Y695600D02*
X575500Y675600D01*
G01X555500Y745600D02*
X575500Y725600D01*
G01X555500Y795600D02*
X575500Y775600D01*
G01X555000Y848100D02*
X575000Y828100D01*
G01X555000Y902600D02*
X575000Y882600D01*
G01X555000Y952600D02*
X575000Y932600D01*
G01X555000Y1002600D02*
X575000Y982600D01*
G01X565590Y-598540D02*
X605590Y-638540D01*
G01X565590Y-393540D02*
X705590D01*
G01X565500Y695600D02*
X585500Y675600D01*
G01X575500Y695600D02*
X595500Y675600D01*
G01X565500Y745600D02*
X585500Y725600D01*
G01X575500Y745600D02*
X595500Y725600D01*
G01X575500Y795600D02*
X595500Y775600D01*
G01X565500Y795600D02*
X585500Y775600D01*
G01X565000Y848100D02*
X585000Y828100D01*
G01X575000Y848100D02*
X595000Y828100D01*
G01X565000Y902600D02*
X585000Y882600D01*
G01X575000Y902600D02*
X595000Y882600D01*
G01X575000Y952600D02*
X595000Y932600D01*
G01X565000Y952600D02*
X585000Y932600D01*
G01X575000Y1002600D02*
X595000Y982600D01*
G01X565000Y1002600D02*
X585000Y982600D01*
G01X580590Y-598540D02*
X620590Y-638540D01*
G01X585590Y-588540D02*
X635590Y-638540D01*
G01X585590Y-578540D02*
Y-598540D01*
G01X590590Y-578540D02*
X650590Y-638540D01*
G01X595500Y695600D02*
X615500Y675600D01*
G01X585500Y695600D02*
X605500Y675600D01*
G01X585500Y745600D02*
X605500Y725600D01*
G01X595500Y745600D02*
X615500Y725600D01*
G01X585500Y795600D02*
X605500Y775600D01*
G01X595500Y795600D02*
X615500Y775600D01*
G01X585000Y848100D02*
X605000Y828100D01*
G01X595000Y848100D02*
X615000Y828100D01*
G01X595000Y902600D02*
X615000Y882600D01*
G01X585000Y902600D02*
X605000Y882600D01*
G01X595000Y952600D02*
X615000Y932600D01*
G01X585000Y952600D02*
X605000Y932600D01*
G01X585000Y1002600D02*
X605000Y982600D01*
G01X595000Y1002600D02*
X615000Y982600D01*
G01X665590Y-638540D02*
X605590Y-578540D01*
G01X605500Y695600D02*
X625500Y675600D01*
G01X605500Y745600D02*
X625500Y725600D01*
G01X605500Y795600D02*
X625500Y775600D01*
G01X605000Y848100D02*
X625000Y828100D01*
G01X605000Y902600D02*
X625000Y882600D01*
G01X605000Y952600D02*
X625000Y932600D01*
G01X605000Y1002600D02*
X625000Y982600D01*
G01X680590Y-638540D02*
X620590Y-578540D01*
G01X615590Y-558540D02*
Y-578540D01*
G01Y-558540D02*
X695590Y-638540D01*
G01X615500Y695600D02*
X635500Y675600D01*
G01X625500Y695600D02*
X645500Y675600D01*
G01X625500Y745600D02*
X645500Y725600D01*
G01X615500Y745600D02*
X635500Y725600D01*
G01X625500Y795600D02*
X645500Y775600D01*
G01X615500Y795600D02*
X635500Y775600D01*
G01X615000Y848100D02*
X635000Y828100D01*
G01X625000Y848100D02*
X645000Y828100D01*
G01X625000Y902600D02*
X645000Y882600D01*
G01X615000Y902600D02*
X635000Y882600D01*
G01X625000Y952600D02*
X645000Y932600D01*
G01X615000Y952600D02*
X635000Y932600D01*
G01X615000Y1002600D02*
X635000Y982600D01*
G01X625000Y1002600D02*
X645000Y982600D01*
G01X630590Y-558540D02*
X710590Y-638540D01*
G01X640200Y330900D02*
Y-214100D01*
G01Y-189100D02*
X1060200D01*
G01X640200Y-164100D02*
X1060200D01*
G01X640200Y-64100D02*
X1060200D01*
G01X639700Y-38100D02*
X1059700D01*
G01X640200Y10900D02*
X1060200D01*
G01X640200Y60900D02*
X1060200D01*
G01X640200Y107900D02*
X1060200D01*
G01X640200Y135900D02*
X1060200D01*
G01X640200Y235900D02*
X1060200D01*
G01X640200Y260900D02*
X1060200D01*
G01X635500Y695600D02*
X655500Y675600D01*
G01X635500Y745600D02*
X655500Y725600D01*
G01X635500Y795600D02*
X655500Y775600D01*
G01X635000Y848100D02*
X655000Y828100D01*
G01X635000Y902600D02*
X655000Y882600D01*
G01X635000Y952600D02*
X655000Y932600D01*
G01X635000Y1002600D02*
X655000Y982600D01*
G01X645590Y-558540D02*
X725590Y-638540D01*
G01X645590Y-538540D02*
Y-558540D01*
G01Y-543540D02*
X740590Y-638540D01*
G01X655590Y-538540D02*
X755590Y-638540D01*
G01X645500Y695600D02*
X655500Y685600D01*
G01X645500Y745600D02*
X655500Y735600D01*
G01X645500Y795600D02*
X655500Y785600D01*
G01X645000Y848100D02*
X655000Y838100D01*
G01X645000Y902600D02*
X655000Y892600D01*
G01X645000Y952600D02*
X655000Y942600D01*
G01X645000Y1002600D02*
X655000Y992600D01*
G01X670590Y-538540D02*
X770590Y-638540D01*
G01X675590Y-518540D02*
Y-538540D01*
G01Y-528540D02*
X785590Y-638540D01*
G01X680590Y-518540D02*
X785590Y-623540D01*
G01X695590Y-518540D02*
X785590Y-608540D01*
G01X705590Y-498540D02*
Y-518540D01*
G01Y-498540D02*
X785590Y-578540D01*
G01X710590Y-518540D02*
X785590Y-593540D01*
G01X720590Y-498540D02*
X785590Y-563540D01*
G01X735590Y-478540D02*
Y-498540D01*
G01D02*
X785590Y-548540D01*
G01X735590Y-483540D02*
X785590Y-533540D01*
G01X745590Y-478540D02*
X785590Y-518540D01*
G01X760590Y-478540D02*
X785590Y-503540D01*
G01X775590Y-478540D02*
X785590Y-488540D01*
G01X840200Y330900D02*
Y-214100D01*
G01X987000Y648100D02*
G02X968500Y636300I-42782J46671D01*
G01X987000Y1038100D02*
G03X965500Y1047600I-24806J-27061D01*
G01X987000Y648100D02*
G03Y838100I-232843J95000D01*
G01Y848100D02*
X992000Y843100D01*
X987000Y838100D01*
G01Y1038100D02*
G02Y848100I-232843J-95000D01*
G54D33*
G01X389750Y1098300D02*
Y1110800D01*
X388010Y1108300D01*
G01Y1098300D02*
X391490D01*
G01X399940Y-333540D02*
Y-321040D01*
X398200Y-323540D01*
G01Y-333540D02*
X401680D01*
G01X409275Y-332082D02*
X410290Y-333123D01*
X411450Y-333540D01*
X412610Y-333123D01*
X413625Y-331874D01*
X414350Y-329998D01*
X414640Y-328123D01*
Y-325832D01*
X414350Y-323957D01*
X413625Y-322290D01*
X412755Y-321457D01*
X411740Y-321040D01*
X410580Y-321457D01*
X409710Y-322290D01*
X409130Y-323540D01*
X408840Y-325207D01*
X409130Y-326665D01*
X409855Y-328123D01*
X410725Y-328957D01*
X411740Y-329165D01*
X412900Y-328749D01*
X413770Y-327707D01*
X414640Y-325832D01*
G01X404550Y345900D02*
Y358400D01*
X402810Y355900D01*
G01Y345900D02*
X406290D01*
G01X416350D02*
X417365Y346108D01*
X418525Y346733D01*
X419250Y347775D01*
X419540Y349233D01*
X419250Y350691D01*
X418380Y351942D01*
X417075Y352567D01*
X415625D01*
X414755Y352983D01*
X414030Y354025D01*
X413740Y355483D01*
X414175Y356942D01*
X415190Y357983D01*
X416350Y358400D01*
X417510Y357983D01*
X418525Y356942D01*
X418960Y355483D01*
X418670Y354025D01*
X417945Y352983D01*
X417075Y352567D01*
X415625D01*
X414320Y351942D01*
X413450Y350691D01*
X413160Y349233D01*
X413450Y347775D01*
X414175Y346733D01*
X415335Y346108D01*
X416350Y345900D01*
G01X467350Y-180000D02*
X468365Y-179792D01*
X469525Y-179167D01*
X470250Y-178125D01*
X470540Y-176667D01*
X470250Y-175209D01*
X469380Y-173958D01*
X468075Y-173333D01*
X466625D01*
X465755Y-172917D01*
X465030Y-171875D01*
X464740Y-170417D01*
X465175Y-168958D01*
X466190Y-167917D01*
X467350Y-167500D01*
X468510Y-167917D01*
X469525Y-168958D01*
X469960Y-170417D01*
X469670Y-171875D01*
X468945Y-172917D01*
X468075Y-173333D01*
X466625D01*
X465320Y-173958D01*
X464450Y-175209D01*
X464160Y-176667D01*
X464450Y-178125D01*
X465175Y-179167D01*
X466335Y-179792D01*
X467350Y-180000D01*
G01X464260Y-119100D02*
X464550Y-116392D01*
X464985Y-114100D01*
X465565Y-112017D01*
X466290Y-109725D01*
X467450Y-106600D01*
X461650D01*
G01X461795Y-38892D02*
X462810Y-37433D01*
X463680Y-36600D01*
X464840Y-36183D01*
X465855Y-36600D01*
X466580Y-37433D01*
X467160Y-38683D01*
X467305Y-40142D01*
X467160Y-41392D01*
X466580Y-42642D01*
X465710Y-43683D01*
X464695Y-44100D01*
X463535Y-43683D01*
X462520Y-42434D01*
X461940Y-40558D01*
X461795Y-38475D01*
X462085Y-35767D01*
X462520Y-34308D01*
X463245Y-32850D01*
X464260Y-31808D01*
X465275Y-31600D01*
X466290Y-32017D01*
X467015Y-33058D01*
G01X461360Y7775D02*
X462230Y6733D01*
X463245Y6108D01*
X464550Y5900D01*
X465855Y6317D01*
X466870Y7150D01*
X467595Y8608D01*
X467740Y10275D01*
X467450Y11942D01*
X466725Y12983D01*
X465710Y13816D01*
X464695Y14025D01*
X463680Y13816D01*
X462375Y12983D01*
X462810Y18400D01*
X466725D01*
G01X466290Y55900D02*
Y68400D01*
X460925Y59442D01*
X468175D01*
G01X460860Y117400D02*
X461730Y115941D01*
X462890Y115108D01*
X464195Y114900D01*
X465355Y115108D01*
X466515Y116150D01*
X467240Y117400D01*
X467385Y118650D01*
X467095Y120108D01*
X466080Y121150D01*
X465065Y121567D01*
X463760D01*
G01X465065D02*
X465935Y122192D01*
X466660Y123233D01*
X466950Y124483D01*
X466660Y125733D01*
X465935Y126775D01*
X464630Y127400D01*
X463325Y127192D01*
X462020Y126358D01*
G01X461795Y185317D02*
X462665Y186566D01*
X463680Y187192D01*
X464840Y187400D01*
X466290Y186983D01*
X467305Y185942D01*
X467595Y184692D01*
X467450Y183441D01*
X466870Y182400D01*
X463970Y180317D01*
X462665Y178858D01*
X461795Y176775D01*
X461505Y174900D01*
X467595D01*
G01X466850Y237500D02*
Y250000D01*
X465110Y247500D01*
G01Y237500D02*
X468590D01*
G01X513700Y313400D02*
Y300900D01*
X519500D01*
G01X524775D02*
X528400Y313400D01*
X532025Y300900D01*
G01X530720Y305275D02*
X526080D01*
G01X540200Y300900D02*
Y306525D01*
X537300Y313400D01*
G01X543100D02*
X540200Y306525D01*
G01X554900Y300900D02*
X549100D01*
Y313400D01*
X554900D01*
G01X552580Y307358D02*
X549100D01*
G01X560900Y300900D02*
Y313400D01*
X564525D01*
X565685Y312775D01*
X566410Y311942D01*
X566700Y310275D01*
X566410Y308608D01*
X565540Y307567D01*
X564525Y306942D01*
X560900D01*
G01X564525D02*
X566700Y300900D01*
G01X527160Y-173833D02*
X527740Y-173208D01*
X528175Y-172167D01*
X528465Y-170708D01*
X528175Y-169458D01*
X527595Y-168625D01*
X526580Y-168000D01*
X522665D01*
Y-180500D01*
X527450D01*
X528465Y-179667D01*
X529045Y-178417D01*
X529335Y-176958D01*
X529045Y-175500D01*
X528175Y-174250D01*
X527160Y-173833D01*
X522665D01*
G01X537800Y-180500D02*
X536640Y-180292D01*
X535625Y-179459D01*
X534755Y-178208D01*
X534175Y-176750D01*
X533885Y-175083D01*
Y-173417D01*
X534175Y-171750D01*
X534755Y-170292D01*
X535625Y-169042D01*
X536640Y-168208D01*
X537800Y-168000D01*
X538960Y-168208D01*
X539975Y-169042D01*
X540845Y-170292D01*
X541425Y-171750D01*
X541715Y-173417D01*
Y-175083D01*
X541425Y-176750D01*
X540845Y-178208D01*
X539975Y-179459D01*
X538960Y-180292D01*
X537800Y-180500D01*
G01X549600Y-168000D02*
Y-180500D01*
G01X546265Y-168000D02*
X552935D01*
G01X561400D02*
Y-180500D01*
G01X558065Y-168000D02*
X564735D01*
G01X573200Y-180500D02*
X572040Y-180292D01*
X571025Y-179459D01*
X570155Y-178208D01*
X569575Y-176750D01*
X569285Y-175083D01*
Y-173417D01*
X569575Y-171750D01*
X570155Y-170292D01*
X571025Y-169042D01*
X572040Y-168208D01*
X573200Y-168000D01*
X574360Y-168208D01*
X575375Y-169042D01*
X576245Y-170292D01*
X576825Y-171750D01*
X577115Y-173417D01*
Y-175083D01*
X576825Y-176750D01*
X576245Y-178208D01*
X575375Y-179459D01*
X574360Y-180292D01*
X573200Y-180500D01*
G01X581230D02*
Y-168000D01*
X585000Y-178417D01*
X588770Y-168000D01*
Y-180500D01*
G01X531900Y358400D02*
Y345900D01*
G01X528565Y358400D02*
X535235D01*
G01X540075Y345900D02*
X543700Y358400D01*
X547325Y345900D01*
G01X546020Y350275D02*
X541380D01*
G01X552600Y345900D02*
Y358400D01*
X556225D01*
X557385Y357775D01*
X558110Y356942D01*
X558400Y355275D01*
X558110Y353608D01*
X557240Y352567D01*
X556225Y351942D01*
X552600D01*
G01X556225D02*
X558400Y345900D01*
G01X568170Y352150D02*
X571070D01*
Y348400D01*
X570200Y347150D01*
X569185Y346317D01*
X567735Y345900D01*
X566285Y346317D01*
X565270Y347150D01*
X564400Y348400D01*
X563820Y349858D01*
X563530Y351525D01*
Y352983D01*
X563820Y354233D01*
X564400Y355692D01*
X565270Y356942D01*
X566140Y357775D01*
X567300Y358400D01*
X568315D01*
X569475Y357983D01*
X570345Y357150D01*
G01X582000Y345900D02*
X576200D01*
Y358400D01*
X582000D01*
G01X579680Y352358D02*
X576200D01*
G01X590900Y358400D02*
Y345900D01*
G01X587565Y358400D02*
X594235D01*
G01X612760D02*
X616240D01*
G01X614500D02*
Y345900D01*
G01X612760D02*
X616240D01*
G01X622530D02*
Y358400D01*
X626300Y347983D01*
X630070Y358400D01*
Y345900D01*
G01X635200D02*
Y358400D01*
X638680D01*
X639840Y357775D01*
X640710Y356317D01*
X641000Y354650D01*
X640710Y352983D01*
X639985Y351733D01*
X638680Y351108D01*
X635200D01*
G01X652800Y345900D02*
X647000D01*
Y358400D01*
X652800D01*
G01X650480Y352358D02*
X647000D01*
G01X658510Y345900D02*
Y358400D01*
X661410D01*
X662570Y357775D01*
X663440Y356942D01*
X664165Y355692D01*
X664745Y354233D01*
X664890Y352150D01*
X664745Y350067D01*
X664165Y348608D01*
X663440Y347358D01*
X662570Y346525D01*
X661410Y345900D01*
X658510D01*
G01X669875D02*
X673500Y358400D01*
X677125Y345900D01*
G01X675820Y350275D02*
X671180D01*
G01X681965Y345900D02*
Y358400D01*
X688635Y345900D01*
Y358400D01*
G01X700290Y357358D02*
X699420Y357983D01*
X698405Y358400D01*
X697245D01*
X695940Y357775D01*
X694925Y356733D01*
X694200Y355483D01*
X693620Y353400D01*
X693475Y351525D01*
X693765Y349650D01*
X694200Y348400D01*
X695070Y347150D01*
X696085Y346317D01*
X697100Y345900D01*
X698115D01*
X699130Y346317D01*
X700000Y346941D01*
X700725Y347775D01*
G01X711800Y345900D02*
X706000D01*
Y358400D01*
X711800D01*
G01X709480Y352358D02*
X706000D01*
G01X732500Y358400D02*
Y345900D01*
G01X729165Y358400D02*
X735835D01*
G01X740675Y345900D02*
X744300Y358400D01*
X747925Y345900D01*
G01X746620Y350275D02*
X741980D01*
G01X757260Y352567D02*
X757840Y353192D01*
X758275Y354233D01*
X758565Y355692D01*
X758275Y356942D01*
X757695Y357775D01*
X756680Y358400D01*
X752765D01*
Y345900D01*
X757550D01*
X758565Y346733D01*
X759145Y347983D01*
X759435Y349442D01*
X759145Y350900D01*
X758275Y352150D01*
X757260Y352567D01*
X752765D01*
G01X765000Y358400D02*
Y345900D01*
X770800D01*
G01X782600D02*
X776800D01*
Y358400D01*
X782600D01*
G01X780280Y352358D02*
X776800D01*
G01X801415Y350067D02*
X805185D01*
G01X823710Y358400D02*
Y349442D01*
X824290Y347566D01*
X825450Y346317D01*
X826900Y345900D01*
X828350Y346317D01*
X829510Y347566D01*
X830090Y349442D01*
Y358400D01*
G01X835365Y345900D02*
Y358400D01*
X842035Y345900D01*
Y358400D01*
G01X848760D02*
X852240D01*
G01X850500D02*
Y345900D01*
G01X848760D02*
X852240D01*
G01X862300Y358400D02*
Y345900D01*
G01X858965Y358400D02*
X865635D01*
G01X871055Y347566D02*
X872215Y346525D01*
X873520Y345900D01*
X874680D01*
X875840Y346525D01*
X876710Y347566D01*
X877145Y349025D01*
X876855Y350483D01*
X876130Y351733D01*
X874825Y352567D01*
X873085Y352983D01*
X872070Y353816D01*
X871635Y355275D01*
X871925Y356733D01*
X872650Y357775D01*
X873665Y358400D01*
X874680D01*
X875695Y357983D01*
X876565Y356942D01*
G01X895960Y358400D02*
X899440D01*
G01X897700D02*
Y345900D01*
G01X895960D02*
X899440D01*
G01X906165D02*
Y358400D01*
X912835Y345900D01*
Y358400D01*
G01X929330Y345900D02*
Y358400D01*
X933100Y347983D01*
X936870Y358400D01*
Y345900D01*
G01X943160Y358400D02*
X946640D01*
G01X944900D02*
Y345900D01*
G01X943160D02*
X946640D01*
G01X953800Y358400D02*
Y345900D01*
X959600D01*
G01X965455Y347566D02*
X966615Y346525D01*
X967920Y345900D01*
X969080D01*
X970240Y346525D01*
X971110Y347566D01*
X971545Y349025D01*
X971255Y350483D01*
X970530Y351733D01*
X969225Y352567D01*
X967485Y352983D01*
X966470Y353816D01*
X966035Y355275D01*
X966325Y356733D01*
X967050Y357775D01*
X968065Y358400D01*
X969080D01*
X970095Y357983D01*
X970965Y356942D01*
G01X544600Y-106600D02*
Y-119100D01*
X550400D01*
G01X559300D02*
Y-113475D01*
X556400Y-106600D01*
G01X562200D02*
X559300Y-113475D01*
G01X568200Y-119100D02*
Y-106600D01*
X571825D01*
X572985Y-107225D01*
X573710Y-108058D01*
X574000Y-109725D01*
X573710Y-111392D01*
X572840Y-112433D01*
X571825Y-113058D01*
X568200D01*
G01X571825D02*
X574000Y-119100D01*
G01X582610D02*
X582900Y-116392D01*
X583335Y-114100D01*
X583915Y-112017D01*
X584640Y-109725D01*
X585800Y-106600D01*
X580000D01*
G01X544400Y-41000D02*
Y-53500D01*
X550200D01*
G01X559100D02*
Y-47875D01*
X556200Y-41000D01*
G01X562000D02*
X559100Y-47875D01*
G01X568000Y-53500D02*
Y-41000D01*
X571625D01*
X572785Y-41625D01*
X573510Y-42458D01*
X573800Y-44125D01*
X573510Y-45792D01*
X572640Y-46833D01*
X571625Y-47458D01*
X568000D01*
G01X571625D02*
X573800Y-53500D01*
G01X579945Y-48292D02*
X580960Y-46833D01*
X581830Y-46000D01*
X582990Y-45584D01*
X584005Y-46000D01*
X584730Y-46833D01*
X585310Y-48083D01*
X585455Y-49542D01*
X585310Y-50792D01*
X584730Y-52042D01*
X583860Y-53083D01*
X582845Y-53500D01*
X581685Y-53083D01*
X580670Y-51834D01*
X580090Y-49958D01*
X579945Y-47875D01*
X580235Y-45167D01*
X580670Y-43708D01*
X581395Y-42250D01*
X582410Y-41208D01*
X583425Y-41000D01*
X584440Y-41417D01*
X585165Y-42458D01*
G01X544600Y18400D02*
Y5900D01*
X550400D01*
G01X559300D02*
Y11525D01*
X556400Y18400D01*
G01X562200D02*
X559300Y11525D01*
G01X568200Y5900D02*
Y18400D01*
X571825D01*
X572985Y17775D01*
X573710Y16942D01*
X574000Y15275D01*
X573710Y13608D01*
X572840Y12567D01*
X571825Y11942D01*
X568200D01*
G01X571825D02*
X574000Y5900D01*
G01X579710Y7775D02*
X580580Y6733D01*
X581595Y6108D01*
X582900Y5900D01*
X584205Y6317D01*
X585220Y7150D01*
X585945Y8608D01*
X586090Y10275D01*
X585800Y11942D01*
X585075Y12983D01*
X584060Y13816D01*
X583045Y14025D01*
X582030Y13816D01*
X580725Y12983D01*
X581160Y18400D01*
X585075D01*
G01X544600Y68400D02*
Y55900D01*
X550400D01*
G01X559300D02*
Y61525D01*
X556400Y68400D01*
G01X562200D02*
X559300Y61525D01*
G01X568200Y55900D02*
Y68400D01*
X571825D01*
X572985Y67775D01*
X573710Y66942D01*
X574000Y65275D01*
X573710Y63608D01*
X572840Y62567D01*
X571825Y61942D01*
X568200D01*
G01X571825D02*
X574000Y55900D01*
G01X584640D02*
Y68400D01*
X579275Y59442D01*
X586525D01*
G01X539100Y127400D02*
Y114900D01*
X544900D01*
G01X553800D02*
Y120525D01*
X550900Y127400D01*
G01X556700D02*
X553800Y120525D01*
G01X562700Y114900D02*
Y127400D01*
X566325D01*
X567485Y126775D01*
X568210Y125942D01*
X568500Y124275D01*
X568210Y122608D01*
X567340Y121567D01*
X566325Y120942D01*
X562700D01*
G01X566325D02*
X568500Y114900D01*
G01X574210Y117400D02*
X575080Y115941D01*
X576240Y115108D01*
X577545Y114900D01*
X578705Y115108D01*
X579865Y116150D01*
X580590Y117400D01*
X580735Y118650D01*
X580445Y120108D01*
X579430Y121150D01*
X578415Y121567D01*
X577110D01*
G01X578415D02*
X579285Y122192D01*
X580010Y123233D01*
X580300Y124483D01*
X580010Y125733D01*
X579285Y126775D01*
X577980Y127400D01*
X576675Y127192D01*
X575370Y126358D01*
G01X548400Y189500D02*
Y177000D01*
X554200D01*
G01X563100D02*
Y182625D01*
X560200Y189500D01*
G01X566000D02*
X563100Y182625D01*
G01X572000Y177000D02*
Y189500D01*
X575625D01*
X576785Y188875D01*
X577510Y188042D01*
X577800Y186375D01*
X577510Y184708D01*
X576640Y183667D01*
X575625Y183042D01*
X572000D01*
G01X575625D02*
X577800Y177000D01*
G01X583945Y187417D02*
X584815Y188666D01*
X585830Y189292D01*
X586990Y189500D01*
X588440Y189083D01*
X589455Y188042D01*
X589745Y186792D01*
X589600Y185541D01*
X589020Y184500D01*
X586120Y182417D01*
X584815Y180958D01*
X583945Y178875D01*
X583655Y177000D01*
X589745D01*
G01X552700Y249500D02*
Y237000D01*
G01X549365Y249500D02*
X556035D01*
G01X564500Y237000D02*
X563340Y237208D01*
X562325Y238041D01*
X561455Y239292D01*
X560875Y240750D01*
X560585Y242417D01*
Y244083D01*
X560875Y245750D01*
X561455Y247208D01*
X562325Y248458D01*
X563340Y249292D01*
X564500Y249500D01*
X565660Y249292D01*
X566675Y248458D01*
X567545Y247208D01*
X568125Y245750D01*
X568415Y244083D01*
Y242417D01*
X568125Y240750D01*
X567545Y239292D01*
X566675Y238041D01*
X565660Y237208D01*
X564500Y237000D01*
G01X573400D02*
Y249500D01*
X576880D01*
X578040Y248875D01*
X578910Y247417D01*
X579200Y245750D01*
X578910Y244083D01*
X578185Y242833D01*
X576880Y242208D01*
X573400D01*
G01X555845Y-331874D02*
X557005Y-332915D01*
X558310Y-333540D01*
X559470D01*
X560630Y-332915D01*
X561500Y-331874D01*
X561935Y-330415D01*
X561645Y-328957D01*
X560920Y-327707D01*
X559615Y-326873D01*
X557875Y-326457D01*
X556860Y-325624D01*
X556425Y-324165D01*
X556715Y-322707D01*
X557440Y-321665D01*
X558455Y-321040D01*
X559470D01*
X560485Y-321457D01*
X561355Y-322498D01*
G01X570690Y-321040D02*
Y-333540D01*
G01X567355Y-321040D02*
X574025D01*
G01X578865Y-333540D02*
X582490Y-321040D01*
X586115Y-333540D01*
G01X584810Y-329165D02*
X580170D01*
G01X597480Y-322082D02*
X596610Y-321457D01*
X595595Y-321040D01*
X594435D01*
X593130Y-321665D01*
X592115Y-322707D01*
X591390Y-323957D01*
X590810Y-326040D01*
X590665Y-327915D01*
X590955Y-329790D01*
X591390Y-331040D01*
X592260Y-332290D01*
X593275Y-333123D01*
X594290Y-333540D01*
X595305D01*
X596320Y-333123D01*
X597190Y-332499D01*
X597915Y-331665D01*
G01X602900Y-333540D02*
Y-321040D01*
G01X608410D02*
X602900Y-328749D01*
G01X609280Y-333540D02*
X605365Y-325207D01*
G01X616150Y-321040D02*
X619630D01*
G01X617890D02*
Y-333540D01*
G01X616150D02*
X619630D01*
G01X626355D02*
Y-321040D01*
X633025Y-333540D01*
Y-321040D01*
G01X642360Y-327290D02*
X645260D01*
Y-331040D01*
X644390Y-332290D01*
X643375Y-333123D01*
X641925Y-333540D01*
X640475Y-333123D01*
X639460Y-332290D01*
X638590Y-331040D01*
X638010Y-329582D01*
X637720Y-327915D01*
Y-326457D01*
X638010Y-325207D01*
X638590Y-323748D01*
X639460Y-322498D01*
X640330Y-321665D01*
X641490Y-321040D01*
X642505D01*
X643665Y-321457D01*
X644535Y-322290D01*
G01X662045Y-331874D02*
X663205Y-332915D01*
X664510Y-333540D01*
X665670D01*
X666830Y-332915D01*
X667700Y-331874D01*
X668135Y-330415D01*
X667845Y-328957D01*
X667120Y-327707D01*
X665815Y-326873D01*
X664075Y-326457D01*
X663060Y-325624D01*
X662625Y-324165D01*
X662915Y-322707D01*
X663640Y-321665D01*
X664655Y-321040D01*
X665670D01*
X666685Y-321457D01*
X667555Y-322498D01*
G01X676890Y-321040D02*
Y-333540D01*
G01X673555Y-321040D02*
X680225D01*
G01X685790Y-333540D02*
Y-321040D01*
X689415D01*
X690575Y-321665D01*
X691300Y-322498D01*
X691590Y-324165D01*
X691300Y-325832D01*
X690430Y-326873D01*
X689415Y-327498D01*
X685790D01*
G01X689415D02*
X691590Y-333540D01*
G01X698750Y-321040D02*
X702230D01*
G01X700490D02*
Y-333540D01*
G01X698750D02*
X702230D01*
G01X709390D02*
Y-321040D01*
X712870D01*
X714030Y-321665D01*
X714900Y-323123D01*
X715190Y-324790D01*
X714900Y-326457D01*
X714175Y-327707D01*
X712870Y-328332D01*
X709390D01*
G01X577750Y-656873D02*
X578330Y-656248D01*
X578765Y-655207D01*
X579055Y-653748D01*
X578765Y-652498D01*
X578185Y-651665D01*
X577170Y-651040D01*
X573255D01*
Y-663540D01*
X578040D01*
X579055Y-662707D01*
X579635Y-661457D01*
X579925Y-659998D01*
X579635Y-658540D01*
X578765Y-657290D01*
X577750Y-656873D01*
X573255D01*
G01X588390Y-663540D02*
X587230Y-663332D01*
X586215Y-662499D01*
X585345Y-661248D01*
X584765Y-659790D01*
X584475Y-658123D01*
Y-656457D01*
X584765Y-654790D01*
X585345Y-653332D01*
X586215Y-652082D01*
X587230Y-651248D01*
X588390Y-651040D01*
X589550Y-651248D01*
X590565Y-652082D01*
X591435Y-653332D01*
X592015Y-654790D01*
X592305Y-656457D01*
Y-658123D01*
X592015Y-659790D01*
X591435Y-661248D01*
X590565Y-662499D01*
X589550Y-663332D01*
X588390Y-663540D01*
G01X600190Y-651040D02*
Y-663540D01*
G01X596855Y-651040D02*
X603525D01*
G01X611990D02*
Y-663540D01*
G01X608655Y-651040D02*
X615325D01*
G01X623790Y-663540D02*
X622630Y-663332D01*
X621615Y-662499D01*
X620745Y-661248D01*
X620165Y-659790D01*
X619875Y-658123D01*
Y-656457D01*
X620165Y-654790D01*
X620745Y-653332D01*
X621615Y-652082D01*
X622630Y-651248D01*
X623790Y-651040D01*
X624950Y-651248D01*
X625965Y-652082D01*
X626835Y-653332D01*
X627415Y-654790D01*
X627705Y-656457D01*
Y-658123D01*
X627415Y-659790D01*
X626835Y-661248D01*
X625965Y-662499D01*
X624950Y-663332D01*
X623790Y-663540D01*
G01X631820D02*
Y-651040D01*
X635590Y-661457D01*
X639360Y-651040D01*
Y-663540D01*
G01X656145Y-661874D02*
X657305Y-662915D01*
X658610Y-663540D01*
X659770D01*
X660930Y-662915D01*
X661800Y-661874D01*
X662235Y-660415D01*
X661945Y-658957D01*
X661220Y-657707D01*
X659915Y-656873D01*
X658175Y-656457D01*
X657160Y-655624D01*
X656725Y-654165D01*
X657015Y-652707D01*
X657740Y-651665D01*
X658755Y-651040D01*
X659770D01*
X660785Y-651457D01*
X661655Y-652498D01*
G01X669250Y-651040D02*
X672730D01*
G01X670990D02*
Y-663540D01*
G01X669250D02*
X672730D01*
G01X679600D02*
Y-651040D01*
X682500D01*
X683660Y-651665D01*
X684530Y-652498D01*
X685255Y-653748D01*
X685835Y-655207D01*
X685980Y-657290D01*
X685835Y-659373D01*
X685255Y-660832D01*
X684530Y-662082D01*
X683660Y-662915D01*
X682500Y-663540D01*
X679600D01*
G01X697490D02*
X691690D01*
Y-651040D01*
X697490D01*
G01X695170Y-657082D02*
X691690D01*
G01X567645Y-411874D02*
X568805Y-412915D01*
X570110Y-413540D01*
X571270D01*
X572430Y-412915D01*
X573300Y-411874D01*
X573735Y-410415D01*
X573445Y-408957D01*
X572720Y-407707D01*
X571415Y-406873D01*
X569675Y-406457D01*
X568660Y-405624D01*
X568225Y-404165D01*
X568515Y-402707D01*
X569240Y-401665D01*
X570255Y-401040D01*
X571270D01*
X572285Y-401457D01*
X573155Y-402498D01*
G01X585680Y-402082D02*
X584810Y-401457D01*
X583795Y-401040D01*
X582635D01*
X581330Y-401665D01*
X580315Y-402707D01*
X579590Y-403957D01*
X579010Y-406040D01*
X578865Y-407915D01*
X579155Y-409790D01*
X579590Y-411040D01*
X580460Y-412290D01*
X581475Y-413123D01*
X582490Y-413540D01*
X583505D01*
X584520Y-413123D01*
X585390Y-412499D01*
X586115Y-411665D01*
G01X590665Y-413540D02*
X594290Y-401040D01*
X597915Y-413540D01*
G01X596610Y-409165D02*
X591970D01*
G01X603190Y-401040D02*
Y-413540D01*
X608990D01*
G01X620790D02*
X614990D01*
Y-401040D01*
X620790D01*
G01X618470Y-407082D02*
X614990D01*
G01X639605Y-411248D02*
X643375D01*
G01Y-407498D02*
X639605D01*
G01X661755Y-413540D02*
Y-401040D01*
X668425Y-413540D01*
Y-401040D01*
G01X676890Y-413540D02*
X675730Y-413332D01*
X674715Y-412499D01*
X673845Y-411248D01*
X673265Y-409790D01*
X672975Y-408123D01*
Y-406457D01*
X673265Y-404790D01*
X673845Y-403332D01*
X674715Y-402082D01*
X675730Y-401248D01*
X676890Y-401040D01*
X678050Y-401248D01*
X679065Y-402082D01*
X679935Y-403332D01*
X680515Y-404790D01*
X680805Y-406457D01*
Y-408123D01*
X680515Y-409790D01*
X679935Y-411248D01*
X679065Y-412499D01*
X678050Y-413332D01*
X676890Y-413540D01*
G01X685355D02*
Y-401040D01*
X692025Y-413540D01*
Y-401040D01*
G01X703390Y-413540D02*
X697590D01*
Y-401040D01*
X703390D01*
G01X701070Y-407082D02*
X697590D01*
G01X594290Y-456040D02*
Y-468540D01*
G01X590955Y-456040D02*
X597625D01*
G01X606090Y-468540D02*
X604930Y-468332D01*
X603915Y-467499D01*
X603045Y-466248D01*
X602465Y-464790D01*
X602175Y-463123D01*
Y-461457D01*
X602465Y-459790D01*
X603045Y-458332D01*
X603915Y-457082D01*
X604930Y-456248D01*
X606090Y-456040D01*
X607250Y-456248D01*
X608265Y-457082D01*
X609135Y-458332D01*
X609715Y-459790D01*
X610005Y-461457D01*
Y-463123D01*
X609715Y-464790D01*
X609135Y-466248D01*
X608265Y-467499D01*
X607250Y-468332D01*
X606090Y-468540D01*
G01X614990D02*
Y-456040D01*
X618470D01*
X619630Y-456665D01*
X620500Y-458123D01*
X620790Y-459790D01*
X620500Y-461457D01*
X619775Y-462707D01*
X618470Y-463332D01*
X614990D01*
G01X638445Y-466874D02*
X639605Y-467915D01*
X640910Y-468540D01*
X642070D01*
X643230Y-467915D01*
X644100Y-466874D01*
X644535Y-465415D01*
X644245Y-463957D01*
X643520Y-462707D01*
X642215Y-461873D01*
X640475Y-461457D01*
X639460Y-460624D01*
X639025Y-459165D01*
X639315Y-457707D01*
X640040Y-456665D01*
X641055Y-456040D01*
X642070D01*
X643085Y-456457D01*
X643955Y-457498D01*
G01X651550Y-456040D02*
X655030D01*
G01X653290D02*
Y-468540D01*
G01X651550D02*
X655030D01*
G01X661900D02*
Y-456040D01*
X664800D01*
X665960Y-456665D01*
X666830Y-457498D01*
X667555Y-458748D01*
X668135Y-460207D01*
X668280Y-462290D01*
X668135Y-464373D01*
X667555Y-465832D01*
X666830Y-467082D01*
X665960Y-467915D01*
X664800Y-468540D01*
X661900D01*
G01X679790D02*
X673990D01*
Y-456040D01*
X679790D01*
G01X677470Y-462082D02*
X673990D01*
G01X590665Y-371040D02*
X594290Y-383540D01*
X597915Y-371040D01*
G01X604350D02*
X607830D01*
G01X606090D02*
Y-383540D01*
G01X604350D02*
X607830D01*
G01X620790D02*
X614990D01*
Y-371040D01*
X620790D01*
G01X618470Y-377082D02*
X614990D01*
G01X625340Y-371040D02*
X627370Y-383540D01*
X629690Y-371040D01*
X632010Y-383540D01*
X634040Y-371040D01*
G01X656190Y-383540D02*
X650390D01*
Y-371040D01*
X656190D01*
G01X653870Y-377082D02*
X650390D01*
G01X663205Y-379373D02*
X666975D01*
G01X679790Y-383540D02*
X673990D01*
Y-371040D01*
X679790D01*
G01X677470Y-377082D02*
X673990D01*
G01X667700Y-209000D02*
Y-196500D01*
X665960Y-199000D01*
G01Y-209000D02*
X669440D01*
G01X679500Y-196500D02*
X678340Y-196917D01*
X677470Y-197958D01*
X676890Y-199208D01*
X676455Y-200875D01*
X676310Y-202750D01*
X676455Y-204625D01*
X676890Y-206292D01*
X677470Y-207542D01*
X678340Y-208583D01*
X679500Y-209000D01*
X680660Y-208583D01*
X681530Y-207542D01*
X682110Y-206292D01*
X682545Y-204625D01*
X682690Y-202750D01*
X682545Y-200875D01*
X682110Y-199208D01*
X681530Y-197958D01*
X680660Y-196917D01*
X679500Y-196500D01*
G01X691300D02*
X690140Y-196917D01*
X689270Y-197958D01*
X688690Y-199208D01*
X688255Y-200875D01*
X688110Y-202750D01*
X688255Y-204625D01*
X688690Y-206292D01*
X689270Y-207542D01*
X690140Y-208583D01*
X691300Y-209000D01*
X692460Y-208583D01*
X693330Y-207542D01*
X693910Y-206292D01*
X694345Y-204625D01*
X694490Y-202750D01*
X694345Y-200875D01*
X693910Y-199208D01*
X693330Y-197958D01*
X692460Y-196917D01*
X691300Y-196500D01*
G01X703100Y-209000D02*
X702230Y-208792D01*
X701360Y-207959D01*
X700780Y-206500D01*
X700490Y-204833D01*
X700780Y-203167D01*
X701360Y-201708D01*
X702230Y-200875D01*
X703100Y-200667D01*
X703970Y-200875D01*
X704840Y-201708D01*
X705420Y-203167D01*
X705565Y-204833D01*
X705420Y-206500D01*
X704840Y-207959D01*
X703970Y-208792D01*
X703100Y-209000D01*
G01X712435D02*
Y-196500D01*
G01Y-202542D02*
X713160Y-201500D01*
X713885Y-200875D01*
X715045Y-200667D01*
X715915Y-200875D01*
X716930Y-201708D01*
X717365Y-202958D01*
Y-209000D01*
G01X722350D02*
Y-200667D01*
G01Y-202958D02*
X722785Y-201917D01*
X723510Y-201084D01*
X724525Y-200667D01*
X725540Y-201084D01*
X726265Y-201917D01*
X726700Y-202958D01*
Y-209000D01*
G01Y-202958D02*
X727135Y-201917D01*
X727860Y-201084D01*
X728875Y-200667D01*
X729890Y-201084D01*
X730615Y-201917D01*
X731050Y-203167D01*
Y-209000D01*
G01X748705Y-204833D02*
X752185D01*
G01X750300Y-202125D02*
Y-207542D01*
G01X759490Y-209417D02*
X764710Y-196500D01*
G01X772015Y-204833D02*
X775785D01*
G01X785700Y-209000D02*
Y-196500D01*
X783960Y-199000D01*
G01Y-209000D02*
X787440D01*
G01X797500Y-196500D02*
X796340Y-196917D01*
X795470Y-197958D01*
X794890Y-199208D01*
X794455Y-200875D01*
X794310Y-202750D01*
X794455Y-204625D01*
X794890Y-206292D01*
X795470Y-207542D01*
X796340Y-208583D01*
X797500Y-209000D01*
X798660Y-208583D01*
X799530Y-207542D01*
X800110Y-206292D01*
X800545Y-204625D01*
X800690Y-202750D01*
X800545Y-200875D01*
X800110Y-199208D01*
X799530Y-197958D01*
X798660Y-196917D01*
X797500Y-196500D01*
G01X806690Y-209417D02*
X811910Y-196500D01*
G01X806690D02*
X805820Y-196917D01*
X805385Y-197542D01*
X805095Y-198792D01*
X805385Y-200042D01*
X805820Y-200667D01*
X806690Y-201084D01*
X807560Y-200667D01*
X807995Y-200042D01*
X808285Y-198792D01*
X807995Y-197542D01*
X807560Y-196917D01*
X806690Y-196500D01*
G01X811910Y-204833D02*
X811040Y-205250D01*
X810605Y-205875D01*
X810315Y-207125D01*
X810605Y-208375D01*
X811040Y-209000D01*
X811910Y-209417D01*
X812780Y-209000D01*
X813215Y-208375D01*
X813505Y-207125D01*
X813215Y-205875D01*
X812780Y-205250D01*
X811910Y-204833D01*
G01X669400Y-184100D02*
X670415Y-183892D01*
X671575Y-183267D01*
X672300Y-182225D01*
X672590Y-180767D01*
X672300Y-179309D01*
X671430Y-178058D01*
X670125Y-177433D01*
X668675D01*
X667805Y-177017D01*
X667080Y-175975D01*
X666790Y-174517D01*
X667225Y-173058D01*
X668240Y-172017D01*
X669400Y-171600D01*
X670560Y-172017D01*
X671575Y-173058D01*
X672010Y-174517D01*
X671720Y-175975D01*
X670995Y-177017D01*
X670125Y-177433D01*
X668675D01*
X667370Y-178058D01*
X666500Y-179309D01*
X666210Y-180767D01*
X666500Y-182225D01*
X667225Y-183267D01*
X668385Y-183892D01*
X669400Y-184100D01*
G01X678010Y-182225D02*
X678880Y-183267D01*
X679895Y-183892D01*
X681200Y-184100D01*
X682505Y-183683D01*
X683520Y-182850D01*
X684245Y-181392D01*
X684390Y-179725D01*
X684100Y-178058D01*
X683375Y-177017D01*
X682360Y-176184D01*
X681345Y-175975D01*
X680330Y-176184D01*
X679025Y-177017D01*
X679460Y-171600D01*
X683375D01*
G01X693000Y-184100D02*
X692130Y-183892D01*
X691260Y-183059D01*
X690680Y-181600D01*
X690390Y-179933D01*
X690680Y-178267D01*
X691260Y-176808D01*
X692130Y-175975D01*
X693000Y-175767D01*
X693870Y-175975D01*
X694740Y-176808D01*
X695320Y-178267D01*
X695465Y-179933D01*
X695320Y-181600D01*
X694740Y-183059D01*
X693870Y-183892D01*
X693000Y-184100D01*
G01X702335D02*
Y-171600D01*
G01Y-177642D02*
X703060Y-176600D01*
X703785Y-175975D01*
X704945Y-175767D01*
X705815Y-175975D01*
X706830Y-176808D01*
X707265Y-178058D01*
Y-184100D01*
G01X712250D02*
Y-175767D01*
G01Y-178058D02*
X712685Y-177017D01*
X713410Y-176184D01*
X714425Y-175767D01*
X715440Y-176184D01*
X716165Y-177017D01*
X716600Y-178058D01*
Y-184100D01*
G01Y-178058D02*
X717035Y-177017D01*
X717760Y-176184D01*
X718775Y-175767D01*
X719790Y-176184D01*
X720515Y-177017D01*
X720950Y-178267D01*
Y-184100D01*
G01X738605Y-179933D02*
X742085D01*
G01X740200Y-177225D02*
Y-182642D01*
G01X749390Y-184517D02*
X754610Y-171600D01*
G01X761915Y-179933D02*
X765685D01*
G01X787400Y-184100D02*
Y-171600D01*
X785660Y-174100D01*
G01Y-184100D02*
X789140D01*
G01X799200Y-171600D02*
X798040Y-172017D01*
X797170Y-173058D01*
X796590Y-174308D01*
X796155Y-175975D01*
X796010Y-177850D01*
X796155Y-179725D01*
X796590Y-181392D01*
X797170Y-182642D01*
X798040Y-183683D01*
X799200Y-184100D01*
X800360Y-183683D01*
X801230Y-182642D01*
X801810Y-181392D01*
X802245Y-179725D01*
X802390Y-177850D01*
X802245Y-175975D01*
X801810Y-174308D01*
X801230Y-173058D01*
X800360Y-172017D01*
X799200Y-171600D01*
G01X808390Y-184517D02*
X813610Y-171600D01*
G01X808390D02*
X807520Y-172017D01*
X807085Y-172642D01*
X806795Y-173892D01*
X807085Y-175142D01*
X807520Y-175767D01*
X808390Y-176184D01*
X809260Y-175767D01*
X809695Y-175142D01*
X809985Y-173892D01*
X809695Y-172642D01*
X809260Y-172017D01*
X808390Y-171600D01*
G01X813610Y-179933D02*
X812740Y-180350D01*
X812305Y-180975D01*
X812015Y-182225D01*
X812305Y-183475D01*
X812740Y-184100D01*
X813610Y-184517D01*
X814480Y-184100D01*
X814915Y-183475D01*
X815205Y-182225D01*
X814915Y-180975D01*
X814480Y-180350D01*
X813610Y-179933D01*
G01X667210Y-155725D02*
X668080Y-156767D01*
X669095Y-157392D01*
X670400Y-157600D01*
X671705Y-157183D01*
X672720Y-156350D01*
X673445Y-154892D01*
X673590Y-153225D01*
X673300Y-151558D01*
X672575Y-150517D01*
X671560Y-149684D01*
X670545Y-149475D01*
X669530Y-149684D01*
X668225Y-150517D01*
X668660Y-145100D01*
X672575D01*
G01X682200D02*
X681040Y-145517D01*
X680170Y-146558D01*
X679590Y-147808D01*
X679155Y-149475D01*
X679010Y-151350D01*
X679155Y-153225D01*
X679590Y-154892D01*
X680170Y-156142D01*
X681040Y-157183D01*
X682200Y-157600D01*
X683360Y-157183D01*
X684230Y-156142D01*
X684810Y-154892D01*
X685245Y-153225D01*
X685390Y-151350D01*
X685245Y-149475D01*
X684810Y-147808D01*
X684230Y-146558D01*
X683360Y-145517D01*
X682200Y-145100D01*
G01X694000Y-157600D02*
X693130Y-157392D01*
X692260Y-156559D01*
X691680Y-155100D01*
X691390Y-153433D01*
X691680Y-151767D01*
X692260Y-150308D01*
X693130Y-149475D01*
X694000Y-149267D01*
X694870Y-149475D01*
X695740Y-150308D01*
X696320Y-151767D01*
X696465Y-153433D01*
X696320Y-155100D01*
X695740Y-156559D01*
X694870Y-157392D01*
X694000Y-157600D01*
G01X703335D02*
Y-145100D01*
G01Y-151142D02*
X704060Y-150100D01*
X704785Y-149475D01*
X705945Y-149267D01*
X706815Y-149475D01*
X707830Y-150308D01*
X708265Y-151558D01*
Y-157600D01*
G01X713250D02*
Y-149267D01*
G01Y-151558D02*
X713685Y-150517D01*
X714410Y-149684D01*
X715425Y-149267D01*
X716440Y-149684D01*
X717165Y-150517D01*
X717600Y-151558D01*
Y-157600D01*
G01Y-151558D02*
X718035Y-150517D01*
X718760Y-149684D01*
X719775Y-149267D01*
X720790Y-149684D01*
X721515Y-150517D01*
X721950Y-151767D01*
Y-157600D01*
G01X739605Y-153433D02*
X743085D01*
G01X741200Y-150725D02*
Y-156142D01*
G01X750390Y-158017D02*
X755610Y-145100D01*
G01X762915Y-153433D02*
X766685D01*
G01X788400Y-157600D02*
Y-145100D01*
X786660Y-147600D01*
G01Y-157600D02*
X790140D01*
G01X800200Y-145100D02*
X799040Y-145517D01*
X798170Y-146558D01*
X797590Y-147808D01*
X797155Y-149475D01*
X797010Y-151350D01*
X797155Y-153225D01*
X797590Y-154892D01*
X798170Y-156142D01*
X799040Y-157183D01*
X800200Y-157600D01*
X801360Y-157183D01*
X802230Y-156142D01*
X802810Y-154892D01*
X803245Y-153225D01*
X803390Y-151350D01*
X803245Y-149475D01*
X802810Y-147808D01*
X802230Y-146558D01*
X801360Y-145517D01*
X800200Y-145100D01*
G01X809390Y-158017D02*
X814610Y-145100D01*
G01X809390D02*
X808520Y-145517D01*
X808085Y-146142D01*
X807795Y-147392D01*
X808085Y-148642D01*
X808520Y-149267D01*
X809390Y-149684D01*
X810260Y-149267D01*
X810695Y-148642D01*
X810985Y-147392D01*
X810695Y-146142D01*
X810260Y-145517D01*
X809390Y-145100D01*
G01X814610Y-153433D02*
X813740Y-153850D01*
X813305Y-154475D01*
X813015Y-155725D01*
X813305Y-156975D01*
X813740Y-157600D01*
X814610Y-158017D01*
X815480Y-157600D01*
X815915Y-156975D01*
X816205Y-155725D01*
X815915Y-154475D01*
X815480Y-153850D01*
X814610Y-153433D01*
G01X669400Y-84100D02*
Y-71600D01*
X667660Y-74100D01*
G01Y-84100D02*
X671140D01*
G01X681200Y-71600D02*
X680040Y-72017D01*
X679170Y-73058D01*
X678590Y-74308D01*
X678155Y-75975D01*
X678010Y-77850D01*
X678155Y-79725D01*
X678590Y-81392D01*
X679170Y-82642D01*
X680040Y-83683D01*
X681200Y-84100D01*
X682360Y-83683D01*
X683230Y-82642D01*
X683810Y-81392D01*
X684245Y-79725D01*
X684390Y-77850D01*
X684245Y-75975D01*
X683810Y-74308D01*
X683230Y-73058D01*
X682360Y-72017D01*
X681200Y-71600D01*
G01X693000D02*
X691840Y-72017D01*
X690970Y-73058D01*
X690390Y-74308D01*
X689955Y-75975D01*
X689810Y-77850D01*
X689955Y-79725D01*
X690390Y-81392D01*
X690970Y-82642D01*
X691840Y-83683D01*
X693000Y-84100D01*
X694160Y-83683D01*
X695030Y-82642D01*
X695610Y-81392D01*
X696045Y-79725D01*
X696190Y-77850D01*
X696045Y-75975D01*
X695610Y-74308D01*
X695030Y-73058D01*
X694160Y-72017D01*
X693000Y-71600D01*
G01X704800Y-84100D02*
X703930Y-83892D01*
X703060Y-83059D01*
X702480Y-81600D01*
X702190Y-79933D01*
X702480Y-78267D01*
X703060Y-76808D01*
X703930Y-75975D01*
X704800Y-75767D01*
X705670Y-75975D01*
X706540Y-76808D01*
X707120Y-78267D01*
X707265Y-79933D01*
X707120Y-81600D01*
X706540Y-83059D01*
X705670Y-83892D01*
X704800Y-84100D01*
G01X714135D02*
Y-71600D01*
G01Y-77642D02*
X714860Y-76600D01*
X715585Y-75975D01*
X716745Y-75767D01*
X717615Y-75975D01*
X718630Y-76808D01*
X719065Y-78058D01*
Y-84100D01*
G01X724050D02*
Y-75767D01*
G01Y-78058D02*
X724485Y-77017D01*
X725210Y-76184D01*
X726225Y-75767D01*
X727240Y-76184D01*
X727965Y-77017D01*
X728400Y-78058D01*
Y-84100D01*
G01Y-78058D02*
X728835Y-77017D01*
X729560Y-76184D01*
X730575Y-75767D01*
X731590Y-76184D01*
X732315Y-77017D01*
X732750Y-78267D01*
Y-84100D01*
G01X750405Y-79933D02*
X753885D01*
G01X752000Y-77225D02*
Y-82642D01*
G01X761190Y-84517D02*
X766410Y-71600D01*
G01X773715Y-79933D02*
X777485D01*
G01X787400Y-84100D02*
Y-71600D01*
X785660Y-74100D01*
G01Y-84100D02*
X789140D01*
G01X799200Y-71600D02*
X798040Y-72017D01*
X797170Y-73058D01*
X796590Y-74308D01*
X796155Y-75975D01*
X796010Y-77850D01*
X796155Y-79725D01*
X796590Y-81392D01*
X797170Y-82642D01*
X798040Y-83683D01*
X799200Y-84100D01*
X800360Y-83683D01*
X801230Y-82642D01*
X801810Y-81392D01*
X802245Y-79725D01*
X802390Y-77850D01*
X802245Y-75975D01*
X801810Y-74308D01*
X801230Y-73058D01*
X800360Y-72017D01*
X799200Y-71600D01*
G01X808390Y-84517D02*
X813610Y-71600D01*
G01X808390D02*
X807520Y-72017D01*
X807085Y-72642D01*
X806795Y-73892D01*
X807085Y-75142D01*
X807520Y-75767D01*
X808390Y-76184D01*
X809260Y-75767D01*
X809695Y-75142D01*
X809985Y-73892D01*
X809695Y-72642D01*
X809260Y-72017D01*
X808390Y-71600D01*
G01X813610Y-79933D02*
X812740Y-80350D01*
X812305Y-80975D01*
X812015Y-82225D01*
X812305Y-83475D01*
X812740Y-84100D01*
X813610Y-84517D01*
X814480Y-84100D01*
X814915Y-83475D01*
X815205Y-82225D01*
X814915Y-80975D01*
X814480Y-80350D01*
X813610Y-79933D01*
G01X672700Y-58500D02*
X673715Y-58292D01*
X674875Y-57667D01*
X675600Y-56625D01*
X675890Y-55167D01*
X675600Y-53709D01*
X674730Y-52458D01*
X673425Y-51833D01*
X671975D01*
X671105Y-51417D01*
X670380Y-50375D01*
X670090Y-48917D01*
X670525Y-47458D01*
X671540Y-46417D01*
X672700Y-46000D01*
X673860Y-46417D01*
X674875Y-47458D01*
X675310Y-48917D01*
X675020Y-50375D01*
X674295Y-51417D01*
X673425Y-51833D01*
X671975D01*
X670670Y-52458D01*
X669800Y-53709D01*
X669510Y-55167D01*
X669800Y-56625D01*
X670525Y-57667D01*
X671685Y-58292D01*
X672700Y-58500D01*
G01X681310Y-56625D02*
X682180Y-57667D01*
X683195Y-58292D01*
X684500Y-58500D01*
X685805Y-58083D01*
X686820Y-57250D01*
X687545Y-55792D01*
X687690Y-54125D01*
X687400Y-52458D01*
X686675Y-51417D01*
X685660Y-50584D01*
X684645Y-50375D01*
X683630Y-50584D01*
X682325Y-51417D01*
X682760Y-46000D01*
X686675D01*
G01X696300Y-58500D02*
X695430Y-58292D01*
X694560Y-57459D01*
X693980Y-56000D01*
X693690Y-54333D01*
X693980Y-52667D01*
X694560Y-51208D01*
X695430Y-50375D01*
X696300Y-50167D01*
X697170Y-50375D01*
X698040Y-51208D01*
X698620Y-52667D01*
X698765Y-54333D01*
X698620Y-56000D01*
X698040Y-57459D01*
X697170Y-58292D01*
X696300Y-58500D01*
G01X705635D02*
Y-46000D01*
G01Y-52042D02*
X706360Y-51000D01*
X707085Y-50375D01*
X708245Y-50167D01*
X709115Y-50375D01*
X710130Y-51208D01*
X710565Y-52458D01*
Y-58500D01*
G01X715550D02*
Y-50167D01*
G01Y-52458D02*
X715985Y-51417D01*
X716710Y-50584D01*
X717725Y-50167D01*
X718740Y-50584D01*
X719465Y-51417D01*
X719900Y-52458D01*
Y-58500D01*
G01Y-52458D02*
X720335Y-51417D01*
X721060Y-50584D01*
X722075Y-50167D01*
X723090Y-50584D01*
X723815Y-51417D01*
X724250Y-52667D01*
Y-58500D01*
G01X741905Y-54333D02*
X745385D01*
G01X743500Y-51625D02*
Y-57042D01*
G01X752690Y-58917D02*
X757910Y-46000D01*
G01X765215Y-54333D02*
X768985D01*
G01X790700Y-58500D02*
Y-46000D01*
X788960Y-48500D01*
G01Y-58500D02*
X792440D01*
G01X802500Y-46000D02*
X801340Y-46417D01*
X800470Y-47458D01*
X799890Y-48708D01*
X799455Y-50375D01*
X799310Y-52250D01*
X799455Y-54125D01*
X799890Y-55792D01*
X800470Y-57042D01*
X801340Y-58083D01*
X802500Y-58500D01*
X803660Y-58083D01*
X804530Y-57042D01*
X805110Y-55792D01*
X805545Y-54125D01*
X805690Y-52250D01*
X805545Y-50375D01*
X805110Y-48708D01*
X804530Y-47458D01*
X803660Y-46417D01*
X802500Y-46000D01*
G01X811690Y-58917D02*
X816910Y-46000D01*
G01X811690D02*
X810820Y-46417D01*
X810385Y-47042D01*
X810095Y-48292D01*
X810385Y-49542D01*
X810820Y-50167D01*
X811690Y-50584D01*
X812560Y-50167D01*
X812995Y-49542D01*
X813285Y-48292D01*
X812995Y-47042D01*
X812560Y-46417D01*
X811690Y-46000D01*
G01X816910Y-54333D02*
X816040Y-54750D01*
X815605Y-55375D01*
X815315Y-56625D01*
X815605Y-57875D01*
X816040Y-58500D01*
X816910Y-58917D01*
X817780Y-58500D01*
X818215Y-57875D01*
X818505Y-56625D01*
X818215Y-55375D01*
X817780Y-54750D01*
X816910Y-54333D01*
G01X665700Y115500D02*
X666715Y115708D01*
X667875Y116333D01*
X668600Y117375D01*
X668890Y118833D01*
X668600Y120291D01*
X667730Y121542D01*
X666425Y122167D01*
X664975D01*
X664105Y122583D01*
X663380Y123625D01*
X663090Y125083D01*
X663525Y126542D01*
X664540Y127583D01*
X665700Y128000D01*
X666860Y127583D01*
X667875Y126542D01*
X668310Y125083D01*
X668020Y123625D01*
X667295Y122583D01*
X666425Y122167D01*
X664975D01*
X663670Y121542D01*
X662800Y120291D01*
X662510Y118833D01*
X662800Y117375D01*
X663525Y116333D01*
X664685Y115708D01*
X665700Y115500D01*
G01X674310Y117375D02*
X675180Y116333D01*
X676195Y115708D01*
X677500Y115500D01*
X678805Y115917D01*
X679820Y116750D01*
X680545Y118208D01*
X680690Y119875D01*
X680400Y121542D01*
X679675Y122583D01*
X678660Y123416D01*
X677645Y123625D01*
X676630Y123416D01*
X675325Y122583D01*
X675760Y128000D01*
X679675D01*
G01X689300Y115500D02*
X688430Y115708D01*
X687560Y116541D01*
X686980Y118000D01*
X686690Y119667D01*
X686980Y121333D01*
X687560Y122792D01*
X688430Y123625D01*
X689300Y123833D01*
X690170Y123625D01*
X691040Y122792D01*
X691620Y121333D01*
X691765Y119667D01*
X691620Y118000D01*
X691040Y116541D01*
X690170Y115708D01*
X689300Y115500D01*
G01X698635D02*
Y128000D01*
G01Y121958D02*
X699360Y123000D01*
X700085Y123625D01*
X701245Y123833D01*
X702115Y123625D01*
X703130Y122792D01*
X703565Y121542D01*
Y115500D01*
G01X708550D02*
Y123833D01*
G01Y121542D02*
X708985Y122583D01*
X709710Y123416D01*
X710725Y123833D01*
X711740Y123416D01*
X712465Y122583D01*
X712900Y121542D01*
Y115500D01*
G01Y121542D02*
X713335Y122583D01*
X714060Y123416D01*
X715075Y123833D01*
X716090Y123416D01*
X716815Y122583D01*
X717250Y121333D01*
Y115500D01*
G01X734905Y119667D02*
X738385D01*
G01X736500Y122375D02*
Y116958D01*
G01X745690Y115083D02*
X750910Y128000D01*
G01X758215Y119667D02*
X761985D01*
G01X783700Y115500D02*
Y128000D01*
X781960Y125500D01*
G01Y115500D02*
X785440D01*
G01X795500Y128000D02*
X794340Y127583D01*
X793470Y126542D01*
X792890Y125292D01*
X792455Y123625D01*
X792310Y121750D01*
X792455Y119875D01*
X792890Y118208D01*
X793470Y116958D01*
X794340Y115917D01*
X795500Y115500D01*
X796660Y115917D01*
X797530Y116958D01*
X798110Y118208D01*
X798545Y119875D01*
X798690Y121750D01*
X798545Y123625D01*
X798110Y125292D01*
X797530Y126542D01*
X796660Y127583D01*
X795500Y128000D01*
G01X804690Y115083D02*
X809910Y128000D01*
G01X804690D02*
X803820Y127583D01*
X803385Y126958D01*
X803095Y125708D01*
X803385Y124458D01*
X803820Y123833D01*
X804690Y123416D01*
X805560Y123833D01*
X805995Y124458D01*
X806285Y125708D01*
X805995Y126958D01*
X805560Y127583D01*
X804690Y128000D01*
G01X809910Y119667D02*
X809040Y119250D01*
X808605Y118625D01*
X808315Y117375D01*
X808605Y116125D01*
X809040Y115500D01*
X809910Y115083D01*
X810780Y115500D01*
X811215Y116125D01*
X811505Y117375D01*
X811215Y118625D01*
X810780Y119250D01*
X809910Y119667D01*
G01X666210Y142775D02*
X667080Y141733D01*
X668095Y141108D01*
X669400Y140900D01*
X670705Y141317D01*
X671720Y142150D01*
X672445Y143608D01*
X672590Y145275D01*
X672300Y146942D01*
X671575Y147983D01*
X670560Y148816D01*
X669545Y149025D01*
X668530Y148816D01*
X667225Y147983D01*
X667660Y153400D01*
X671575D01*
G01X681200D02*
X680040Y152983D01*
X679170Y151942D01*
X678590Y150692D01*
X678155Y149025D01*
X678010Y147150D01*
X678155Y145275D01*
X678590Y143608D01*
X679170Y142358D01*
X680040Y141317D01*
X681200Y140900D01*
X682360Y141317D01*
X683230Y142358D01*
X683810Y143608D01*
X684245Y145275D01*
X684390Y147150D01*
X684245Y149025D01*
X683810Y150692D01*
X683230Y151942D01*
X682360Y152983D01*
X681200Y153400D01*
G01X693000Y140900D02*
X692130Y141108D01*
X691260Y141941D01*
X690680Y143400D01*
X690390Y145067D01*
X690680Y146733D01*
X691260Y148192D01*
X692130Y149025D01*
X693000Y149233D01*
X693870Y149025D01*
X694740Y148192D01*
X695320Y146733D01*
X695465Y145067D01*
X695320Y143400D01*
X694740Y141941D01*
X693870Y141108D01*
X693000Y140900D01*
G01X702335D02*
Y153400D01*
G01Y147358D02*
X703060Y148400D01*
X703785Y149025D01*
X704945Y149233D01*
X705815Y149025D01*
X706830Y148192D01*
X707265Y146942D01*
Y140900D01*
G01X712250D02*
Y149233D01*
G01Y146942D02*
X712685Y147983D01*
X713410Y148816D01*
X714425Y149233D01*
X715440Y148816D01*
X716165Y147983D01*
X716600Y146942D01*
Y140900D01*
G01Y146942D02*
X717035Y147983D01*
X717760Y148816D01*
X718775Y149233D01*
X719790Y148816D01*
X720515Y147983D01*
X720950Y146733D01*
Y140900D01*
G01X738605Y145067D02*
X742085D01*
G01X740200Y147775D02*
Y142358D01*
G01X749390Y140483D02*
X754610Y153400D01*
G01X761915Y145067D02*
X765685D01*
G01X787400Y140900D02*
Y153400D01*
X785660Y150900D01*
G01Y140900D02*
X789140D01*
G01X799200Y153400D02*
X798040Y152983D01*
X797170Y151942D01*
X796590Y150692D01*
X796155Y149025D01*
X796010Y147150D01*
X796155Y145275D01*
X796590Y143608D01*
X797170Y142358D01*
X798040Y141317D01*
X799200Y140900D01*
X800360Y141317D01*
X801230Y142358D01*
X801810Y143608D01*
X802245Y145275D01*
X802390Y147150D01*
X802245Y149025D01*
X801810Y150692D01*
X801230Y151942D01*
X800360Y152983D01*
X799200Y153400D01*
G01X808390Y140483D02*
X813610Y153400D01*
G01X808390D02*
X807520Y152983D01*
X807085Y152358D01*
X806795Y151108D01*
X807085Y149858D01*
X807520Y149233D01*
X808390Y148816D01*
X809260Y149233D01*
X809695Y149858D01*
X809985Y151108D01*
X809695Y152358D01*
X809260Y152983D01*
X808390Y153400D01*
G01X813610Y145067D02*
X812740Y144650D01*
X812305Y144025D01*
X812015Y142775D01*
X812305Y141525D01*
X812740Y140900D01*
X813610Y140483D01*
X814480Y140900D01*
X814915Y141525D01*
X815205Y142775D01*
X814915Y144025D01*
X814480Y144650D01*
X813610Y145067D01*
G01X668100Y216500D02*
Y229000D01*
X666360Y226500D01*
G01Y216500D02*
X669840D01*
G01X679900Y229000D02*
X678740Y228583D01*
X677870Y227542D01*
X677290Y226292D01*
X676855Y224625D01*
X676710Y222750D01*
X676855Y220875D01*
X677290Y219208D01*
X677870Y217958D01*
X678740Y216917D01*
X679900Y216500D01*
X681060Y216917D01*
X681930Y217958D01*
X682510Y219208D01*
X682945Y220875D01*
X683090Y222750D01*
X682945Y224625D01*
X682510Y226292D01*
X681930Y227542D01*
X681060Y228583D01*
X679900Y229000D01*
G01X691700D02*
X690540Y228583D01*
X689670Y227542D01*
X689090Y226292D01*
X688655Y224625D01*
X688510Y222750D01*
X688655Y220875D01*
X689090Y219208D01*
X689670Y217958D01*
X690540Y216917D01*
X691700Y216500D01*
X692860Y216917D01*
X693730Y217958D01*
X694310Y219208D01*
X694745Y220875D01*
X694890Y222750D01*
X694745Y224625D01*
X694310Y226292D01*
X693730Y227542D01*
X692860Y228583D01*
X691700Y229000D01*
G01X703500Y216500D02*
X702630Y216708D01*
X701760Y217541D01*
X701180Y219000D01*
X700890Y220667D01*
X701180Y222333D01*
X701760Y223792D01*
X702630Y224625D01*
X703500Y224833D01*
X704370Y224625D01*
X705240Y223792D01*
X705820Y222333D01*
X705965Y220667D01*
X705820Y219000D01*
X705240Y217541D01*
X704370Y216708D01*
X703500Y216500D01*
G01X712835D02*
Y229000D01*
G01Y222958D02*
X713560Y224000D01*
X714285Y224625D01*
X715445Y224833D01*
X716315Y224625D01*
X717330Y223792D01*
X717765Y222542D01*
Y216500D01*
G01X722750D02*
Y224833D01*
G01Y222542D02*
X723185Y223583D01*
X723910Y224417D01*
X724925Y224833D01*
X725940Y224417D01*
X726665Y223583D01*
X727100Y222542D01*
Y216500D01*
G01Y222542D02*
X727535Y223583D01*
X728260Y224417D01*
X729275Y224833D01*
X730290Y224417D01*
X731015Y223583D01*
X731450Y222333D01*
Y216500D01*
G01X749105Y220667D02*
X752585D01*
G01X750700Y223375D02*
Y217958D01*
G01X759890Y216083D02*
X765110Y229000D01*
G01X772415Y220667D02*
X776185D01*
G01X786100Y216500D02*
Y229000D01*
X784360Y226500D01*
G01Y216500D02*
X787840D01*
G01X797900Y229000D02*
X796740Y228583D01*
X795870Y227542D01*
X795290Y226292D01*
X794855Y224625D01*
X794710Y222750D01*
X794855Y220875D01*
X795290Y219208D01*
X795870Y217958D01*
X796740Y216917D01*
X797900Y216500D01*
X799060Y216917D01*
X799930Y217958D01*
X800510Y219208D01*
X800945Y220875D01*
X801090Y222750D01*
X800945Y224625D01*
X800510Y226292D01*
X799930Y227542D01*
X799060Y228583D01*
X797900Y229000D01*
G01X807090Y216083D02*
X812310Y229000D01*
G01X807090D02*
X806220Y228583D01*
X805785Y227958D01*
X805495Y226708D01*
X805785Y225458D01*
X806220Y224833D01*
X807090Y224417D01*
X807960Y224833D01*
X808395Y225458D01*
X808685Y226708D01*
X808395Y227958D01*
X807960Y228583D01*
X807090Y229000D01*
G01X812310Y220667D02*
X811440Y220250D01*
X811005Y219625D01*
X810715Y218375D01*
X811005Y217125D01*
X811440Y216500D01*
X812310Y216083D01*
X813180Y216500D01*
X813615Y217125D01*
X813905Y218375D01*
X813615Y219625D01*
X813180Y220250D01*
X812310Y220667D01*
G01X668100Y241500D02*
X669115Y241708D01*
X670275Y242333D01*
X671000Y243375D01*
X671290Y244833D01*
X671000Y246291D01*
X670130Y247542D01*
X668825Y248167D01*
X667375D01*
X666505Y248583D01*
X665780Y249625D01*
X665490Y251083D01*
X665925Y252542D01*
X666940Y253583D01*
X668100Y254000D01*
X669260Y253583D01*
X670275Y252542D01*
X670710Y251083D01*
X670420Y249625D01*
X669695Y248583D01*
X668825Y248167D01*
X667375D01*
X666070Y247542D01*
X665200Y246291D01*
X664910Y244833D01*
X665200Y243375D01*
X665925Y242333D01*
X667085Y241708D01*
X668100Y241500D01*
G01X676710Y243375D02*
X677580Y242333D01*
X678595Y241708D01*
X679900Y241500D01*
X681205Y241917D01*
X682220Y242750D01*
X682945Y244208D01*
X683090Y245875D01*
X682800Y247542D01*
X682075Y248583D01*
X681060Y249417D01*
X680045Y249625D01*
X679030Y249417D01*
X677725Y248583D01*
X678160Y254000D01*
X682075D01*
G01X691700Y241500D02*
X690830Y241708D01*
X689960Y242541D01*
X689380Y244000D01*
X689090Y245667D01*
X689380Y247333D01*
X689960Y248792D01*
X690830Y249625D01*
X691700Y249833D01*
X692570Y249625D01*
X693440Y248792D01*
X694020Y247333D01*
X694165Y245667D01*
X694020Y244000D01*
X693440Y242541D01*
X692570Y241708D01*
X691700Y241500D01*
G01X701035D02*
Y254000D01*
G01Y247958D02*
X701760Y249000D01*
X702485Y249625D01*
X703645Y249833D01*
X704515Y249625D01*
X705530Y248792D01*
X705965Y247542D01*
Y241500D01*
G01X710950D02*
Y249833D01*
G01Y247542D02*
X711385Y248583D01*
X712110Y249417D01*
X713125Y249833D01*
X714140Y249417D01*
X714865Y248583D01*
X715300Y247542D01*
Y241500D01*
G01Y247542D02*
X715735Y248583D01*
X716460Y249417D01*
X717475Y249833D01*
X718490Y249417D01*
X719215Y248583D01*
X719650Y247333D01*
Y241500D01*
G01X737305Y245667D02*
X740785D01*
G01X738900Y248375D02*
Y242958D01*
G01X748090Y241083D02*
X753310Y254000D01*
G01X760615Y245667D02*
X764385D01*
G01X786100Y241500D02*
Y254000D01*
X784360Y251500D01*
G01Y241500D02*
X787840D01*
G01X797900Y254000D02*
X796740Y253583D01*
X795870Y252542D01*
X795290Y251292D01*
X794855Y249625D01*
X794710Y247750D01*
X794855Y245875D01*
X795290Y244208D01*
X795870Y242958D01*
X796740Y241917D01*
X797900Y241500D01*
X799060Y241917D01*
X799930Y242958D01*
X800510Y244208D01*
X800945Y245875D01*
X801090Y247750D01*
X800945Y249625D01*
X800510Y251292D01*
X799930Y252542D01*
X799060Y253583D01*
X797900Y254000D01*
G01X807090Y241083D02*
X812310Y254000D01*
G01X807090D02*
X806220Y253583D01*
X805785Y252958D01*
X805495Y251708D01*
X805785Y250458D01*
X806220Y249833D01*
X807090Y249417D01*
X807960Y249833D01*
X808395Y250458D01*
X808685Y251708D01*
X808395Y252958D01*
X807960Y253583D01*
X807090Y254000D01*
G01X812310Y245667D02*
X811440Y245250D01*
X811005Y244625D01*
X810715Y243375D01*
X811005Y242125D01*
X811440Y241500D01*
X812310Y241083D01*
X813180Y241500D01*
X813615Y242125D01*
X813905Y243375D01*
X813615Y244625D01*
X813180Y245250D01*
X812310Y245667D01*
G01X663910Y269575D02*
X664780Y268533D01*
X665795Y267908D01*
X667100Y267700D01*
X668405Y268117D01*
X669420Y268950D01*
X670145Y270408D01*
X670290Y272075D01*
X670000Y273742D01*
X669275Y274783D01*
X668260Y275616D01*
X667245Y275825D01*
X666230Y275616D01*
X664925Y274783D01*
X665360Y280200D01*
X669275D01*
G01X678900D02*
X677740Y279783D01*
X676870Y278742D01*
X676290Y277492D01*
X675855Y275825D01*
X675710Y273950D01*
X675855Y272075D01*
X676290Y270408D01*
X676870Y269158D01*
X677740Y268117D01*
X678900Y267700D01*
X680060Y268117D01*
X680930Y269158D01*
X681510Y270408D01*
X681945Y272075D01*
X682090Y273950D01*
X681945Y275825D01*
X681510Y277492D01*
X680930Y278742D01*
X680060Y279783D01*
X678900Y280200D01*
G01X690700Y267700D02*
X689830Y267908D01*
X688960Y268741D01*
X688380Y270200D01*
X688090Y271867D01*
X688380Y273533D01*
X688960Y274992D01*
X689830Y275825D01*
X690700Y276033D01*
X691570Y275825D01*
X692440Y274992D01*
X693020Y273533D01*
X693165Y271867D01*
X693020Y270200D01*
X692440Y268741D01*
X691570Y267908D01*
X690700Y267700D01*
G01X700035D02*
Y280200D01*
G01Y274158D02*
X700760Y275200D01*
X701485Y275825D01*
X702645Y276033D01*
X703515Y275825D01*
X704530Y274992D01*
X704965Y273742D01*
Y267700D01*
G01X709950D02*
Y276033D01*
G01Y273742D02*
X710385Y274783D01*
X711110Y275616D01*
X712125Y276033D01*
X713140Y275616D01*
X713865Y274783D01*
X714300Y273742D01*
Y267700D01*
G01Y273742D02*
X714735Y274783D01*
X715460Y275616D01*
X716475Y276033D01*
X717490Y275616D01*
X718215Y274783D01*
X718650Y273533D01*
Y267700D01*
G01X736305Y271867D02*
X739785D01*
G01X737900Y274575D02*
Y269158D01*
G01X747090Y267283D02*
X752310Y280200D01*
G01X759615Y271867D02*
X763385D01*
G01X785100Y267700D02*
Y280200D01*
X783360Y277700D01*
G01Y267700D02*
X786840D01*
G01X793710Y269575D02*
X794580Y268533D01*
X795595Y267908D01*
X796900Y267700D01*
X798205Y268117D01*
X799220Y268950D01*
X799945Y270408D01*
X800090Y272075D01*
X799800Y273742D01*
X799075Y274783D01*
X798060Y275616D01*
X797045Y275825D01*
X796030Y275616D01*
X794725Y274783D01*
X795160Y280200D01*
X799075D01*
G01X806090Y267283D02*
X811310Y280200D01*
G01X806090D02*
X805220Y279783D01*
X804785Y279158D01*
X804495Y277908D01*
X804785Y276658D01*
X805220Y276033D01*
X806090Y275616D01*
X806960Y276033D01*
X807395Y276658D01*
X807685Y277908D01*
X807395Y279158D01*
X806960Y279783D01*
X806090Y280200D01*
G01X811310Y271867D02*
X810440Y271450D01*
X810005Y270825D01*
X809715Y269575D01*
X810005Y268325D01*
X810440Y267700D01*
X811310Y267283D01*
X812180Y267700D01*
X812615Y268325D01*
X812905Y269575D01*
X812615Y270825D01*
X812180Y271450D01*
X811310Y271867D01*
G01X676410Y-31625D02*
X677280Y-32667D01*
X678295Y-33292D01*
X679600Y-33500D01*
X680905Y-33083D01*
X681920Y-32250D01*
X682645Y-30792D01*
X682790Y-29125D01*
X682500Y-27458D01*
X681775Y-26417D01*
X680760Y-25584D01*
X679745Y-25375D01*
X678730Y-25584D01*
X677425Y-26417D01*
X677860Y-21000D01*
X681775D01*
G01X691400D02*
X690240Y-21417D01*
X689370Y-22458D01*
X688790Y-23708D01*
X688355Y-25375D01*
X688210Y-27250D01*
X688355Y-29125D01*
X688790Y-30792D01*
X689370Y-32042D01*
X690240Y-33083D01*
X691400Y-33500D01*
X692560Y-33083D01*
X693430Y-32042D01*
X694010Y-30792D01*
X694445Y-29125D01*
X694590Y-27250D01*
X694445Y-25375D01*
X694010Y-23708D01*
X693430Y-22458D01*
X692560Y-21417D01*
X691400Y-21000D01*
G01X703200Y-33500D02*
X702330Y-33292D01*
X701460Y-32459D01*
X700880Y-31000D01*
X700590Y-29333D01*
X700880Y-27667D01*
X701460Y-26208D01*
X702330Y-25375D01*
X703200Y-25167D01*
X704070Y-25375D01*
X704940Y-26208D01*
X705520Y-27667D01*
X705665Y-29333D01*
X705520Y-31000D01*
X704940Y-32459D01*
X704070Y-33292D01*
X703200Y-33500D01*
G01X712535D02*
Y-21000D01*
G01Y-27042D02*
X713260Y-26000D01*
X713985Y-25375D01*
X715145Y-25167D01*
X716015Y-25375D01*
X717030Y-26208D01*
X717465Y-27458D01*
Y-33500D01*
G01X722450D02*
Y-25167D01*
G01Y-27458D02*
X722885Y-26417D01*
X723610Y-25584D01*
X724625Y-25167D01*
X725640Y-25584D01*
X726365Y-26417D01*
X726800Y-27458D01*
Y-33500D01*
G01Y-27458D02*
X727235Y-26417D01*
X727960Y-25584D01*
X728975Y-25167D01*
X729990Y-25584D01*
X730715Y-26417D01*
X731150Y-27667D01*
Y-33500D01*
G01X748805Y-29333D02*
X752285D01*
G01X750400Y-26625D02*
Y-32042D01*
G01X759590Y-33917D02*
X764810Y-21000D01*
G01X772115Y-29333D02*
X775885D01*
G01X785800Y-33500D02*
Y-21000D01*
X784060Y-23500D01*
G01Y-33500D02*
X787540D01*
G01X797600Y-21000D02*
X796440Y-21417D01*
X795570Y-22458D01*
X794990Y-23708D01*
X794555Y-25375D01*
X794410Y-27250D01*
X794555Y-29125D01*
X794990Y-30792D01*
X795570Y-32042D01*
X796440Y-33083D01*
X797600Y-33500D01*
X798760Y-33083D01*
X799630Y-32042D01*
X800210Y-30792D01*
X800645Y-29125D01*
X800790Y-27250D01*
X800645Y-25375D01*
X800210Y-23708D01*
X799630Y-22458D01*
X798760Y-21417D01*
X797600Y-21000D01*
G01X806790Y-33917D02*
X812010Y-21000D01*
G01X806790D02*
X805920Y-21417D01*
X805485Y-22042D01*
X805195Y-23292D01*
X805485Y-24542D01*
X805920Y-25167D01*
X806790Y-25584D01*
X807660Y-25167D01*
X808095Y-24542D01*
X808385Y-23292D01*
X808095Y-22042D01*
X807660Y-21417D01*
X806790Y-21000D01*
G01X812010Y-29333D02*
X811140Y-29750D01*
X810705Y-30375D01*
X810415Y-31625D01*
X810705Y-32875D01*
X811140Y-33500D01*
X812010Y-33917D01*
X812880Y-33500D01*
X813315Y-32875D01*
X813605Y-31625D01*
X813315Y-30375D01*
X812880Y-29750D01*
X812010Y-29333D01*
G01X691260Y313400D02*
X694740D01*
G01X693000D02*
Y300900D01*
G01X691260D02*
X694740D01*
G01X701030D02*
Y313400D01*
X704800Y302983D01*
X708570Y313400D01*
Y300900D01*
G01X713700D02*
Y313400D01*
X717180D01*
X718340Y312775D01*
X719210Y311317D01*
X719500Y309650D01*
X719210Y307983D01*
X718485Y306733D01*
X717180Y306108D01*
X713700D01*
G01X731300Y300900D02*
X725500D01*
Y313400D01*
X731300D01*
G01X728980Y307358D02*
X725500D01*
G01X737010Y300900D02*
Y313400D01*
X739910D01*
X741070Y312775D01*
X741940Y311942D01*
X742665Y310692D01*
X743245Y309233D01*
X743390Y307150D01*
X743245Y305067D01*
X742665Y303608D01*
X741940Y302358D01*
X741070Y301525D01*
X739910Y300900D01*
X737010D01*
G01X748375D02*
X752000Y313400D01*
X755625Y300900D01*
G01X754320Y305275D02*
X749680D01*
G01X760465Y300900D02*
Y313400D01*
X767135Y300900D01*
Y313400D01*
G01X778790Y312358D02*
X777920Y312983D01*
X776905Y313400D01*
X775745D01*
X774440Y312775D01*
X773425Y311733D01*
X772700Y310483D01*
X772120Y308400D01*
X771975Y306525D01*
X772265Y304650D01*
X772700Y303400D01*
X773570Y302150D01*
X774585Y301317D01*
X775600Y300900D01*
X776615D01*
X777630Y301317D01*
X778500Y301941D01*
X779225Y302775D01*
G01X790300Y300900D02*
X784500D01*
Y313400D01*
X790300D01*
G01X787980Y307358D02*
X784500D01*
G01X869340Y-84100D02*
Y-71600D01*
X863975Y-80558D01*
X871225D01*
G01X879400Y-84517D02*
X879110Y-84308D01*
Y-83892D01*
X879400Y-83683D01*
X879690Y-83892D01*
Y-84308D01*
X879400Y-84517D01*
G01X892940Y-84100D02*
Y-71600D01*
X887575Y-80558D01*
X894825D01*
G01X912915Y-79933D02*
X916685D01*
G01X935935Y-82642D02*
X936950Y-83683D01*
X938110Y-84100D01*
X939270Y-83683D01*
X940285Y-82434D01*
X941010Y-80558D01*
X941300Y-78683D01*
Y-76392D01*
X941010Y-74517D01*
X940285Y-72850D01*
X939415Y-72017D01*
X938400Y-71600D01*
X937240Y-72017D01*
X936370Y-72850D01*
X935790Y-74100D01*
X935500Y-75767D01*
X935790Y-77225D01*
X936515Y-78683D01*
X937385Y-79517D01*
X938400Y-79725D01*
X939560Y-79309D01*
X940430Y-78267D01*
X941300Y-76392D01*
G01X950200Y-84517D02*
X949910Y-84308D01*
Y-83892D01*
X950200Y-83683D01*
X950490Y-83892D01*
Y-84308D01*
X950200Y-84517D01*
G01X962000Y-84100D02*
Y-71600D01*
X960260Y-74100D01*
G01Y-84100D02*
X963740D01*
G01X983715Y-79933D02*
X987485D01*
G01X1010940Y-84100D02*
Y-71600D01*
X1005575Y-80558D01*
X1012825D01*
G01X1021000Y-84517D02*
X1020710Y-84308D01*
Y-83892D01*
X1021000Y-83683D01*
X1021290Y-83892D01*
Y-84308D01*
X1021000Y-84517D01*
G01X1034540Y-84100D02*
Y-71600D01*
X1029175Y-80558D01*
X1036425D01*
G01X885740Y216500D02*
Y229000D01*
X880375Y220042D01*
X887625D01*
G01X895800Y216083D02*
X895510Y216292D01*
Y216708D01*
X895800Y216917D01*
X896090Y216708D01*
Y216292D01*
X895800Y216083D01*
G01X904845Y226917D02*
X905715Y228166D01*
X906730Y228792D01*
X907890Y229000D01*
X909340Y228583D01*
X910355Y227542D01*
X910645Y226292D01*
X910500Y225041D01*
X909920Y224000D01*
X907020Y221917D01*
X905715Y220458D01*
X904845Y218375D01*
X904555Y216500D01*
X910645D01*
G01X917515Y220667D02*
X921285D01*
G01X931200Y216500D02*
Y229000D01*
X929460Y226500D01*
G01Y216500D02*
X932940D01*
G01X940245Y226917D02*
X941115Y228166D01*
X942130Y228792D01*
X943290Y229000D01*
X944740Y228583D01*
X945755Y227542D01*
X946045Y226292D01*
X945900Y225041D01*
X945320Y224000D01*
X942420Y221917D01*
X941115Y220458D01*
X940245Y218375D01*
X939955Y216500D01*
X946045D01*
G01X954800Y216083D02*
X954510Y216292D01*
Y216708D01*
X954800Y216917D01*
X955090Y216708D01*
Y216292D01*
X954800Y216083D01*
G01X964135Y217958D02*
X965150Y216917D01*
X966310Y216500D01*
X967470Y216917D01*
X968485Y218166D01*
X969210Y220042D01*
X969500Y221917D01*
Y224208D01*
X969210Y226083D01*
X968485Y227750D01*
X967615Y228583D01*
X966600Y229000D01*
X965440Y228583D01*
X964570Y227750D01*
X963990Y226500D01*
X963700Y224833D01*
X963990Y223375D01*
X964715Y221917D01*
X965585Y221083D01*
X966600Y220875D01*
X967760Y221291D01*
X968630Y222333D01*
X969500Y224208D01*
G01X976515Y220667D02*
X980285D01*
G01X991940Y216500D02*
Y229000D01*
X986575Y220042D01*
X993825D01*
G01X1002000Y216083D02*
X1001710Y216292D01*
Y216708D01*
X1002000Y216917D01*
X1002290Y216708D01*
Y216292D01*
X1002000Y216083D01*
G01X1011045Y226917D02*
X1011915Y228166D01*
X1012930Y228792D01*
X1014090Y229000D01*
X1015540Y228583D01*
X1016555Y227542D01*
X1016845Y226292D01*
X1016700Y225041D01*
X1016120Y224000D01*
X1013220Y221917D01*
X1011915Y220458D01*
X1011045Y218375D01*
X1010755Y216500D01*
X1016845D01*
G01X887040Y-209100D02*
Y-196600D01*
X881675Y-205558D01*
X888925D01*
G01X897100Y-209517D02*
X896810Y-209308D01*
Y-208892D01*
X897100Y-208683D01*
X897390Y-208892D01*
Y-209308D01*
X897100Y-209517D01*
G01X906145Y-198683D02*
X907015Y-197434D01*
X908030Y-196808D01*
X909190Y-196600D01*
X910640Y-197017D01*
X911655Y-198058D01*
X911945Y-199308D01*
X911800Y-200559D01*
X911220Y-201600D01*
X908320Y-203683D01*
X907015Y-205142D01*
X906145Y-207225D01*
X905855Y-209100D01*
X911945D01*
G01X918815Y-204933D02*
X922585D01*
G01X932500Y-209100D02*
Y-196600D01*
X930760Y-199100D01*
G01Y-209100D02*
X934240D01*
G01X941545Y-198683D02*
X942415Y-197434D01*
X943430Y-196808D01*
X944590Y-196600D01*
X946040Y-197017D01*
X947055Y-198058D01*
X947345Y-199308D01*
X947200Y-200559D01*
X946620Y-201600D01*
X943720Y-203683D01*
X942415Y-205142D01*
X941545Y-207225D01*
X941255Y-209100D01*
X947345D01*
G01X956100Y-209517D02*
X955810Y-209308D01*
Y-208892D01*
X956100Y-208683D01*
X956390Y-208892D01*
Y-209308D01*
X956100Y-209517D01*
G01X965435Y-207642D02*
X966450Y-208683D01*
X967610Y-209100D01*
X968770Y-208683D01*
X969785Y-207434D01*
X970510Y-205558D01*
X970800Y-203683D01*
Y-201392D01*
X970510Y-199517D01*
X969785Y-197850D01*
X968915Y-197017D01*
X967900Y-196600D01*
X966740Y-197017D01*
X965870Y-197850D01*
X965290Y-199100D01*
X965000Y-200767D01*
X965290Y-202225D01*
X966015Y-203683D01*
X966885Y-204517D01*
X967900Y-204725D01*
X969060Y-204309D01*
X969930Y-203267D01*
X970800Y-201392D01*
G01X977815Y-204933D02*
X981585D01*
G01X993240Y-209100D02*
Y-196600D01*
X987875Y-205558D01*
X995125D01*
G01X1003300Y-209517D02*
X1003010Y-209308D01*
Y-208892D01*
X1003300Y-208683D01*
X1003590Y-208892D01*
Y-209308D01*
X1003300Y-209517D01*
G01X1012345Y-198683D02*
X1013215Y-197434D01*
X1014230Y-196808D01*
X1015390Y-196600D01*
X1016840Y-197017D01*
X1017855Y-198058D01*
X1018145Y-199308D01*
X1018000Y-200559D01*
X1017420Y-201600D01*
X1014520Y-203683D01*
X1013215Y-205142D01*
X1012345Y-207225D01*
X1012055Y-209100D01*
X1018145D01*
G01X882255Y312566D02*
X883415Y311525D01*
X884720Y310900D01*
X885880D01*
X887040Y311525D01*
X887910Y312566D01*
X888345Y314025D01*
X888055Y315483D01*
X887330Y316733D01*
X886025Y317567D01*
X884285Y317983D01*
X883270Y318816D01*
X882835Y320275D01*
X883125Y321733D01*
X883850Y322775D01*
X884865Y323400D01*
X885880D01*
X886895Y322983D01*
X887765Y321942D01*
G01X895360Y323400D02*
X898840D01*
G01X897100D02*
Y310900D01*
G01X895360D02*
X898840D01*
G01X909770Y317150D02*
X912670D01*
Y313400D01*
X911800Y312150D01*
X910785Y311317D01*
X909335Y310900D01*
X907885Y311317D01*
X906870Y312150D01*
X906000Y313400D01*
X905420Y314858D01*
X905130Y316525D01*
Y317983D01*
X905420Y319233D01*
X906000Y320692D01*
X906870Y321942D01*
X907740Y322775D01*
X908900Y323400D01*
X909915D01*
X911075Y322983D01*
X911945Y322150D01*
G01X917365Y310900D02*
Y323400D01*
X924035Y310900D01*
Y323400D01*
G01X928875Y310900D02*
X932500Y323400D01*
X936125Y310900D01*
G01X934820Y315275D02*
X930180D01*
G01X941400Y323400D02*
Y310900D01*
X947200D01*
G01X963550Y323400D02*
X965580Y310900D01*
X967900Y323400D01*
X970220Y310900D01*
X972250Y323400D01*
G01X977960D02*
X981440D01*
G01X979700D02*
Y310900D01*
G01X977960D02*
X981440D01*
G01X988310D02*
Y323400D01*
X991210D01*
X992370Y322775D01*
X993240Y321942D01*
X993965Y320692D01*
X994545Y319233D01*
X994690Y317150D01*
X994545Y315067D01*
X993965Y313608D01*
X993240Y312358D01*
X992370Y311525D01*
X991210Y310900D01*
X988310D01*
G01X1003300Y323400D02*
Y310900D01*
G01X999965Y323400D02*
X1006635D01*
G01X1012055Y310900D02*
Y323400D01*
G01X1018145D02*
Y310900D01*
G01Y317150D02*
X1012055D01*
G01X907910Y-55125D02*
X908780Y-56167D01*
X909795Y-56792D01*
X911100Y-57000D01*
X912405Y-56583D01*
X913420Y-55750D01*
X914145Y-54292D01*
X914290Y-52625D01*
X914000Y-50958D01*
X913275Y-49917D01*
X912260Y-49084D01*
X911245Y-48875D01*
X910230Y-49084D01*
X908925Y-49917D01*
X909360Y-44500D01*
X913275D01*
G01X921015Y-52833D02*
X924785D01*
G01X931945Y-51792D02*
X932960Y-50333D01*
X933830Y-49500D01*
X934990Y-49084D01*
X936005Y-49500D01*
X936730Y-50333D01*
X937310Y-51583D01*
X937455Y-53042D01*
X937310Y-54292D01*
X936730Y-55542D01*
X935860Y-56583D01*
X934845Y-57000D01*
X933685Y-56583D01*
X932670Y-55334D01*
X932090Y-53458D01*
X931945Y-51375D01*
X932235Y-48667D01*
X932670Y-47208D01*
X933395Y-45750D01*
X934410Y-44708D01*
X935425Y-44500D01*
X936440Y-44917D01*
X937165Y-45958D01*
G01X946500Y-57417D02*
X946210Y-57208D01*
Y-56792D01*
X946500Y-56583D01*
X946790Y-56792D01*
Y-57208D01*
X946500Y-57417D01*
G01X955110Y-55125D02*
X955980Y-56167D01*
X956995Y-56792D01*
X958300Y-57000D01*
X959605Y-56583D01*
X960620Y-55750D01*
X961345Y-54292D01*
X961490Y-52625D01*
X961200Y-50958D01*
X960475Y-49917D01*
X959460Y-49084D01*
X958445Y-48875D01*
X957430Y-49084D01*
X956125Y-49917D01*
X956560Y-44500D01*
X960475D01*
G01X968215Y-52833D02*
X971985D01*
G01X978710Y-55125D02*
X979580Y-56167D01*
X980595Y-56792D01*
X981900Y-57000D01*
X983205Y-56583D01*
X984220Y-55750D01*
X984945Y-54292D01*
X985090Y-52625D01*
X984800Y-50958D01*
X984075Y-49917D01*
X983060Y-49084D01*
X982045Y-48875D01*
X981030Y-49084D01*
X979725Y-49917D01*
X980160Y-44500D01*
X984075D01*
G01X907410Y-31125D02*
X908280Y-32167D01*
X909295Y-32792D01*
X910600Y-33000D01*
X911905Y-32583D01*
X912920Y-31750D01*
X913645Y-30292D01*
X913790Y-28625D01*
X913500Y-26958D01*
X912775Y-25917D01*
X911760Y-25084D01*
X910745Y-24875D01*
X909730Y-25084D01*
X908425Y-25917D01*
X908860Y-20500D01*
X912775D01*
G01X922400Y-33417D02*
X922110Y-33208D01*
Y-32792D01*
X922400Y-32583D01*
X922690Y-32792D01*
Y-33208D01*
X922400Y-33417D01*
G01X934200Y-33000D02*
Y-20500D01*
X932460Y-23000D01*
G01Y-33000D02*
X935940D01*
G01X954030D02*
Y-20500D01*
X957800Y-30917D01*
X961570Y-20500D01*
Y-33000D01*
G01X967860Y-20500D02*
X971340D01*
G01X969600D02*
Y-33000D01*
G01X967860D02*
X971340D01*
G01X978500Y-20500D02*
Y-33000D01*
X984300D01*
G01X900610Y115275D02*
X901480Y114233D01*
X902495Y113608D01*
X903800Y113400D01*
X905105Y113817D01*
X906120Y114650D01*
X906845Y116108D01*
X906990Y117775D01*
X906700Y119442D01*
X905975Y120483D01*
X904960Y121316D01*
X903945Y121525D01*
X902930Y121316D01*
X901625Y120483D01*
X902060Y125900D01*
X905975D01*
G01X913715Y117567D02*
X917485D01*
G01X924645Y118608D02*
X925660Y120067D01*
X926530Y120900D01*
X927690Y121316D01*
X928705Y120900D01*
X929430Y120067D01*
X930010Y118817D01*
X930155Y117358D01*
X930010Y116108D01*
X929430Y114858D01*
X928560Y113817D01*
X927545Y113400D01*
X926385Y113817D01*
X925370Y115066D01*
X924790Y116942D01*
X924645Y119025D01*
X924935Y121733D01*
X925370Y123192D01*
X926095Y124650D01*
X927110Y125692D01*
X928125Y125900D01*
X929140Y125483D01*
X929865Y124442D01*
G01X939200Y112983D02*
X938910Y113192D01*
Y113608D01*
X939200Y113817D01*
X939490Y113608D01*
Y113192D01*
X939200Y112983D01*
G01X947810Y115275D02*
X948680Y114233D01*
X949695Y113608D01*
X951000Y113400D01*
X952305Y113817D01*
X953320Y114650D01*
X954045Y116108D01*
X954190Y117775D01*
X953900Y119442D01*
X953175Y120483D01*
X952160Y121316D01*
X951145Y121525D01*
X950130Y121316D01*
X948825Y120483D01*
X949260Y125900D01*
X953175D01*
G01X960915Y117567D02*
X964685D01*
G01X971410Y115275D02*
X972280Y114233D01*
X973295Y113608D01*
X974600Y113400D01*
X975905Y113817D01*
X976920Y114650D01*
X977645Y116108D01*
X977790Y117775D01*
X977500Y119442D01*
X976775Y120483D01*
X975760Y121316D01*
X974745Y121525D01*
X973730Y121316D01*
X972425Y120483D01*
X972860Y125900D01*
X976775D01*
G01X907110Y143275D02*
X907980Y142233D01*
X908995Y141608D01*
X910300Y141400D01*
X911605Y141817D01*
X912620Y142650D01*
X913345Y144108D01*
X913490Y145775D01*
X913200Y147442D01*
X912475Y148483D01*
X911460Y149316D01*
X910445Y149525D01*
X909430Y149316D01*
X908125Y148483D01*
X908560Y153900D01*
X912475D01*
G01X922100Y140983D02*
X921810Y141192D01*
Y141608D01*
X922100Y141817D01*
X922390Y141608D01*
Y141192D01*
X922100Y140983D01*
G01X933900Y141400D02*
Y153900D01*
X932160Y151400D01*
G01Y141400D02*
X935640D01*
G01X953730D02*
Y153900D01*
X957500Y143483D01*
X961270Y153900D01*
Y141400D01*
G01X967560Y153900D02*
X971040D01*
G01X969300D02*
Y141400D01*
G01X967560D02*
X971040D01*
G01X978200Y153900D02*
Y141400D01*
X984000D01*
G01X923410Y-182225D02*
X924280Y-183267D01*
X925295Y-183892D01*
X926600Y-184100D01*
X927905Y-183683D01*
X928920Y-182850D01*
X929645Y-181392D01*
X929790Y-179725D01*
X929500Y-178058D01*
X928775Y-177017D01*
X927760Y-176184D01*
X926745Y-175975D01*
X925730Y-176184D01*
X924425Y-177017D01*
X924860Y-171600D01*
X928775D01*
G01X936515Y-179933D02*
X940285D01*
G01X949910Y-184100D02*
X950200Y-181392D01*
X950635Y-179100D01*
X951215Y-177017D01*
X951940Y-174725D01*
X953100Y-171600D01*
X947300D01*
G01X960115Y-179933D02*
X963885D01*
G01X970610Y-182225D02*
X971480Y-183267D01*
X972495Y-183892D01*
X973800Y-184100D01*
X975105Y-183683D01*
X976120Y-182850D01*
X976845Y-181392D01*
X976990Y-179725D01*
X976700Y-178058D01*
X975975Y-177017D01*
X974960Y-176184D01*
X973945Y-175975D01*
X972930Y-176184D01*
X971625Y-177017D01*
X972060Y-171600D01*
X975975D01*
G01X928340Y-159100D02*
Y-146600D01*
X922975Y-155558D01*
X930225D01*
G01X946430Y-159100D02*
Y-146600D01*
X950200Y-157017D01*
X953970Y-146600D01*
Y-159100D01*
G01X960260Y-146600D02*
X963740D01*
G01X962000D02*
Y-159100D01*
G01X960260D02*
X963740D01*
G01X970900Y-146600D02*
Y-159100D01*
X976700D01*
G01X922110Y243375D02*
X922980Y242333D01*
X923995Y241708D01*
X925300Y241500D01*
X926605Y241917D01*
X927620Y242750D01*
X928345Y244208D01*
X928490Y245875D01*
X928200Y247542D01*
X927475Y248583D01*
X926460Y249417D01*
X925445Y249625D01*
X924430Y249417D01*
X923125Y248583D01*
X923560Y254000D01*
X927475D01*
G01X935215Y245667D02*
X938985D01*
G01X948610Y241500D02*
X948900Y244208D01*
X949335Y246500D01*
X949915Y248583D01*
X950640Y250875D01*
X951800Y254000D01*
X946000D01*
G01X958815Y245667D02*
X962585D01*
G01X969310Y243375D02*
X970180Y242333D01*
X971195Y241708D01*
X972500Y241500D01*
X973805Y241917D01*
X974820Y242750D01*
X975545Y244208D01*
X975690Y245875D01*
X975400Y247542D01*
X974675Y248583D01*
X973660Y249417D01*
X972645Y249625D01*
X971630Y249417D01*
X970325Y248583D01*
X970760Y254000D01*
X974675D01*
G01X928340Y265900D02*
Y278400D01*
X922975Y269442D01*
X930225D01*
G01X946430Y265900D02*
Y278400D01*
X950200Y267983D01*
X953970Y278400D01*
Y265900D01*
G01X960260Y278400D02*
X963740D01*
G01X962000D02*
Y265900D01*
G01X960260D02*
X963740D01*
G01X970900Y278400D02*
Y265900D01*
X976700D01*
G54D15*
X-1670620Y457670D03*
X-1488693Y-178940D03*
X-1476693Y-64840D03*
X-618614Y-178940D03*
X-606614Y-64840D03*
G54D24*
X-1670620Y668270D03*
X-1327756Y-175039D03*
Y-167165D03*
Y-159291D03*
Y-143543D03*
Y-135669D03*
Y-127795D03*
X-1319882Y-175039D03*
Y-167165D03*
Y-159291D03*
Y-143543D03*
Y-135669D03*
Y-127795D03*
X-1296260Y-175039D03*
X-1304134D03*
X-1296260Y-167165D03*
X-1304134D03*
X-1296260Y-159291D03*
X-1304134D03*
X-1296260Y-143543D03*
X-1304134D03*
X-1296260Y-135669D03*
X-1304134D03*
X-1296260Y-127795D03*
X-1304134D03*
X-457677Y-175039D03*
Y-167165D03*
Y-159291D03*
Y-143543D03*
Y-135669D03*
Y-127795D03*
X-449803Y-175039D03*
Y-167165D03*
Y-159291D03*
Y-143543D03*
Y-135669D03*
Y-127795D03*
X-426181Y-175039D03*
X-434055D03*
X-426181Y-167165D03*
X-434055D03*
X-426181Y-159291D03*
X-434055D03*
X-426181Y-143543D03*
X-434055D03*
X-426181Y-135669D03*
X-434055D03*
X-426181Y-127795D03*
X-434055D03*
G54D34*
G01X-1900000Y250000D02*
X-1910000Y255000D01*
Y245000D01*
X-1900000Y250000D01*
G01Y-800000D02*
X1400000D01*
Y1300000D01*
X-1900000D01*
Y-800000D01*
G01X-1670000Y1300000D02*
Y1205000D01*
X-1900000D01*
G01X-200000Y-800000D02*
X-205000Y-810000D01*
X-195000D01*
X-200000Y-800000D01*
G01Y1300000D02*
X-195000Y1310000D01*
X-205000D01*
X-200000Y1300000D01*
G01X1400000Y250000D02*
X1410000Y245000D01*
Y255000D01*
X1400000Y250000D01*
G54D25*
X-1670620Y691670D03*
X-1025000Y-50942D03*
Y1459D03*
X-1015157Y-105312D03*
X-997441D03*
X-981693Y-50942D03*
Y1459D03*
X-971850Y-105312D03*
X-954134D03*
X-938386Y-50942D03*
Y1459D03*
X-145079Y-105312D03*
X-154921Y-50942D03*
Y1459D03*
X-127362Y-105312D03*
X-111614Y-50942D03*
Y1459D03*
X-101772Y-105312D03*
X-84055D03*
X-68307Y-50942D03*
Y1459D03*
G54D16*
X-1670620Y481070D03*
X-1356889Y-145000D03*
X-1051613D03*
X-486810D03*
X-181534D03*
G54D35*
G01X-1900000Y-300000D02*
X-1950000D01*
G01Y250000D02*
X-1900000D01*
G01Y800000D02*
X-1950000D01*
G01X-1475000Y-800000D02*
Y-850000D01*
G01Y1350000D02*
Y1300000D01*
G01X-1050000Y-800000D02*
Y-850000D01*
G01Y1350000D02*
Y1300000D01*
G01X-625000Y-800000D02*
Y-850000D01*
G01Y1350000D02*
Y1300000D01*
G01X-200000Y-800000D02*
Y-850000D01*
G01Y1350000D02*
Y1300000D01*
G01X225000Y-800000D02*
Y-850000D01*
G01Y1350000D02*
Y1300000D01*
G01X650000Y-800000D02*
Y-850000D01*
G01Y1350000D02*
Y1300000D01*
G01X1018890Y-701240D02*
Y-716240D01*
G01X1014865Y-701240D02*
X1022915D01*
G01X1030640Y-716240D02*
Y-706240D01*
G01Y-708240D02*
X1031515Y-707240D01*
X1032390Y-706490D01*
X1033615Y-706240D01*
X1034490Y-706490D01*
X1035540Y-707240D01*
G01X1050440Y-716240D02*
Y-706240D01*
G01Y-707990D02*
X1049740Y-706990D01*
X1048690Y-706490D01*
X1047465Y-706240D01*
X1046240Y-706740D01*
X1045190Y-707740D01*
X1044490Y-709240D01*
X1044140Y-711240D01*
X1044490Y-713240D01*
X1045190Y-714740D01*
X1046240Y-715740D01*
X1047465Y-716240D01*
X1048690Y-715990D01*
X1049740Y-715240D01*
X1050440Y-714240D01*
G01X1057815Y-720740D02*
X1058865Y-721240D01*
X1060265Y-720740D01*
X1061140Y-719740D01*
X1061840Y-718490D01*
X1062890Y-714490D01*
X1065165Y-706240D01*
G01X1059565D02*
X1062890Y-714490D01*
G01X1091290Y-708240D02*
X1091990Y-707490D01*
X1092515Y-706240D01*
X1092865Y-704490D01*
X1092515Y-702990D01*
X1091815Y-701990D01*
X1090590Y-701240D01*
X1085865D01*
Y-716240D01*
X1091640D01*
X1092865Y-715240D01*
X1093565Y-713740D01*
X1093915Y-711990D01*
X1093565Y-710240D01*
X1092515Y-708740D01*
X1091290Y-708240D01*
X1085865D01*
G01X1107240Y-716240D02*
Y-706240D01*
G01Y-707990D02*
X1106540Y-706990D01*
X1105490Y-706490D01*
X1104265Y-706240D01*
X1103040Y-706740D01*
X1101990Y-707740D01*
X1101290Y-709240D01*
X1100940Y-711240D01*
X1101290Y-713240D01*
X1101990Y-714740D01*
X1103040Y-715740D01*
X1104265Y-716240D01*
X1105490Y-715990D01*
X1106540Y-715240D01*
X1107240Y-714240D01*
G01X1121090Y-707490D02*
X1119865Y-706490D01*
X1118815Y-706240D01*
X1117415Y-706740D01*
X1116365Y-707740D01*
X1115665Y-709490D01*
X1115490Y-711240D01*
X1115665Y-712990D01*
X1116365Y-714490D01*
X1117415Y-715740D01*
X1118815Y-716240D01*
X1120040Y-715740D01*
X1121090Y-714740D01*
G01X1129515Y-716240D02*
Y-701240D01*
G01X1135115Y-706240D02*
X1129515Y-711990D01*
G01X1131790Y-709740D02*
X1135465Y-716240D01*
G01X1143540Y-721240D02*
Y-706240D01*
G01Y-708490D02*
X1144415Y-707240D01*
X1145290Y-706490D01*
X1146690Y-706240D01*
X1147915Y-706490D01*
X1149140Y-707740D01*
X1149665Y-709490D01*
X1149840Y-711240D01*
X1149665Y-712990D01*
X1149140Y-714740D01*
X1148090Y-715740D01*
X1146690Y-716240D01*
X1145465Y-715990D01*
X1144240Y-715240D01*
X1143540Y-714240D01*
G01X1160890Y-716240D02*
Y-701240D01*
G01X1178240Y-716240D02*
Y-706240D01*
G01Y-707990D02*
X1177540Y-706990D01*
X1176490Y-706490D01*
X1175265Y-706240D01*
X1174040Y-706740D01*
X1172990Y-707740D01*
X1172290Y-709240D01*
X1171940Y-711240D01*
X1172290Y-713240D01*
X1172990Y-714740D01*
X1174040Y-715740D01*
X1175265Y-716240D01*
X1176490Y-715990D01*
X1177540Y-715240D01*
X1178240Y-714240D01*
G01X1186315Y-716240D02*
Y-706240D01*
G01Y-708740D02*
X1187015Y-707490D01*
X1188065Y-706490D01*
X1189465Y-706240D01*
X1190690Y-706490D01*
X1191740Y-707490D01*
X1192265Y-709240D01*
Y-716240D01*
G01X1200865Y-709490D02*
X1206465D01*
X1205940Y-707740D01*
X1205065Y-706740D01*
X1203840Y-706240D01*
X1202615Y-706490D01*
X1201565Y-707240D01*
X1200865Y-708990D01*
X1200515Y-710490D01*
Y-711990D01*
X1200865Y-713490D01*
X1201740Y-714990D01*
X1202790Y-715990D01*
X1204015Y-716240D01*
X1205240Y-715740D01*
X1206465Y-714240D01*
G01X1228390Y-716240D02*
Y-701240D01*
X1232590D01*
X1233990Y-701990D01*
X1235040Y-703740D01*
X1235390Y-705740D01*
X1235040Y-707740D01*
X1234165Y-709240D01*
X1232590Y-709990D01*
X1228390D01*
G01X1249940Y-702490D02*
X1248890Y-701740D01*
X1247665Y-701240D01*
X1246265D01*
X1244690Y-701990D01*
X1243465Y-703240D01*
X1242590Y-704740D01*
X1241890Y-707240D01*
X1241715Y-709490D01*
X1242065Y-711740D01*
X1242590Y-713240D01*
X1243640Y-714740D01*
X1244865Y-715740D01*
X1246090Y-716240D01*
X1247315D01*
X1248540Y-715740D01*
X1249590Y-714990D01*
X1250465Y-713990D01*
G01X1261690Y-708240D02*
X1262390Y-707490D01*
X1262915Y-706240D01*
X1263265Y-704490D01*
X1262915Y-702990D01*
X1262215Y-701990D01*
X1260990Y-701240D01*
X1256265D01*
Y-716240D01*
X1262040D01*
X1263265Y-715240D01*
X1263965Y-713740D01*
X1264315Y-711990D01*
X1263965Y-710240D01*
X1262915Y-708740D01*
X1261690Y-708240D01*
X1256265D01*
G01X1290090D02*
X1290790Y-707490D01*
X1291315Y-706240D01*
X1291665Y-704490D01*
X1291315Y-702990D01*
X1290615Y-701990D01*
X1289390Y-701240D01*
X1284665D01*
Y-716240D01*
X1290440D01*
X1291665Y-715240D01*
X1292365Y-713740D01*
X1292715Y-711990D01*
X1292365Y-710240D01*
X1291315Y-708740D01*
X1290090Y-708240D01*
X1284665D01*
G01X1316215Y-721240D02*
X1314465Y-718740D01*
X1313590Y-716240D01*
Y-706240D01*
X1314465Y-703740D01*
X1316215Y-701240D01*
G01X1331290Y-716240D02*
X1329890Y-715990D01*
X1328665Y-714990D01*
X1327615Y-713490D01*
X1326915Y-711740D01*
X1326565Y-709740D01*
Y-707740D01*
X1326915Y-705740D01*
X1327615Y-703990D01*
X1328665Y-702490D01*
X1329890Y-701490D01*
X1331290Y-701240D01*
X1332690Y-701490D01*
X1333915Y-702490D01*
X1334965Y-703990D01*
X1335665Y-705740D01*
X1336015Y-707740D01*
Y-709740D01*
X1335665Y-711740D01*
X1334965Y-713490D01*
X1333915Y-714990D01*
X1332690Y-715990D01*
X1331290Y-716240D01*
G01X1341815Y-714240D02*
X1343215Y-715490D01*
X1344790Y-716240D01*
X1346190D01*
X1347590Y-715490D01*
X1348640Y-714240D01*
X1349165Y-712490D01*
X1348815Y-710740D01*
X1347940Y-709240D01*
X1346365Y-708240D01*
X1344265Y-707740D01*
X1343040Y-706740D01*
X1342515Y-704990D01*
X1342865Y-703240D01*
X1343740Y-701990D01*
X1344965Y-701240D01*
X1346190D01*
X1347415Y-701740D01*
X1348465Y-702990D01*
G01X1356190Y-716240D02*
Y-701240D01*
X1360390D01*
X1361790Y-701990D01*
X1362840Y-703740D01*
X1363190Y-705740D01*
X1362840Y-707740D01*
X1361965Y-709240D01*
X1360390Y-709990D01*
X1356190D01*
G01X1374765Y-721240D02*
X1376515Y-718740D01*
X1377390Y-716240D01*
Y-706240D01*
X1376515Y-703740D01*
X1374765Y-701240D01*
G01X1063785Y-680640D02*
Y-665640D01*
X1070435D01*
G01X1067985Y-672890D02*
X1063785D01*
G01X1084460Y-680640D02*
Y-670640D01*
G01Y-672390D02*
X1083760Y-671390D01*
X1082710Y-670890D01*
X1081485Y-670640D01*
X1080260Y-671140D01*
X1079210Y-672140D01*
X1078510Y-673640D01*
X1078160Y-675640D01*
X1078510Y-677640D01*
X1079210Y-679140D01*
X1080260Y-680140D01*
X1081485Y-680640D01*
X1082710Y-680390D01*
X1083760Y-679640D01*
X1084460Y-678640D01*
G01X1092360Y-680640D02*
Y-665640D01*
G01Y-673140D02*
X1093235Y-671640D01*
X1094285Y-670890D01*
X1095335Y-670640D01*
X1096910Y-671140D01*
X1097960Y-672140D01*
X1098660Y-673890D01*
Y-675890D01*
X1098310Y-677890D01*
X1097610Y-679390D01*
X1096385Y-680390D01*
X1095335Y-680640D01*
X1094285Y-680390D01*
X1093235Y-679640D01*
X1092360Y-678390D01*
G01X1107260Y-680640D02*
Y-670640D01*
G01Y-672640D02*
X1108135Y-671640D01*
X1109010Y-670890D01*
X1110235Y-670640D01*
X1111110Y-670890D01*
X1112160Y-671640D01*
G01X1123910Y-670640D02*
Y-680640D01*
G01Y-666640D02*
X1123560Y-666390D01*
Y-665890D01*
X1123910Y-665640D01*
X1124260Y-665890D01*
Y-666390D01*
X1123910Y-666640D01*
G01X1140910Y-671890D02*
X1139685Y-670890D01*
X1138635Y-670640D01*
X1137235Y-671140D01*
X1136185Y-672140D01*
X1135485Y-673890D01*
X1135310Y-675640D01*
X1135485Y-677390D01*
X1136185Y-678890D01*
X1137235Y-680140D01*
X1138635Y-680640D01*
X1139860Y-680140D01*
X1140910Y-679140D01*
G01X1155460Y-680640D02*
Y-670640D01*
G01Y-672390D02*
X1154760Y-671390D01*
X1153710Y-670890D01*
X1152485Y-670640D01*
X1151260Y-671140D01*
X1150210Y-672140D01*
X1149510Y-673640D01*
X1149160Y-675640D01*
X1149510Y-677640D01*
X1150210Y-679140D01*
X1151260Y-680140D01*
X1152485Y-680640D01*
X1153710Y-680390D01*
X1154760Y-679640D01*
X1155460Y-678640D01*
G01X1166510Y-665640D02*
Y-680640D01*
G01X1164060Y-670640D02*
X1168960D01*
G01X1180710D02*
Y-680640D01*
G01Y-666640D02*
X1180360Y-666390D01*
Y-665890D01*
X1180710Y-665640D01*
X1181060Y-665890D01*
Y-666390D01*
X1180710Y-666640D01*
G01X1194910Y-680640D02*
X1193860Y-680390D01*
X1192810Y-679390D01*
X1192110Y-677640D01*
X1191760Y-675640D01*
X1192110Y-673640D01*
X1192810Y-671890D01*
X1193860Y-670890D01*
X1194910Y-670640D01*
X1195960Y-670890D01*
X1197010Y-671890D01*
X1197710Y-673640D01*
X1197885Y-675640D01*
X1197710Y-677640D01*
X1197010Y-679390D01*
X1195960Y-680390D01*
X1194910Y-680640D01*
G01X1206135D02*
Y-670640D01*
G01Y-673140D02*
X1206835Y-671890D01*
X1207885Y-670890D01*
X1209285Y-670640D01*
X1210510Y-670890D01*
X1211560Y-671890D01*
X1212085Y-673640D01*
Y-680640D01*
G01X1233660D02*
Y-665640D01*
X1237160D01*
X1238560Y-666390D01*
X1239610Y-667390D01*
X1240485Y-668890D01*
X1241185Y-670640D01*
X1241360Y-673140D01*
X1241185Y-675640D01*
X1240485Y-677390D01*
X1239610Y-678890D01*
X1238560Y-679890D01*
X1237160Y-680640D01*
X1233660D01*
G01X1249260D02*
Y-670640D01*
G01Y-672640D02*
X1250135Y-671640D01*
X1251010Y-670890D01*
X1252235Y-670640D01*
X1253110Y-670890D01*
X1254160Y-671640D01*
G01X1269060Y-680640D02*
Y-670640D01*
G01Y-672390D02*
X1268360Y-671390D01*
X1267310Y-670890D01*
X1266085Y-670640D01*
X1264860Y-671140D01*
X1263810Y-672140D01*
X1263110Y-673640D01*
X1262760Y-675640D01*
X1263110Y-677640D01*
X1263810Y-679140D01*
X1264860Y-680140D01*
X1266085Y-680640D01*
X1267310Y-680390D01*
X1268360Y-679640D01*
X1269060Y-678640D01*
G01X1275735Y-670640D02*
X1277835Y-680640D01*
X1280110Y-670640D01*
X1282385Y-680640D01*
X1284485Y-670640D01*
G01X1294310D02*
Y-680640D01*
G01Y-666640D02*
X1293960Y-666390D01*
Y-665890D01*
X1294310Y-665640D01*
X1294660Y-665890D01*
Y-666390D01*
X1294310Y-666640D01*
G01X1305535Y-680640D02*
Y-670640D01*
G01Y-673140D02*
X1306235Y-671890D01*
X1307285Y-670890D01*
X1308685Y-670640D01*
X1309910Y-670890D01*
X1310960Y-671890D01*
X1311485Y-673640D01*
Y-680640D01*
G01X1320260Y-684390D02*
X1321485Y-685390D01*
X1322885Y-685640D01*
X1324110Y-685390D01*
X1325160Y-684140D01*
X1325860Y-682390D01*
Y-670640D01*
G01Y-672640D02*
X1325160Y-671640D01*
X1324110Y-670890D01*
X1322885Y-670640D01*
X1321485Y-671140D01*
X1320610Y-672140D01*
X1319910Y-673890D01*
X1319560Y-675640D01*
X1319735Y-677140D01*
X1320435Y-678890D01*
X1321485Y-680140D01*
X1322885Y-680640D01*
X1323935Y-680390D01*
X1325160Y-679390D01*
X1325860Y-678390D01*
G01X1075000Y-800000D02*
Y-850000D01*
G01Y1350000D02*
Y1300000D01*
G01X1450000Y-300000D02*
X1400000D01*
G01Y250000D02*
X1450000D01*
G01Y800000D02*
X1400000D01*
G54D17*
X-1670620Y504470D03*
X-1645906Y-167953D03*
X-1522728Y-154950D03*
X-1047676Y-78740D03*
X-652638Y-154950D03*
X-177597Y-78740D03*
X6890Y-167953D03*
G54D26*
X-1670620Y715070D03*
X-1615984Y-173071D03*
Y-178583D03*
Y-167559D03*
X-1608110Y-172677D03*
Y-178189D03*
Y-167165D03*
X-1615984Y-162047D03*
Y-151024D03*
Y-156535D03*
X-1608110Y-161654D03*
Y-150630D03*
Y-156142D03*
X-1615984Y-134488D03*
Y-140000D03*
Y-145512D03*
X-1608110Y-134094D03*
Y-139606D03*
Y-145118D03*
X-1615984Y-128976D03*
Y-123465D03*
Y-117953D03*
X-1608110Y-128583D03*
Y-123071D03*
Y-117559D03*
X-1615984Y-112441D03*
Y-106929D03*
Y-101417D03*
X-1608110Y-112047D03*
Y-106535D03*
Y-101024D03*
X-1615984Y-95906D03*
X-1600236Y-167559D03*
X-1592362Y-167165D03*
X-1600236Y-173071D03*
X-1592362Y-172677D03*
X-1600236Y-178583D03*
X-1592362Y-178189D03*
X-1600236Y-151024D03*
X-1592362Y-150630D03*
X-1600236Y-156535D03*
X-1592362Y-156142D03*
X-1600236Y-162047D03*
X-1592362Y-161654D03*
X-1600236Y-134488D03*
X-1592362Y-134094D03*
X-1600236Y-140000D03*
X-1592362Y-139606D03*
X-1600236Y-145512D03*
X-1592362Y-145118D03*
X-1600236Y-128976D03*
Y-117953D03*
Y-123465D03*
X-1592362Y-128583D03*
Y-117559D03*
Y-123071D03*
X-1600236Y-101417D03*
Y-106929D03*
Y-112441D03*
X-1592362Y-101024D03*
Y-106535D03*
Y-112047D03*
X-1600236Y-95906D03*
X-1584488Y-167559D03*
X-1576614Y-167165D03*
X-1584488Y-173071D03*
X-1576614Y-172677D03*
X-1584488Y-178583D03*
X-1576614Y-178189D03*
X-1584488Y-151024D03*
X-1576614Y-150630D03*
X-1584488Y-156535D03*
X-1576614Y-156142D03*
X-1584488Y-162047D03*
X-1576614Y-161654D03*
X-1584488Y-134488D03*
X-1576614Y-134094D03*
X-1584488Y-140000D03*
X-1576614Y-139606D03*
X-1584488Y-145512D03*
X-1576614Y-145118D03*
X-1584488Y-128976D03*
X-1576614Y-128583D03*
X-1584488Y-117953D03*
X-1576614Y-117559D03*
X-1584488Y-123465D03*
X-1576614Y-123071D03*
X-1584488Y-101417D03*
X-1576614Y-101024D03*
X-1584488Y-106929D03*
X-1576614Y-106535D03*
X-1584488Y-112441D03*
X-1576614Y-112047D03*
X-1584488Y-95906D03*
X-1568740Y-167559D03*
X-1560866Y-167165D03*
X-1568740Y-173071D03*
X-1560866Y-172677D03*
X-1568740Y-178583D03*
X-1560866Y-178189D03*
X-1568740Y-151024D03*
X-1560866Y-150630D03*
X-1568740Y-156535D03*
X-1560866Y-156142D03*
X-1568740Y-162047D03*
X-1560866Y-161654D03*
X-1568740Y-134488D03*
X-1560866Y-134094D03*
X-1568740Y-140000D03*
X-1560866Y-139606D03*
X-1568740Y-145512D03*
X-1560866Y-145118D03*
X-1568740Y-128976D03*
Y-117953D03*
Y-123465D03*
X-1560866Y-128583D03*
Y-117559D03*
Y-123071D03*
X-1568740Y-101417D03*
Y-106929D03*
Y-112441D03*
X-1560866Y-101024D03*
Y-106535D03*
Y-112047D03*
X-1568740Y-95906D03*
X-1552992Y-167559D03*
X-1545118Y-167165D03*
X-1552992Y-173071D03*
X-1545118Y-172677D03*
X-1552992Y-178583D03*
X-1545118Y-178189D03*
X-1552992Y-151024D03*
X-1545118Y-150630D03*
X-1552992Y-156535D03*
X-1545118Y-156142D03*
X-1552992Y-162047D03*
X-1545118Y-161654D03*
X-1552992Y-134488D03*
X-1545118Y-134094D03*
X-1552992Y-140000D03*
X-1545118Y-139606D03*
X-1552992Y-145512D03*
X-1545118Y-145118D03*
X-1552992Y-128976D03*
Y-117953D03*
Y-123465D03*
X-1545118Y-128583D03*
Y-117559D03*
Y-123071D03*
X-1552992Y-101417D03*
Y-106929D03*
Y-112441D03*
X-1545118Y-101024D03*
Y-106535D03*
Y-112047D03*
X-1552992Y-95906D03*
X-1197008Y-167953D03*
X-1189134Y-167559D03*
X-1197008Y-173465D03*
X-1189134Y-173071D03*
X-1197008Y-178976D03*
X-1189134Y-178583D03*
X-1197008Y-151417D03*
X-1189134Y-151024D03*
X-1197008Y-156929D03*
X-1189134Y-156535D03*
X-1197008Y-162441D03*
X-1189134Y-162047D03*
X-1197008Y-134882D03*
X-1189134Y-134488D03*
X-1197008Y-140394D03*
X-1189134Y-140000D03*
X-1197008Y-145906D03*
X-1189134Y-145512D03*
X-1197008Y-129370D03*
X-1181260Y-167953D03*
X-1173386Y-167559D03*
X-1181260Y-173465D03*
X-1173386Y-173071D03*
X-1181260Y-178976D03*
X-1173386Y-178583D03*
X-1181260Y-151417D03*
X-1173386Y-151024D03*
X-1181260Y-156929D03*
X-1173386Y-156535D03*
X-1181260Y-162441D03*
X-1173386Y-162047D03*
X-1181260Y-134882D03*
X-1173386Y-134488D03*
X-1181260Y-140394D03*
X-1173386Y-140000D03*
X-1181260Y-145906D03*
X-1173386Y-145512D03*
X-1181260Y-129370D03*
X-1165512Y-167953D03*
X-1157638Y-167559D03*
X-1165512Y-173465D03*
X-1157638Y-173071D03*
X-1165512Y-178976D03*
X-1157638Y-178583D03*
X-1165512Y-151417D03*
X-1157638Y-151024D03*
X-1165512Y-156929D03*
X-1157638Y-156535D03*
X-1165512Y-162441D03*
X-1157638Y-162047D03*
X-1165512Y-134882D03*
X-1157638Y-134488D03*
X-1165512Y-140394D03*
X-1157638Y-140000D03*
X-1165512Y-145906D03*
X-1157638Y-145512D03*
X-1165512Y-129370D03*
X-1014488Y-167953D03*
Y-173465D03*
Y-178976D03*
Y-151417D03*
Y-156929D03*
Y-162441D03*
Y-134882D03*
Y-140394D03*
Y-145906D03*
Y-129370D03*
X-1006614Y-167559D03*
X-998740Y-167953D03*
X-1006614Y-173071D03*
X-998740Y-173465D03*
X-1006614Y-178583D03*
X-998740Y-178976D03*
X-1006614Y-151024D03*
X-998740Y-151417D03*
X-1006614Y-156535D03*
X-998740Y-156929D03*
X-1006614Y-162047D03*
X-998740Y-162441D03*
X-1006614Y-134488D03*
X-998740Y-134882D03*
X-1006614Y-140000D03*
X-998740Y-140394D03*
X-1006614Y-145512D03*
X-998740Y-145906D03*
Y-129370D03*
X-990866Y-167559D03*
X-982992Y-167953D03*
X-990866Y-173071D03*
X-982992Y-173465D03*
X-990866Y-178583D03*
X-982992Y-178976D03*
X-990866Y-151024D03*
X-982992Y-151417D03*
X-990866Y-156535D03*
X-982992Y-156929D03*
X-990866Y-162047D03*
X-982992Y-162441D03*
X-990866Y-134488D03*
X-982992Y-134882D03*
X-990866Y-140000D03*
X-982992Y-140394D03*
X-990866Y-145512D03*
X-982992Y-145906D03*
Y-129370D03*
X-975118Y-167559D03*
Y-173071D03*
Y-178583D03*
Y-151024D03*
Y-156535D03*
Y-162047D03*
Y-134488D03*
Y-140000D03*
Y-145512D03*
X-745906Y-173071D03*
Y-178583D03*
Y-167559D03*
Y-162047D03*
Y-151024D03*
Y-156535D03*
Y-134488D03*
Y-140000D03*
Y-145512D03*
Y-128976D03*
Y-123465D03*
Y-117953D03*
Y-112441D03*
Y-106929D03*
Y-101417D03*
Y-95906D03*
X-738032Y-172677D03*
Y-178189D03*
Y-167165D03*
X-730157Y-167559D03*
Y-173071D03*
Y-178583D03*
X-738032Y-161654D03*
Y-150630D03*
Y-156142D03*
X-730157Y-151024D03*
Y-156535D03*
Y-162047D03*
X-738032Y-134094D03*
Y-139606D03*
Y-145118D03*
X-730157Y-134488D03*
Y-140000D03*
Y-145512D03*
Y-128976D03*
X-738032Y-128583D03*
X-730157Y-117953D03*
Y-123465D03*
X-738032Y-123071D03*
Y-117559D03*
X-730157Y-101417D03*
Y-106929D03*
Y-112441D03*
X-738032Y-112047D03*
Y-106535D03*
Y-101024D03*
X-730157Y-95906D03*
X-722283Y-167165D03*
X-714409Y-167559D03*
X-722283Y-172677D03*
X-714409Y-173071D03*
X-722283Y-178189D03*
X-714409Y-178583D03*
X-722283Y-150630D03*
X-714409Y-151024D03*
X-722283Y-156142D03*
X-714409Y-156535D03*
X-722283Y-161654D03*
X-714409Y-162047D03*
X-722283Y-134094D03*
X-714409Y-134488D03*
X-722283Y-139606D03*
X-714409Y-140000D03*
X-722283Y-145118D03*
X-714409Y-145512D03*
X-722283Y-128583D03*
Y-117559D03*
Y-123071D03*
X-714409Y-128976D03*
Y-117953D03*
Y-123465D03*
X-722283Y-101024D03*
Y-106535D03*
Y-112047D03*
X-714409Y-101417D03*
Y-106929D03*
Y-112441D03*
Y-95906D03*
X-706535Y-167165D03*
X-698661Y-167559D03*
X-706535Y-172677D03*
X-698661Y-173071D03*
X-706535Y-178189D03*
X-698661Y-178583D03*
X-706535Y-150630D03*
X-698661Y-151024D03*
X-706535Y-156142D03*
X-698661Y-156535D03*
X-706535Y-161654D03*
X-698661Y-162047D03*
X-706535Y-134094D03*
X-698661Y-134488D03*
X-706535Y-139606D03*
X-698661Y-140000D03*
X-706535Y-145118D03*
X-698661Y-145512D03*
X-706535Y-128583D03*
Y-117559D03*
Y-123071D03*
X-698661Y-128976D03*
Y-117953D03*
Y-123465D03*
X-706535Y-101024D03*
Y-106535D03*
Y-112047D03*
X-698661Y-101417D03*
Y-106929D03*
Y-112441D03*
Y-95906D03*
X-690787Y-167165D03*
X-682913Y-167559D03*
X-690787Y-172677D03*
X-682913Y-173071D03*
X-690787Y-178189D03*
X-682913Y-178583D03*
X-690787Y-150630D03*
X-682913Y-151024D03*
X-690787Y-156142D03*
X-682913Y-156535D03*
X-690787Y-161654D03*
X-682913Y-162047D03*
X-690787Y-134094D03*
X-682913Y-134488D03*
X-690787Y-139606D03*
X-682913Y-140000D03*
X-690787Y-145118D03*
X-682913Y-145512D03*
X-690787Y-128583D03*
X-682913Y-128976D03*
X-690787Y-117559D03*
X-682913Y-117953D03*
X-690787Y-123071D03*
X-682913Y-123465D03*
X-690787Y-101024D03*
X-682913Y-101417D03*
X-690787Y-106535D03*
X-682913Y-106929D03*
X-690787Y-112047D03*
X-682913Y-112441D03*
Y-95906D03*
X-675039Y-167165D03*
Y-172677D03*
Y-178189D03*
Y-150630D03*
Y-156142D03*
Y-161654D03*
Y-134094D03*
Y-139606D03*
Y-145118D03*
Y-128583D03*
Y-117559D03*
Y-123071D03*
Y-101024D03*
Y-106535D03*
Y-112047D03*
X-326929Y-167953D03*
X-319055Y-167559D03*
X-326929Y-173465D03*
X-319055Y-173071D03*
X-326929Y-178976D03*
X-319055Y-178583D03*
X-326929Y-151417D03*
X-319055Y-151024D03*
X-326929Y-156929D03*
X-319055Y-156535D03*
X-326929Y-162441D03*
X-319055Y-162047D03*
X-326929Y-134882D03*
X-319055Y-134488D03*
X-326929Y-140394D03*
X-319055Y-140000D03*
X-326929Y-145906D03*
X-319055Y-145512D03*
X-326929Y-129370D03*
X-311181Y-167953D03*
X-303307Y-167559D03*
X-311181Y-173465D03*
X-303307Y-173071D03*
X-311181Y-178976D03*
X-303307Y-178583D03*
X-311181Y-151417D03*
X-303307Y-151024D03*
X-311181Y-156929D03*
X-303307Y-156535D03*
X-311181Y-162441D03*
X-303307Y-162047D03*
X-311181Y-134882D03*
X-303307Y-134488D03*
X-311181Y-140394D03*
X-303307Y-140000D03*
X-311181Y-145906D03*
X-303307Y-145512D03*
X-311181Y-129370D03*
X-295433Y-167953D03*
X-287559Y-167559D03*
X-295433Y-173465D03*
X-287559Y-173071D03*
X-295433Y-178976D03*
X-287559Y-178583D03*
X-295433Y-151417D03*
X-287559Y-151024D03*
X-295433Y-156929D03*
X-287559Y-156535D03*
X-295433Y-162441D03*
X-287559Y-162047D03*
X-295433Y-134882D03*
X-287559Y-134488D03*
X-295433Y-140394D03*
X-287559Y-140000D03*
X-295433Y-145906D03*
X-287559Y-145512D03*
X-295433Y-129370D03*
X-144409Y-167953D03*
Y-173465D03*
Y-178976D03*
Y-151417D03*
Y-156929D03*
Y-162441D03*
Y-134882D03*
Y-140394D03*
Y-145906D03*
Y-129370D03*
X-136535Y-167559D03*
X-128661Y-167953D03*
X-136535Y-173071D03*
X-128661Y-173465D03*
X-136535Y-178583D03*
X-128661Y-178976D03*
X-136535Y-151024D03*
X-128661Y-151417D03*
X-136535Y-156535D03*
X-128661Y-156929D03*
X-136535Y-162047D03*
X-128661Y-162441D03*
X-136535Y-134488D03*
X-128661Y-134882D03*
X-136535Y-140000D03*
X-128661Y-140394D03*
X-136535Y-145512D03*
X-128661Y-145906D03*
Y-129370D03*
X-120787Y-167559D03*
X-112913Y-167953D03*
X-120787Y-173071D03*
X-112913Y-173465D03*
X-120787Y-178583D03*
X-112913Y-178976D03*
X-120787Y-151024D03*
X-112913Y-151417D03*
X-120787Y-156535D03*
X-112913Y-156929D03*
X-120787Y-162047D03*
X-112913Y-162441D03*
X-120787Y-134488D03*
X-112913Y-134882D03*
X-120787Y-140000D03*
X-112913Y-140394D03*
X-120787Y-145512D03*
X-112913Y-145906D03*
Y-129370D03*
X-105039Y-167559D03*
Y-173071D03*
Y-178583D03*
Y-151024D03*
Y-156535D03*
Y-162047D03*
Y-134488D03*
Y-140000D03*
Y-145512D03*
G54D36*
G01X990000Y-800000D02*
Y-740000D01*
X1400000D01*
G01X990000Y-680720D02*
Y-740720D01*
G01X989990Y-681070D02*
Y-621070D01*
X1399990D01*
G01X989990Y-621740D02*
Y-561740D01*
X1399990D01*
G01X1055000Y-740000D02*
Y-800000D01*
G01X1280000Y-740000D02*
Y-800000D01*
G01X1345000Y-740000D02*
Y-800000D01*
G54D27*
X-1670620Y738470D03*
X-1015157Y-95824D03*
X-1012205Y-93068D03*
X-1009252Y-98580D03*
X-1015157Y-80864D03*
X-1012205Y-78108D03*
X-1009252Y-83620D03*
X-1015157Y-65903D03*
X-1012205Y-63147D03*
X-1009252Y-68659D03*
X-1015157Y-50942D03*
X-1012205Y-48187D03*
X-1009252Y-53698D03*
X-1006299Y-95824D03*
X-1000394Y-98580D03*
X-1003346Y-93068D03*
X-997441Y-95824D03*
X-994488Y-93068D03*
X-1000394Y-83620D03*
X-1006299Y-80864D03*
X-1003346Y-78108D03*
X-997441Y-80864D03*
X-994488Y-78108D03*
X-1006299Y-65903D03*
X-1003346Y-63147D03*
X-1000394Y-68659D03*
X-997441Y-65903D03*
X-994488Y-63147D03*
X-1006299Y-50942D03*
X-1003346Y-48187D03*
X-1000394Y-53698D03*
X-997441Y-50942D03*
X-994488Y-48187D03*
X-991535Y-98580D03*
Y-83620D03*
Y-68659D03*
Y-53698D03*
X-971850Y-95824D03*
X-968898Y-93068D03*
X-965945Y-98580D03*
X-962992Y-95824D03*
X-971850Y-80864D03*
X-965945Y-83620D03*
X-962992Y-80864D03*
X-968898Y-78108D03*
X-971850Y-65903D03*
X-965945Y-68659D03*
X-962992Y-65903D03*
X-968898Y-63147D03*
X-971850Y-50942D03*
X-965945Y-53698D03*
X-962992Y-50942D03*
X-968898Y-48187D03*
X-960039Y-93068D03*
X-957087Y-98580D03*
X-954134Y-95824D03*
X-951181Y-93068D03*
X-948228Y-98580D03*
X-960039Y-78108D03*
X-948228Y-83620D03*
X-957087D03*
X-954134Y-80864D03*
X-951181Y-78108D03*
X-960039Y-63147D03*
X-948228Y-68659D03*
X-957087D03*
X-954134Y-65903D03*
X-951181Y-63147D03*
X-960039Y-48187D03*
X-948228Y-53698D03*
X-957087D03*
X-954134Y-50942D03*
X-951181Y-48187D03*
X-145079Y-95824D03*
Y-80864D03*
Y-65903D03*
Y-50942D03*
X-142126Y-93068D03*
X-139173Y-98580D03*
X-136220Y-95824D03*
X-130315Y-98580D03*
X-133268Y-93068D03*
X-127362Y-95824D03*
X-142126Y-78108D03*
X-139173Y-83620D03*
X-130315D03*
X-136220Y-80864D03*
X-133268Y-78108D03*
X-127362Y-80864D03*
X-142126Y-63147D03*
X-139173Y-68659D03*
X-136220Y-65903D03*
X-133268Y-63147D03*
X-130315Y-68659D03*
X-127362Y-65903D03*
X-142126Y-48187D03*
X-139173Y-53698D03*
X-136220Y-50942D03*
X-133268Y-48187D03*
X-130315Y-53698D03*
X-127362Y-50942D03*
X-121457Y-98580D03*
X-124409Y-93068D03*
X-121457Y-83620D03*
X-124409Y-78108D03*
X-121457Y-68659D03*
X-124409Y-63147D03*
X-121457Y-53698D03*
X-124409Y-48187D03*
X-101772Y-95824D03*
X-98819Y-93068D03*
X-95866Y-98580D03*
X-101772Y-80864D03*
X-95866Y-83620D03*
X-98819Y-78108D03*
X-101772Y-65903D03*
X-95866Y-68659D03*
X-98819Y-63147D03*
X-101772Y-50942D03*
X-95866Y-53698D03*
X-98819Y-48187D03*
X-92913Y-95824D03*
X-89961Y-93068D03*
X-87008Y-98580D03*
X-84055Y-95824D03*
X-81102Y-93068D03*
X-92913Y-80864D03*
X-89961Y-78108D03*
X-87008Y-83620D03*
X-84055Y-80864D03*
X-81102Y-78108D03*
X-92913Y-65903D03*
X-89961Y-63147D03*
X-87008Y-68659D03*
X-84055Y-65903D03*
X-81102Y-63147D03*
X-92913Y-50942D03*
X-89961Y-48187D03*
X-87008Y-53698D03*
X-84055Y-50942D03*
X-81102Y-48187D03*
X-78150Y-98580D03*
Y-83620D03*
Y-68659D03*
Y-53698D03*
G54D18*
X-1670620Y527870D03*
X-1003346Y-36375D03*
X-960039D03*
X-133268D03*
X-89961D03*
G54D37*
G01X-1930084Y-565000D02*
X-1925000Y-547500D01*
X-1919916Y-565000D01*
G01X-1921747Y-558875D02*
X-1928254D01*
G01X-1923373Y-20667D02*
X-1922560Y-19792D01*
X-1921950Y-18334D01*
X-1921543Y-16291D01*
X-1921950Y-14542D01*
X-1922763Y-13375D01*
X-1924187Y-12500D01*
X-1929677D01*
Y-30000D01*
X-1922967D01*
X-1921543Y-28834D01*
X-1920730Y-27083D01*
X-1920323Y-25042D01*
X-1920730Y-23000D01*
X-1921950Y-21250D01*
X-1923373Y-20667D01*
X-1929677D01*
G01X-1920527Y526041D02*
X-1921747Y526917D01*
X-1923170Y527500D01*
X-1924797D01*
X-1926627Y526625D01*
X-1928050Y525167D01*
X-1929067Y523416D01*
X-1929880Y520500D01*
X-1930084Y517875D01*
X-1929677Y515250D01*
X-1929067Y513500D01*
X-1927847Y511750D01*
X-1926423Y510583D01*
X-1925000Y510000D01*
X-1923577D01*
X-1922153Y510583D01*
X-1920933Y511458D01*
X-1919916Y512624D01*
G01X-1929473Y1050000D02*
Y1067500D01*
X-1925407D01*
X-1923780Y1066625D01*
X-1922560Y1065458D01*
X-1921543Y1063709D01*
X-1920730Y1061666D01*
X-1920527Y1058750D01*
X-1920730Y1055833D01*
X-1921543Y1053791D01*
X-1922560Y1052041D01*
X-1923780Y1050875D01*
X-1925407Y1050000D01*
X-1929473D01*
G01X-1710000Y-830000D02*
X-1708577Y-829708D01*
X-1706950Y-828834D01*
X-1705933Y-827376D01*
X-1705527Y-825333D01*
X-1705933Y-823292D01*
X-1707153Y-821542D01*
X-1708983Y-820667D01*
X-1711017D01*
X-1712237Y-820083D01*
X-1713254Y-818625D01*
X-1713660Y-816584D01*
X-1713050Y-814542D01*
X-1711627Y-813083D01*
X-1710000Y-812500D01*
X-1708373Y-813083D01*
X-1706950Y-814542D01*
X-1706340Y-816584D01*
X-1706747Y-818625D01*
X-1707763Y-820083D01*
X-1708983Y-820667D01*
X-1711017D01*
X-1712847Y-821542D01*
X-1714067Y-823292D01*
X-1714473Y-825333D01*
X-1714067Y-827376D01*
X-1713050Y-828834D01*
X-1711423Y-829708D01*
X-1710000Y-830000D01*
G01Y1315000D02*
X-1708577Y1315292D01*
X-1706950Y1316166D01*
X-1705933Y1317624D01*
X-1705527Y1319667D01*
X-1705933Y1321708D01*
X-1707153Y1323458D01*
X-1708983Y1324333D01*
X-1711017D01*
X-1712237Y1324917D01*
X-1713254Y1326375D01*
X-1713660Y1328416D01*
X-1713050Y1330458D01*
X-1711627Y1331917D01*
X-1710000Y1332500D01*
X-1708373Y1331917D01*
X-1706950Y1330458D01*
X-1706340Y1328416D01*
X-1706747Y1326375D01*
X-1707763Y1324917D01*
X-1708983Y1324333D01*
X-1711017D01*
X-1712847Y1323458D01*
X-1714067Y1321708D01*
X-1714473Y1319667D01*
X-1714067Y1317624D01*
X-1713050Y1316166D01*
X-1711423Y1315292D01*
X-1710000Y1315000D01*
G01X-1265407Y-830000D02*
X-1265000Y-826209D01*
X-1264390Y-823000D01*
X-1263577Y-820083D01*
X-1262560Y-816875D01*
X-1260933Y-812500D01*
X-1269067D01*
G01X-1265407Y1315000D02*
X-1265000Y1318791D01*
X-1264390Y1322000D01*
X-1263577Y1324917D01*
X-1262560Y1328125D01*
X-1260933Y1332500D01*
X-1269067D01*
G01X-838863Y-822709D02*
X-837440Y-820667D01*
X-836220Y-819500D01*
X-834593Y-818917D01*
X-833170Y-819500D01*
X-832153Y-820667D01*
X-831340Y-822417D01*
X-831137Y-824458D01*
X-831340Y-826209D01*
X-832153Y-827959D01*
X-833373Y-829417D01*
X-834797Y-830000D01*
X-836423Y-829417D01*
X-837847Y-827667D01*
X-838660Y-825042D01*
X-838863Y-822125D01*
X-838457Y-818334D01*
X-837847Y-816291D01*
X-836830Y-814250D01*
X-835407Y-812792D01*
X-833983Y-812500D01*
X-832560Y-813083D01*
X-831543Y-814542D01*
G01X-838863Y1322291D02*
X-837440Y1324333D01*
X-836220Y1325500D01*
X-834593Y1326083D01*
X-833170Y1325500D01*
X-832153Y1324333D01*
X-831340Y1322583D01*
X-831137Y1320542D01*
X-831340Y1318791D01*
X-832153Y1317041D01*
X-833373Y1315583D01*
X-834797Y1315000D01*
X-836423Y1315583D01*
X-837847Y1317333D01*
X-838660Y1319958D01*
X-838863Y1322875D01*
X-838457Y1326666D01*
X-837847Y1328709D01*
X-836830Y1330750D01*
X-835407Y1332208D01*
X-833983Y1332500D01*
X-832560Y1331917D01*
X-831543Y1330458D01*
G01X-414473Y-827376D02*
X-413254Y-828834D01*
X-411830Y-829708D01*
X-410000Y-830000D01*
X-408170Y-829417D01*
X-406747Y-828250D01*
X-405730Y-826209D01*
X-405527Y-823875D01*
X-405933Y-821542D01*
X-406950Y-820083D01*
X-408373Y-818917D01*
X-409797Y-818625D01*
X-411220Y-818917D01*
X-413050Y-820083D01*
X-412440Y-812500D01*
X-406950D01*
G01X-414473Y1317624D02*
X-413254Y1316166D01*
X-411830Y1315292D01*
X-410000Y1315000D01*
X-408170Y1315583D01*
X-406747Y1316750D01*
X-405730Y1318791D01*
X-405527Y1321125D01*
X-405933Y1323458D01*
X-406950Y1324917D01*
X-408373Y1326083D01*
X-409797Y1326375D01*
X-411220Y1326083D01*
X-413050Y1324917D01*
X-412440Y1332500D01*
X-406950D01*
G01X22440Y-830000D02*
Y-812500D01*
X14916Y-825042D01*
X25084D01*
G01X22440Y1315000D02*
Y1332500D01*
X14916Y1319958D01*
X25084D01*
G01X435527Y-826500D02*
X436746Y-828542D01*
X438373Y-829708D01*
X440203Y-830000D01*
X441830Y-829708D01*
X443457Y-828250D01*
X444473Y-826500D01*
X444677Y-824750D01*
X444270Y-822709D01*
X442847Y-821250D01*
X441423Y-820667D01*
X439593D01*
G01X441423D02*
X442643Y-819792D01*
X443660Y-818334D01*
X444067Y-816584D01*
X443660Y-814833D01*
X442643Y-813375D01*
X440813Y-812500D01*
X438983Y-812792D01*
X437153Y-813959D01*
G01X433000Y1113200D02*
Y1095700D01*
G01X428323Y1113200D02*
X437677D01*
G01X445330Y1095700D02*
Y1113200D01*
G01X453870D02*
Y1095700D01*
G01Y1104450D02*
X445330D01*
G01X463760Y1113200D02*
X468640D01*
G01X466200D02*
Y1095700D01*
G01X463760D02*
X468640D01*
G01X478530Y1098033D02*
X480157Y1096575D01*
X481987Y1095700D01*
X483613D01*
X485240Y1096575D01*
X486460Y1098033D01*
X487070Y1100075D01*
X486663Y1102116D01*
X485647Y1103867D01*
X483817Y1105033D01*
X481377Y1105617D01*
X479953Y1106783D01*
X479343Y1108825D01*
X479750Y1110867D01*
X480767Y1112325D01*
X482190Y1113200D01*
X483613D01*
X485037Y1112617D01*
X486257Y1111158D01*
G01X513560Y1113200D02*
X518440D01*
G01X516000D02*
Y1095700D01*
G01X513560D02*
X518440D01*
G01X528330Y1098033D02*
X529957Y1096575D01*
X531787Y1095700D01*
X533413D01*
X535040Y1096575D01*
X536260Y1098033D01*
X536870Y1100075D01*
X536463Y1102116D01*
X535447Y1103867D01*
X533617Y1105033D01*
X531177Y1105617D01*
X529753Y1106783D01*
X529143Y1108825D01*
X529550Y1110867D01*
X530567Y1112325D01*
X531990Y1113200D01*
X533413D01*
X534837Y1112617D01*
X536057Y1111158D01*
G01X560716Y1095700D02*
X565800Y1113200D01*
X570884Y1095700D01*
G01X569053Y1101825D02*
X562546D01*
G01X599000Y1095700D02*
X600423Y1095992D01*
X602050Y1096866D01*
X603067Y1098324D01*
X603473Y1100367D01*
X603067Y1102408D01*
X601847Y1104158D01*
X600017Y1105033D01*
X597983D01*
X596763Y1105617D01*
X595746Y1107075D01*
X595340Y1109116D01*
X595950Y1111158D01*
X597373Y1112617D01*
X599000Y1113200D01*
X600627Y1112617D01*
X602050Y1111158D01*
X602660Y1109116D01*
X602253Y1107075D01*
X601237Y1105617D01*
X600017Y1105033D01*
X597983D01*
X596153Y1104158D01*
X594933Y1102408D01*
X594527Y1100367D01*
X594933Y1098324D01*
X595950Y1096866D01*
X597577Y1095992D01*
X599000Y1095700D01*
G01X628133Y1113200D02*
Y1095700D01*
X636267D01*
G01X643716D02*
X648800Y1113200D01*
X653884Y1095700D01*
G01X652053Y1101825D02*
X645546D01*
G01X665400Y1095700D02*
Y1103575D01*
X661333Y1113200D01*
G01X669467D02*
X665400Y1103575D01*
G01X686067Y1095700D02*
X677933D01*
Y1113200D01*
X686067D01*
G01X682813Y1104742D02*
X677933D01*
G01X694533Y1095700D02*
Y1113200D01*
X699617D01*
X701243Y1112325D01*
X702260Y1111158D01*
X702667Y1108825D01*
X702260Y1106492D01*
X701040Y1105033D01*
X699617Y1104158D01*
X694533D01*
G01X699617D02*
X702667Y1095700D01*
G01X733427Y1105033D02*
X734240Y1105908D01*
X734850Y1107366D01*
X735257Y1109409D01*
X734850Y1111158D01*
X734037Y1112325D01*
X732613Y1113200D01*
X727123D01*
Y1095700D01*
X733833D01*
X735257Y1096866D01*
X736070Y1098617D01*
X736477Y1100658D01*
X736070Y1102700D01*
X734850Y1104450D01*
X733427Y1105033D01*
X727123D01*
G01X748400Y1095700D02*
X746773Y1095992D01*
X745350Y1097158D01*
X744130Y1098908D01*
X743316Y1100950D01*
X742910Y1103283D01*
Y1105617D01*
X743316Y1107950D01*
X744130Y1109992D01*
X745350Y1111741D01*
X746773Y1112908D01*
X748400Y1113200D01*
X750027Y1112908D01*
X751450Y1111741D01*
X752670Y1109992D01*
X753484Y1107950D01*
X753890Y1105617D01*
Y1103283D01*
X753484Y1100950D01*
X752670Y1098908D01*
X751450Y1097158D01*
X750027Y1095992D01*
X748400Y1095700D01*
G01X759916D02*
X765000Y1113200D01*
X770084Y1095700D01*
G01X768253Y1101825D02*
X761746D01*
G01X777533Y1095700D02*
Y1113200D01*
X782617D01*
X784243Y1112325D01*
X785260Y1111158D01*
X785667Y1108825D01*
X785260Y1106492D01*
X784040Y1105033D01*
X782617Y1104158D01*
X777533D01*
G01X782617D02*
X785667Y1095700D01*
G01X793727D02*
Y1113200D01*
X797793D01*
X799420Y1112325D01*
X800640Y1111158D01*
X801657Y1109409D01*
X802470Y1107366D01*
X802673Y1104450D01*
X802470Y1101533D01*
X801657Y1099491D01*
X800640Y1097741D01*
X799420Y1096575D01*
X797793Y1095700D01*
X793727D01*
G01X435527Y1318500D02*
X436746Y1316458D01*
X438373Y1315292D01*
X440203Y1315000D01*
X441830Y1315292D01*
X443457Y1316750D01*
X444473Y1318500D01*
X444677Y1320250D01*
X444270Y1322291D01*
X442847Y1323750D01*
X441423Y1324333D01*
X439593D01*
G01X441423D02*
X442643Y1325208D01*
X443660Y1326666D01*
X444067Y1328416D01*
X443660Y1330167D01*
X442643Y1331625D01*
X440813Y1332500D01*
X438983Y1332208D01*
X437153Y1331041D01*
G01X866137Y-815417D02*
X867357Y-813667D01*
X868780Y-812792D01*
X870407Y-812500D01*
X872440Y-813083D01*
X873863Y-814542D01*
X874270Y-816291D01*
X874067Y-818042D01*
X873253Y-819500D01*
X869187Y-822417D01*
X867357Y-824458D01*
X866137Y-827376D01*
X865730Y-830000D01*
X874270D01*
G01X866137Y1329583D02*
X867357Y1331333D01*
X868780Y1332208D01*
X870407Y1332500D01*
X872440Y1331917D01*
X873863Y1330458D01*
X874270Y1328709D01*
X874067Y1326958D01*
X873253Y1325500D01*
X869187Y1322583D01*
X867357Y1320542D01*
X866137Y1317624D01*
X865730Y1315000D01*
X874270D01*
G01X1026100Y830100D02*
Y812600D01*
G01X1021423Y830100D02*
X1030777D01*
G01X1038227Y812600D02*
Y830100D01*
X1042293D01*
X1043920Y829225D01*
X1045140Y828058D01*
X1046157Y826309D01*
X1046970Y824266D01*
X1047173Y821350D01*
X1046970Y818433D01*
X1046157Y816391D01*
X1045140Y814641D01*
X1043920Y813475D01*
X1042293Y812600D01*
X1038227D01*
G01X1055233D02*
Y830100D01*
X1060317D01*
X1061943Y829225D01*
X1062960Y828058D01*
X1063367Y825725D01*
X1062960Y823392D01*
X1061740Y821933D01*
X1060317Y821058D01*
X1055233D01*
G01X1060317D02*
X1063367Y812600D01*
G01X1092500Y830100D02*
Y812600D01*
G01X1087823Y830100D02*
X1097177D01*
G01X1104016Y812600D02*
X1109100Y830100D01*
X1114184Y812600D01*
G01X1112353Y818725D02*
X1105846D01*
G01X1121227Y812600D02*
Y830100D01*
G01X1128953D02*
X1121227Y819308D01*
G01X1130173Y812600D02*
X1124683Y824266D01*
G01X1146367Y812600D02*
X1138233D01*
Y830100D01*
X1146367D01*
G01X1143113Y821642D02*
X1138233D01*
G01X1154630Y814933D02*
X1156257Y813475D01*
X1158087Y812600D01*
X1159713D01*
X1161340Y813475D01*
X1162560Y814933D01*
X1163170Y816975D01*
X1162763Y819016D01*
X1161747Y820767D01*
X1159917Y821933D01*
X1157477Y822517D01*
X1156053Y823683D01*
X1155443Y825725D01*
X1155850Y827767D01*
X1156867Y829225D01*
X1158290Y830100D01*
X1159713D01*
X1161137Y829517D01*
X1162357Y828058D01*
G01X1188033Y812600D02*
Y830100D01*
X1192913D01*
X1194540Y829225D01*
X1195760Y827183D01*
X1196167Y824850D01*
X1195760Y822517D01*
X1194743Y820767D01*
X1192913Y819891D01*
X1188033D01*
G01X1204633Y812600D02*
Y830100D01*
X1209717D01*
X1211343Y829225D01*
X1212360Y828058D01*
X1212767Y825725D01*
X1212360Y823392D01*
X1211140Y821933D01*
X1209717Y821058D01*
X1204633D01*
G01X1209717D02*
X1212767Y812600D01*
G01X1229367D02*
X1221233D01*
Y830100D01*
X1229367D01*
G01X1226113Y821642D02*
X1221233D01*
G01X1237630Y814933D02*
X1239257Y813475D01*
X1241087Y812600D01*
X1242713D01*
X1244340Y813475D01*
X1245560Y814933D01*
X1246170Y816975D01*
X1245763Y819016D01*
X1244747Y820767D01*
X1242917Y821933D01*
X1240477Y822517D01*
X1239053Y823683D01*
X1238443Y825725D01*
X1238850Y827767D01*
X1239867Y829225D01*
X1241290Y830100D01*
X1242713D01*
X1244137Y829517D01*
X1245357Y828058D01*
G01X1262567Y812600D02*
X1254433D01*
Y830100D01*
X1262567D01*
G01X1259313Y821642D02*
X1254433D01*
G01X1270627Y812600D02*
Y830100D01*
X1274693D01*
X1276320Y829225D01*
X1277540Y828058D01*
X1278557Y826309D01*
X1279370Y824266D01*
X1279573Y821350D01*
X1279370Y818433D01*
X1278557Y816391D01*
X1277540Y814641D01*
X1276320Y813475D01*
X1274693Y812600D01*
X1270627D01*
G01X1295767D02*
X1287633D01*
Y830100D01*
X1295767D01*
G01X1292513Y821642D02*
X1287633D01*
G01X1303623Y812600D02*
Y830100D01*
X1312977Y812600D01*
Y830100D01*
G01X1329373Y828641D02*
X1328153Y829517D01*
X1326730Y830100D01*
X1325103D01*
X1323273Y829225D01*
X1321850Y827767D01*
X1320833Y826016D01*
X1320020Y823100D01*
X1319816Y820475D01*
X1320223Y817850D01*
X1320833Y816100D01*
X1322053Y814350D01*
X1323477Y813183D01*
X1324900Y812600D01*
X1326323D01*
X1327747Y813183D01*
X1328967Y814058D01*
X1329984Y815224D01*
G01X1345567Y812600D02*
X1337433D01*
Y830100D01*
X1345567D01*
G01X1342313Y821642D02*
X1337433D01*
G01X1022237Y850100D02*
Y867600D01*
X1029963D01*
G01X1027117Y859142D02*
X1022237D01*
G01X1042700Y850100D02*
X1041073Y850392D01*
X1039650Y851558D01*
X1038430Y853308D01*
X1037616Y855350D01*
X1037210Y857683D01*
Y860017D01*
X1037616Y862350D01*
X1038430Y864392D01*
X1039650Y866141D01*
X1041073Y867308D01*
X1042700Y867600D01*
X1044327Y867308D01*
X1045750Y866141D01*
X1046970Y864392D01*
X1047784Y862350D01*
X1048190Y860017D01*
Y857683D01*
X1047784Y855350D01*
X1046970Y853308D01*
X1045750Y851558D01*
X1044327Y850392D01*
X1042700Y850100D01*
G01X1055233D02*
Y867600D01*
X1060317D01*
X1061943Y866725D01*
X1062960Y865558D01*
X1063367Y863225D01*
X1062960Y860892D01*
X1061740Y859433D01*
X1060317Y858558D01*
X1055233D01*
G01X1060317D02*
X1063367Y850100D01*
G01X1088433D02*
Y867600D01*
X1093517D01*
X1095143Y866725D01*
X1096160Y865558D01*
X1096567Y863225D01*
X1096160Y860892D01*
X1094940Y859433D01*
X1093517Y858558D01*
X1088433D01*
G01X1093517D02*
X1096567Y850100D01*
G01X1113167D02*
X1105033D01*
Y867600D01*
X1113167D01*
G01X1109913Y859142D02*
X1105033D01*
G01X1121837Y850100D02*
Y867600D01*
X1129563D01*
G01X1126717Y859142D02*
X1121837D01*
G01X1146367Y850100D02*
X1138233D01*
Y867600D01*
X1146367D01*
G01X1143113Y859142D02*
X1138233D01*
G01X1154833Y850100D02*
Y867600D01*
X1159917D01*
X1161543Y866725D01*
X1162560Y865558D01*
X1162967Y863225D01*
X1162560Y860892D01*
X1161340Y859433D01*
X1159917Y858558D01*
X1154833D01*
G01X1159917D02*
X1162967Y850100D01*
G01X1179567D02*
X1171433D01*
Y867600D01*
X1179567D01*
G01X1176313Y859142D02*
X1171433D01*
G01X1187423Y850100D02*
Y867600D01*
X1196777Y850100D01*
Y867600D01*
G01X1213173Y866141D02*
X1211953Y867017D01*
X1210530Y867600D01*
X1208903D01*
X1207073Y866725D01*
X1205650Y865267D01*
X1204633Y863516D01*
X1203820Y860600D01*
X1203616Y857975D01*
X1204023Y855350D01*
X1204633Y853600D01*
X1205853Y851850D01*
X1207277Y850683D01*
X1208700Y850100D01*
X1210123D01*
X1211547Y850683D01*
X1212767Y851558D01*
X1213784Y852724D01*
G01X1229367Y850100D02*
X1221233D01*
Y867600D01*
X1229367D01*
G01X1226113Y859142D02*
X1221233D01*
G01X1258500Y850100D02*
X1256873Y850392D01*
X1255450Y851558D01*
X1254230Y853308D01*
X1253416Y855350D01*
X1253010Y857683D01*
Y860017D01*
X1253416Y862350D01*
X1254230Y864392D01*
X1255450Y866141D01*
X1256873Y867308D01*
X1258500Y867600D01*
X1260127Y867308D01*
X1261550Y866141D01*
X1262770Y864392D01*
X1263584Y862350D01*
X1263990Y860017D01*
Y857683D01*
X1263584Y855350D01*
X1262770Y853308D01*
X1261550Y851558D01*
X1260127Y850392D01*
X1258500Y850100D01*
G01X1270423D02*
Y867600D01*
X1279777Y850100D01*
Y867600D01*
G01X1287633D02*
Y850100D01*
X1295767D01*
G01X1308300D02*
Y857975D01*
X1304233Y867600D01*
G01X1312367D02*
X1308300Y857975D01*
G01X1245000Y-830000D02*
Y-812500D01*
X1242560Y-816000D01*
G01Y-830000D02*
X1247440D01*
G01X1245000Y1315000D02*
Y1332500D01*
X1242560Y1329000D01*
G01Y1315000D02*
X1247440D01*
G01X1419916Y-565000D02*
X1425000Y-547500D01*
X1430084Y-565000D01*
G01X1428253Y-558875D02*
X1421746D01*
G01X1426627Y-20667D02*
X1427440Y-19792D01*
X1428050Y-18334D01*
X1428457Y-16291D01*
X1428050Y-14542D01*
X1427237Y-13375D01*
X1425813Y-12500D01*
X1420323D01*
Y-30000D01*
X1427033D01*
X1428457Y-28834D01*
X1429270Y-27083D01*
X1429677Y-25042D01*
X1429270Y-23000D01*
X1428050Y-21250D01*
X1426627Y-20667D01*
X1420323D01*
G01X1429473Y526041D02*
X1428253Y526917D01*
X1426830Y527500D01*
X1425203D01*
X1423373Y526625D01*
X1421950Y525167D01*
X1420933Y523416D01*
X1420120Y520500D01*
X1419916Y517875D01*
X1420323Y515250D01*
X1420933Y513500D01*
X1422153Y511750D01*
X1423577Y510583D01*
X1425000Y510000D01*
X1426423D01*
X1427847Y510583D01*
X1429067Y511458D01*
X1430084Y512624D01*
G01X1420527Y1050000D02*
Y1067500D01*
X1424593D01*
X1426220Y1066625D01*
X1427440Y1065458D01*
X1428457Y1063709D01*
X1429270Y1061666D01*
X1429473Y1058750D01*
X1429270Y1055833D01*
X1428457Y1053791D01*
X1427440Y1052041D01*
X1426220Y1050875D01*
X1424593Y1050000D01*
X1420527D01*
G54D19*
X-1670620Y551270D03*
X-806854Y-99635D03*
Y-83100D03*
X-785200Y-99635D03*
Y-83100D03*
G54D28*
X-1670620Y761870D03*
X-1656906Y-167953D03*
X-1645906Y-178953D03*
X-1653906Y-175453D03*
X-1653406Y-159953D03*
X-1645906Y-156953D03*
X-1634906Y-167953D03*
X-1637906Y-175453D03*
X-1638406Y-159953D03*
X-1530728Y-162450D03*
X-1533728Y-154950D03*
X-1530228Y-146950D03*
X-1522728Y-165950D03*
X-1514728Y-162450D03*
X-1515228Y-146950D03*
X-1522728Y-143950D03*
X-1511728Y-154950D03*
X-1058676Y-78740D03*
X-1047676Y-89740D03*
X-1055676Y-86240D03*
X-1055176Y-70740D03*
X-1047676Y-67740D03*
X-1039676Y-86240D03*
X-1040176Y-70740D03*
X-1036676Y-78740D03*
X-663638Y-154950D03*
X-652638Y-165950D03*
X-660638Y-162450D03*
X-660138Y-146950D03*
X-652638Y-143950D03*
X-641638Y-154950D03*
X-644638Y-162450D03*
X-645138Y-146950D03*
X-177597Y-89740D03*
X-185597Y-86240D03*
X-188597Y-78740D03*
X-185097Y-70740D03*
X-177597Y-67740D03*
X-169597Y-86240D03*
X-170097Y-70740D03*
X-166597Y-78740D03*
X-4110Y-167953D03*
X6890Y-178953D03*
X-1110Y-175453D03*
X14390Y-159953D03*
X-610D03*
X6890Y-156953D03*
X17890Y-167953D03*
X14890Y-175453D03*
G54D38*
G01X-1894720Y1212520D02*
Y1218520D01*
X-1892900Y1213520D01*
X-1891080Y1218520D01*
Y1212520D01*
G01X-1888040Y1218520D02*
X-1886360D01*
G01X-1887200D02*
Y1212520D01*
G01X-1888040D02*
X-1886360D01*
G01X-1879960Y1218020D02*
X-1880380Y1218320D01*
X-1880870Y1218520D01*
X-1881430D01*
X-1882060Y1218220D01*
X-1882550Y1217720D01*
X-1882900Y1217120D01*
X-1883180Y1216120D01*
X-1883250Y1215220D01*
X-1883110Y1214320D01*
X-1882900Y1213720D01*
X-1882480Y1213120D01*
X-1881990Y1212720D01*
X-1881500Y1212520D01*
X-1881010D01*
X-1880520Y1212720D01*
X-1880100Y1213020D01*
X-1879750Y1213420D01*
G01X-1877200Y1212520D02*
Y1218520D01*
X-1875450D01*
X-1874890Y1218220D01*
X-1874540Y1217820D01*
X-1874400Y1217020D01*
X-1874540Y1216220D01*
X-1874960Y1215720D01*
X-1875450Y1215420D01*
X-1877200D01*
G01X-1875450D02*
X-1874400Y1212520D01*
G01X-1870100D02*
X-1870660Y1212620D01*
X-1871150Y1213020D01*
X-1871570Y1213620D01*
X-1871850Y1214320D01*
X-1871990Y1215120D01*
Y1215920D01*
X-1871850Y1216720D01*
X-1871570Y1217420D01*
X-1871150Y1218020D01*
X-1870660Y1218420D01*
X-1870100Y1218520D01*
X-1869540Y1218420D01*
X-1869050Y1218020D01*
X-1868630Y1217420D01*
X-1868350Y1216720D01*
X-1868210Y1215920D01*
Y1215120D01*
X-1868350Y1214320D01*
X-1868630Y1213620D01*
X-1869050Y1213020D01*
X-1869540Y1212620D01*
X-1870100Y1212520D01*
G01X-1865870Y1213320D02*
X-1865310Y1212820D01*
X-1864680Y1212520D01*
X-1864120D01*
X-1863560Y1212820D01*
X-1863140Y1213320D01*
X-1862930Y1214020D01*
X-1863070Y1214720D01*
X-1863420Y1215320D01*
X-1864050Y1215720D01*
X-1864890Y1215920D01*
X-1865380Y1216320D01*
X-1865590Y1217020D01*
X-1865450Y1217720D01*
X-1865100Y1218220D01*
X-1864610Y1218520D01*
X-1864120D01*
X-1863630Y1218320D01*
X-1863210Y1217820D01*
G01X-1858700Y1212520D02*
X-1859260Y1212620D01*
X-1859750Y1213020D01*
X-1860170Y1213620D01*
X-1860450Y1214320D01*
X-1860590Y1215120D01*
Y1215920D01*
X-1860450Y1216720D01*
X-1860170Y1217420D01*
X-1859750Y1218020D01*
X-1859260Y1218420D01*
X-1858700Y1218520D01*
X-1858140Y1218420D01*
X-1857650Y1218020D01*
X-1857230Y1217420D01*
X-1856950Y1216720D01*
X-1856810Y1215920D01*
Y1215120D01*
X-1856950Y1214320D01*
X-1857230Y1213620D01*
X-1857650Y1213020D01*
X-1858140Y1212620D01*
X-1858700Y1212520D01*
G01X-1854330D02*
Y1218520D01*
X-1851670D01*
G01X-1852650Y1215620D02*
X-1854330D01*
G01X-1847300Y1218520D02*
Y1212520D01*
G01X-1848910Y1218520D02*
X-1845690D01*
G01X-1834360Y1218020D02*
X-1834780Y1218320D01*
X-1835270Y1218520D01*
X-1835830D01*
X-1836460Y1218220D01*
X-1836950Y1217720D01*
X-1837300Y1217120D01*
X-1837580Y1216120D01*
X-1837650Y1215220D01*
X-1837510Y1214320D01*
X-1837300Y1213720D01*
X-1836880Y1213120D01*
X-1836390Y1212720D01*
X-1835900Y1212520D01*
X-1835410D01*
X-1834920Y1212720D01*
X-1834500Y1213020D01*
X-1834150Y1213420D01*
G01X-1830200Y1212520D02*
X-1830760Y1212620D01*
X-1831250Y1213020D01*
X-1831670Y1213620D01*
X-1831950Y1214320D01*
X-1832090Y1215120D01*
Y1215920D01*
X-1831950Y1216720D01*
X-1831670Y1217420D01*
X-1831250Y1218020D01*
X-1830760Y1218420D01*
X-1830200Y1218520D01*
X-1829640Y1218420D01*
X-1829150Y1218020D01*
X-1828730Y1217420D01*
X-1828450Y1216720D01*
X-1828310Y1215920D01*
Y1215120D01*
X-1828450Y1214320D01*
X-1828730Y1213620D01*
X-1829150Y1213020D01*
X-1829640Y1212620D01*
X-1830200Y1212520D01*
G01X-1825900D02*
Y1218520D01*
X-1824150D01*
X-1823590Y1218220D01*
X-1823240Y1217820D01*
X-1823100Y1217020D01*
X-1823240Y1216220D01*
X-1823660Y1215720D01*
X-1824150Y1215420D01*
X-1825900D01*
G01X-1824150D02*
X-1823100Y1212520D01*
G01X-1820200D02*
Y1218520D01*
X-1818520D01*
X-1817960Y1218220D01*
X-1817540Y1217520D01*
X-1817400Y1216720D01*
X-1817540Y1215920D01*
X-1817890Y1215320D01*
X-1818520Y1215020D01*
X-1820200D01*
G01X-1813100Y1212520D02*
X-1813660Y1212620D01*
X-1814150Y1213020D01*
X-1814570Y1213620D01*
X-1814850Y1214320D01*
X-1814990Y1215120D01*
Y1215920D01*
X-1814850Y1216720D01*
X-1814570Y1217420D01*
X-1814150Y1218020D01*
X-1813660Y1218420D01*
X-1813100Y1218520D01*
X-1812540Y1218420D01*
X-1812050Y1218020D01*
X-1811630Y1217420D01*
X-1811350Y1216720D01*
X-1811210Y1215920D01*
Y1215120D01*
X-1811350Y1214320D01*
X-1811630Y1213620D01*
X-1812050Y1213020D01*
X-1812540Y1212620D01*
X-1813100Y1212520D01*
G01X-1808800D02*
Y1218520D01*
X-1807050D01*
X-1806490Y1218220D01*
X-1806140Y1217820D01*
X-1806000Y1217020D01*
X-1806140Y1216220D01*
X-1806560Y1215720D01*
X-1807050Y1215420D01*
X-1808800D01*
G01X-1807050D02*
X-1806000Y1212520D01*
G01X-1803450D02*
X-1801700Y1218520D01*
X-1799950Y1212520D01*
G01X-1800580Y1214620D02*
X-1802820D01*
G01X-1796000Y1218520D02*
Y1212520D01*
G01X-1797610Y1218520D02*
X-1794390D01*
G01X-1791140D02*
X-1789460D01*
G01X-1790300D02*
Y1212520D01*
G01X-1791140D02*
X-1789460D01*
G01X-1784600D02*
X-1785160Y1212620D01*
X-1785650Y1213020D01*
X-1786070Y1213620D01*
X-1786350Y1214320D01*
X-1786490Y1215120D01*
Y1215920D01*
X-1786350Y1216720D01*
X-1786070Y1217420D01*
X-1785650Y1218020D01*
X-1785160Y1218420D01*
X-1784600Y1218520D01*
X-1784040Y1218420D01*
X-1783550Y1218020D01*
X-1783130Y1217420D01*
X-1782850Y1216720D01*
X-1782710Y1215920D01*
Y1215120D01*
X-1782850Y1214320D01*
X-1783130Y1213620D01*
X-1783550Y1213020D01*
X-1784040Y1212620D01*
X-1784600Y1212520D01*
G01X-1780510D02*
Y1218520D01*
X-1777290Y1212520D01*
Y1218520D01*
G01X-1773200Y1212320D02*
X-1773340Y1212420D01*
Y1212620D01*
X-1773200Y1212720D01*
X-1773060Y1212620D01*
Y1212420D01*
X-1773200Y1212320D01*
G01X-1891360Y1243020D02*
X-1891780Y1243320D01*
X-1892270Y1243520D01*
X-1892830D01*
X-1893460Y1243220D01*
X-1893950Y1242720D01*
X-1894300Y1242120D01*
X-1894580Y1241120D01*
X-1894650Y1240220D01*
X-1894510Y1239320D01*
X-1894300Y1238720D01*
X-1893880Y1238120D01*
X-1893390Y1237720D01*
X-1892900Y1237520D01*
X-1892410D01*
X-1891920Y1237720D01*
X-1891500Y1238020D01*
X-1891150Y1238420D01*
G01X-1887200Y1237520D02*
X-1887760Y1237620D01*
X-1888250Y1238020D01*
X-1888670Y1238620D01*
X-1888950Y1239320D01*
X-1889090Y1240120D01*
Y1240920D01*
X-1888950Y1241720D01*
X-1888670Y1242420D01*
X-1888250Y1243020D01*
X-1887760Y1243420D01*
X-1887200Y1243520D01*
X-1886640Y1243420D01*
X-1886150Y1243020D01*
X-1885730Y1242420D01*
X-1885450Y1241720D01*
X-1885310Y1240920D01*
Y1240120D01*
X-1885450Y1239320D01*
X-1885730Y1238620D01*
X-1886150Y1238020D01*
X-1886640Y1237620D01*
X-1887200Y1237520D01*
G01X-1883110D02*
Y1243520D01*
X-1879890Y1237520D01*
Y1243520D01*
G01X-1875800D02*
Y1237520D01*
G01X-1877410Y1243520D02*
X-1874190D01*
G01X-1868700Y1237520D02*
X-1871500D01*
Y1243520D01*
X-1868700D01*
G01X-1869820Y1240620D02*
X-1871500D01*
G01X-1866010Y1237520D02*
Y1243520D01*
X-1862790Y1237520D01*
Y1243520D01*
G01X-1858700D02*
Y1237520D01*
G01X-1860310Y1243520D02*
X-1857090D01*
G01X-1854470Y1238320D02*
X-1853910Y1237820D01*
X-1853280Y1237520D01*
X-1852720D01*
X-1852160Y1237820D01*
X-1851740Y1238320D01*
X-1851530Y1239020D01*
X-1851670Y1239720D01*
X-1852020Y1240320D01*
X-1852650Y1240720D01*
X-1853490Y1240920D01*
X-1853980Y1241320D01*
X-1854190Y1242020D01*
X-1854050Y1242720D01*
X-1853700Y1243220D01*
X-1853210Y1243520D01*
X-1852720D01*
X-1852230Y1243320D01*
X-1851810Y1242820D01*
G01X-1843420Y1237520D02*
Y1243520D01*
X-1841600Y1238520D01*
X-1839780Y1243520D01*
Y1237520D01*
G01X-1837650D02*
X-1835900Y1243520D01*
X-1834150Y1237520D01*
G01X-1834780Y1239620D02*
X-1837020D01*
G01X-1830200Y1237520D02*
Y1240220D01*
X-1831600Y1243520D01*
G01X-1828800D02*
X-1830200Y1240220D01*
G01X-1820410Y1237520D02*
Y1243520D01*
X-1817190Y1237520D01*
Y1243520D01*
G01X-1813100Y1237520D02*
X-1813660Y1237620D01*
X-1814150Y1238020D01*
X-1814570Y1238620D01*
X-1814850Y1239320D01*
X-1814990Y1240120D01*
Y1240920D01*
X-1814850Y1241720D01*
X-1814570Y1242420D01*
X-1814150Y1243020D01*
X-1813660Y1243420D01*
X-1813100Y1243520D01*
X-1812540Y1243420D01*
X-1812050Y1243020D01*
X-1811630Y1242420D01*
X-1811350Y1241720D01*
X-1811210Y1240920D01*
Y1240120D01*
X-1811350Y1239320D01*
X-1811630Y1238620D01*
X-1812050Y1238020D01*
X-1812540Y1237620D01*
X-1813100Y1237520D01*
G01X-1807400Y1243520D02*
Y1237520D01*
G01X-1809010Y1243520D02*
X-1805790D01*
G01X-1795440Y1240720D02*
X-1795160Y1241020D01*
X-1794950Y1241520D01*
X-1794810Y1242220D01*
X-1794950Y1242820D01*
X-1795230Y1243220D01*
X-1795720Y1243520D01*
X-1797610D01*
Y1237520D01*
X-1795300D01*
X-1794810Y1237920D01*
X-1794530Y1238520D01*
X-1794390Y1239220D01*
X-1794530Y1239920D01*
X-1794950Y1240520D01*
X-1795440Y1240720D01*
X-1797610D01*
G01X-1788900Y1237520D02*
X-1791700D01*
Y1243520D01*
X-1788900D01*
G01X-1790020Y1240620D02*
X-1791700D01*
G01X-1780440Y1237520D02*
Y1243520D01*
X-1779040D01*
X-1778480Y1243220D01*
X-1778060Y1242820D01*
X-1777710Y1242220D01*
X-1777430Y1241520D01*
X-1777360Y1240520D01*
X-1777430Y1239520D01*
X-1777710Y1238820D01*
X-1778060Y1238220D01*
X-1778480Y1237820D01*
X-1779040Y1237520D01*
X-1780440D01*
G01X-1774040Y1243520D02*
X-1772360D01*
G01X-1773200D02*
Y1237520D01*
G01X-1774040D02*
X-1772360D01*
G01X-1768970Y1238320D02*
X-1768410Y1237820D01*
X-1767780Y1237520D01*
X-1767220D01*
X-1766660Y1237820D01*
X-1766240Y1238320D01*
X-1766030Y1239020D01*
X-1766170Y1239720D01*
X-1766520Y1240320D01*
X-1767150Y1240720D01*
X-1767990Y1240920D01*
X-1768480Y1241320D01*
X-1768690Y1242020D01*
X-1768550Y1242720D01*
X-1768200Y1243220D01*
X-1767710Y1243520D01*
X-1767220D01*
X-1766730Y1243320D01*
X-1766310Y1242820D01*
G01X-1760260Y1243020D02*
X-1760680Y1243320D01*
X-1761170Y1243520D01*
X-1761730D01*
X-1762360Y1243220D01*
X-1762850Y1242720D01*
X-1763200Y1242120D01*
X-1763480Y1241120D01*
X-1763550Y1240220D01*
X-1763410Y1239320D01*
X-1763200Y1238720D01*
X-1762780Y1238120D01*
X-1762290Y1237720D01*
X-1761800Y1237520D01*
X-1761310D01*
X-1760820Y1237720D01*
X-1760400Y1238020D01*
X-1760050Y1238420D01*
G01X-1757500Y1243520D02*
Y1237520D01*
X-1754700D01*
G01X-1750400D02*
X-1750960Y1237620D01*
X-1751450Y1238020D01*
X-1751870Y1238620D01*
X-1752150Y1239320D01*
X-1752290Y1240120D01*
Y1240920D01*
X-1752150Y1241720D01*
X-1751870Y1242420D01*
X-1751450Y1243020D01*
X-1750960Y1243420D01*
X-1750400Y1243520D01*
X-1749840Y1243420D01*
X-1749350Y1243020D01*
X-1748930Y1242420D01*
X-1748650Y1241720D01*
X-1748510Y1240920D01*
Y1240120D01*
X-1748650Y1239320D01*
X-1748930Y1238620D01*
X-1749350Y1238020D01*
X-1749840Y1237620D01*
X-1750400Y1237520D01*
G01X-1746170Y1238320D02*
X-1745610Y1237820D01*
X-1744980Y1237520D01*
X-1744420D01*
X-1743860Y1237820D01*
X-1743440Y1238320D01*
X-1743230Y1239020D01*
X-1743370Y1239720D01*
X-1743720Y1240320D01*
X-1744350Y1240720D01*
X-1745190Y1240920D01*
X-1745680Y1241320D01*
X-1745890Y1242020D01*
X-1745750Y1242720D01*
X-1745400Y1243220D01*
X-1744910Y1243520D01*
X-1744420D01*
X-1743930Y1243320D01*
X-1743510Y1242820D01*
G01X-1737600Y1237520D02*
X-1740400D01*
Y1243520D01*
X-1737600D01*
G01X-1738720Y1240620D02*
X-1740400D01*
G01X-1734840Y1237520D02*
Y1243520D01*
X-1733440D01*
X-1732880Y1243220D01*
X-1732460Y1242820D01*
X-1732110Y1242220D01*
X-1731830Y1241520D01*
X-1731760Y1240520D01*
X-1731830Y1239520D01*
X-1732110Y1238820D01*
X-1732460Y1238220D01*
X-1732880Y1237820D01*
X-1733440Y1237520D01*
X-1734840D01*
G01X-1724000Y1243520D02*
X-1723020Y1237520D01*
X-1721900Y1243520D01*
X-1720780Y1237520D01*
X-1719800Y1243520D01*
G01X-1717040D02*
X-1715360D01*
G01X-1716200D02*
Y1237520D01*
G01X-1717040D02*
X-1715360D01*
G01X-1710500Y1243520D02*
Y1237520D01*
G01X-1712110Y1243520D02*
X-1708890D01*
G01X-1706270Y1237520D02*
Y1243520D01*
G01X-1703330D02*
Y1237520D01*
G01Y1240520D02*
X-1706270D01*
G01X-1700010Y1239520D02*
X-1698190D01*
G01X-1892900Y1225000D02*
X-1893460Y1225100D01*
X-1893950Y1225500D01*
X-1894370Y1226100D01*
X-1894650Y1226800D01*
X-1894790Y1227600D01*
Y1228400D01*
X-1894650Y1229200D01*
X-1894370Y1229900D01*
X-1893950Y1230500D01*
X-1893460Y1230900D01*
X-1892900Y1231000D01*
X-1892340Y1230900D01*
X-1891850Y1230500D01*
X-1891430Y1229900D01*
X-1891150Y1229200D01*
X-1891010Y1228400D01*
Y1227600D01*
X-1891150Y1226800D01*
X-1891430Y1226100D01*
X-1891850Y1225500D01*
X-1892340Y1225100D01*
X-1892900Y1225000D01*
G01X-1888740Y1231000D02*
Y1226700D01*
X-1888460Y1225800D01*
X-1887900Y1225200D01*
X-1887200Y1225000D01*
X-1886500Y1225200D01*
X-1885940Y1225800D01*
X-1885660Y1226700D01*
Y1231000D01*
G01X-1881500D02*
Y1225000D01*
G01X-1883110Y1231000D02*
X-1879890D01*
G01X-1870100D02*
Y1225000D01*
G01X-1871710Y1231000D02*
X-1868490D01*
G01X-1865870Y1225000D02*
Y1231000D01*
G01X-1862930D02*
Y1225000D01*
G01Y1228000D02*
X-1865870D01*
G01X-1857300Y1225000D02*
X-1860100D01*
Y1231000D01*
X-1857300D01*
G01X-1858420Y1228100D02*
X-1860100D01*
G01X-1848700Y1225000D02*
Y1231000D01*
X-1847020D01*
X-1846460Y1230700D01*
X-1846040Y1230000D01*
X-1845900Y1229200D01*
X-1846040Y1228400D01*
X-1846390Y1227800D01*
X-1847020Y1227500D01*
X-1848700D01*
G01X-1843000Y1225000D02*
Y1231000D01*
X-1841250D01*
X-1840690Y1230700D01*
X-1840340Y1230300D01*
X-1840200Y1229500D01*
X-1840340Y1228700D01*
X-1840760Y1228200D01*
X-1841250Y1227900D01*
X-1843000D01*
G01X-1841250D02*
X-1840200Y1225000D01*
G01X-1836740Y1231000D02*
X-1835060D01*
G01X-1835900D02*
Y1225000D01*
G01X-1836740D02*
X-1835060D01*
G01X-1830200D02*
X-1830760Y1225100D01*
X-1831250Y1225500D01*
X-1831670Y1226100D01*
X-1831950Y1226800D01*
X-1832090Y1227600D01*
Y1228400D01*
X-1831950Y1229200D01*
X-1831670Y1229900D01*
X-1831250Y1230500D01*
X-1830760Y1230900D01*
X-1830200Y1231000D01*
X-1829640Y1230900D01*
X-1829150Y1230500D01*
X-1828730Y1229900D01*
X-1828450Y1229200D01*
X-1828310Y1228400D01*
Y1227600D01*
X-1828450Y1226800D01*
X-1828730Y1226100D01*
X-1829150Y1225500D01*
X-1829640Y1225100D01*
X-1830200Y1225000D01*
G01X-1825900D02*
Y1231000D01*
X-1824150D01*
X-1823590Y1230700D01*
X-1823240Y1230300D01*
X-1823100Y1229500D01*
X-1823240Y1228700D01*
X-1823660Y1228200D01*
X-1824150Y1227900D01*
X-1825900D01*
G01X-1824150D02*
X-1823100Y1225000D01*
G01X-1815200Y1231000D02*
X-1814220Y1225000D01*
X-1813100Y1231000D01*
X-1811980Y1225000D01*
X-1811000Y1231000D01*
G01X-1808800Y1225000D02*
Y1231000D01*
X-1807050D01*
X-1806490Y1230700D01*
X-1806140Y1230300D01*
X-1806000Y1229500D01*
X-1806140Y1228700D01*
X-1806560Y1228200D01*
X-1807050Y1227900D01*
X-1808800D01*
G01X-1807050D02*
X-1806000Y1225000D01*
G01X-1802540Y1231000D02*
X-1800860D01*
G01X-1801700D02*
Y1225000D01*
G01X-1802540D02*
X-1800860D01*
G01X-1796000Y1231000D02*
Y1225000D01*
G01X-1797610Y1231000D02*
X-1794390D01*
G01X-1790300D02*
Y1225000D01*
G01X-1791910Y1231000D02*
X-1788690D01*
G01X-1783200Y1225000D02*
X-1786000D01*
Y1231000D01*
X-1783200D01*
G01X-1784320Y1228100D02*
X-1786000D01*
G01X-1780510Y1225000D02*
Y1231000D01*
X-1777290Y1225000D01*
Y1231000D01*
G01X-1765960Y1230500D02*
X-1766380Y1230800D01*
X-1766870Y1231000D01*
X-1767430D01*
X-1768060Y1230700D01*
X-1768550Y1230200D01*
X-1768900Y1229600D01*
X-1769180Y1228600D01*
X-1769250Y1227700D01*
X-1769110Y1226800D01*
X-1768900Y1226200D01*
X-1768480Y1225600D01*
X-1767990Y1225200D01*
X-1767500Y1225000D01*
X-1767010D01*
X-1766520Y1225200D01*
X-1766100Y1225500D01*
X-1765750Y1225900D01*
G01X-1761800Y1225000D02*
X-1762360Y1225100D01*
X-1762850Y1225500D01*
X-1763270Y1226100D01*
X-1763550Y1226800D01*
X-1763690Y1227600D01*
Y1228400D01*
X-1763550Y1229200D01*
X-1763270Y1229900D01*
X-1762850Y1230500D01*
X-1762360Y1230900D01*
X-1761800Y1231000D01*
X-1761240Y1230900D01*
X-1760750Y1230500D01*
X-1760330Y1229900D01*
X-1760050Y1229200D01*
X-1759910Y1228400D01*
Y1227600D01*
X-1760050Y1226800D01*
X-1760330Y1226100D01*
X-1760750Y1225500D01*
X-1761240Y1225100D01*
X-1761800Y1225000D01*
G01X-1757710D02*
Y1231000D01*
X-1754490Y1225000D01*
Y1231000D01*
G01X-1751870Y1225800D02*
X-1751310Y1225300D01*
X-1750680Y1225000D01*
X-1750120D01*
X-1749560Y1225300D01*
X-1749140Y1225800D01*
X-1748930Y1226500D01*
X-1749070Y1227200D01*
X-1749420Y1227800D01*
X-1750050Y1228200D01*
X-1750890Y1228400D01*
X-1751380Y1228800D01*
X-1751590Y1229500D01*
X-1751450Y1230200D01*
X-1751100Y1230700D01*
X-1750610Y1231000D01*
X-1750120D01*
X-1749630Y1230800D01*
X-1749210Y1230300D01*
G01X-1743300Y1225000D02*
X-1746100D01*
Y1231000D01*
X-1743300D01*
G01X-1744420Y1228100D02*
X-1746100D01*
G01X-1740610Y1225000D02*
Y1231000D01*
X-1737390Y1225000D01*
Y1231000D01*
G01X-1733300D02*
Y1225000D01*
G01X-1734910Y1231000D02*
X-1731690D01*
G01X-1721900Y1225000D02*
X-1722460Y1225100D01*
X-1722950Y1225500D01*
X-1723370Y1226100D01*
X-1723650Y1226800D01*
X-1723790Y1227600D01*
Y1228400D01*
X-1723650Y1229200D01*
X-1723370Y1229900D01*
X-1722950Y1230500D01*
X-1722460Y1230900D01*
X-1721900Y1231000D01*
X-1721340Y1230900D01*
X-1720850Y1230500D01*
X-1720430Y1229900D01*
X-1720150Y1229200D01*
X-1720010Y1228400D01*
Y1227600D01*
X-1720150Y1226800D01*
X-1720430Y1226100D01*
X-1720850Y1225500D01*
X-1721340Y1225100D01*
X-1721900Y1225000D01*
G01X-1717530D02*
Y1231000D01*
X-1714870D01*
G01X-1715850Y1228100D02*
X-1717530D01*
G01X-1893740Y1256000D02*
X-1892060D01*
G01X-1892900D02*
Y1250000D01*
G01X-1893740D02*
X-1892060D01*
G01X-1888670Y1250800D02*
X-1888110Y1250300D01*
X-1887480Y1250000D01*
X-1886920D01*
X-1886360Y1250300D01*
X-1885940Y1250800D01*
X-1885730Y1251500D01*
X-1885870Y1252200D01*
X-1886220Y1252800D01*
X-1886850Y1253200D01*
X-1887690Y1253400D01*
X-1888180Y1253800D01*
X-1888390Y1254500D01*
X-1888250Y1255200D01*
X-1887900Y1255700D01*
X-1887410Y1256000D01*
X-1886920D01*
X-1886430Y1255800D01*
X-1886010Y1255300D01*
G01X-1877200Y1250000D02*
Y1256000D01*
X-1875450D01*
X-1874890Y1255700D01*
X-1874540Y1255300D01*
X-1874400Y1254500D01*
X-1874540Y1253700D01*
X-1874960Y1253200D01*
X-1875450Y1252900D01*
X-1877200D01*
G01X-1875450D02*
X-1874400Y1250000D01*
G01X-1868700D02*
X-1871500D01*
Y1256000D01*
X-1868700D01*
G01X-1869820Y1253100D02*
X-1871500D01*
G01X-1862860Y1255500D02*
X-1863280Y1255800D01*
X-1863770Y1256000D01*
X-1864330D01*
X-1864960Y1255700D01*
X-1865450Y1255200D01*
X-1865800Y1254600D01*
X-1866080Y1253600D01*
X-1866150Y1252700D01*
X-1866010Y1251800D01*
X-1865800Y1251200D01*
X-1865380Y1250600D01*
X-1864890Y1250200D01*
X-1864400Y1250000D01*
X-1863910D01*
X-1863420Y1250200D01*
X-1863000Y1250500D01*
X-1862650Y1250900D01*
G01X-1857300Y1250000D02*
X-1860100D01*
Y1256000D01*
X-1857300D01*
G01X-1858420Y1253100D02*
X-1860100D01*
G01X-1853840Y1256000D02*
X-1852160D01*
G01X-1853000D02*
Y1250000D01*
G01X-1853840D02*
X-1852160D01*
G01X-1849050Y1256000D02*
X-1847300Y1250000D01*
X-1845550Y1256000D01*
G01X-1840200Y1250000D02*
X-1843000D01*
Y1256000D01*
X-1840200D01*
G01X-1841320Y1253100D02*
X-1843000D01*
G01X-1837440Y1250000D02*
Y1256000D01*
X-1836040D01*
X-1835480Y1255700D01*
X-1835060Y1255300D01*
X-1834710Y1254700D01*
X-1834430Y1254000D01*
X-1834360Y1253000D01*
X-1834430Y1252000D01*
X-1834710Y1251300D01*
X-1835060Y1250700D01*
X-1835480Y1250300D01*
X-1836040Y1250000D01*
X-1837440D01*
G01X-1825340Y1256000D02*
X-1823660D01*
G01X-1824500D02*
Y1250000D01*
G01X-1825340D02*
X-1823660D01*
G01X-1820410D02*
Y1256000D01*
X-1817190Y1250000D01*
Y1256000D01*
G01X-1805860Y1255500D02*
X-1806280Y1255800D01*
X-1806770Y1256000D01*
X-1807330D01*
X-1807960Y1255700D01*
X-1808450Y1255200D01*
X-1808800Y1254600D01*
X-1809080Y1253600D01*
X-1809150Y1252700D01*
X-1809010Y1251800D01*
X-1808800Y1251200D01*
X-1808380Y1250600D01*
X-1807890Y1250200D01*
X-1807400Y1250000D01*
X-1806910D01*
X-1806420Y1250200D01*
X-1806000Y1250500D01*
X-1805650Y1250900D01*
G01X-1801700Y1250000D02*
X-1802260Y1250100D01*
X-1802750Y1250500D01*
X-1803170Y1251100D01*
X-1803450Y1251800D01*
X-1803590Y1252600D01*
Y1253400D01*
X-1803450Y1254200D01*
X-1803170Y1254900D01*
X-1802750Y1255500D01*
X-1802260Y1255900D01*
X-1801700Y1256000D01*
X-1801140Y1255900D01*
X-1800650Y1255500D01*
X-1800230Y1254900D01*
X-1799950Y1254200D01*
X-1799810Y1253400D01*
Y1252600D01*
X-1799950Y1251800D01*
X-1800230Y1251100D01*
X-1800650Y1250500D01*
X-1801140Y1250100D01*
X-1801700Y1250000D01*
G01X-1797610D02*
Y1256000D01*
X-1794390Y1250000D01*
Y1256000D01*
G01X-1791630Y1250000D02*
Y1256000D01*
X-1788970D01*
G01X-1789950Y1253100D02*
X-1791630D01*
G01X-1785440Y1256000D02*
X-1783760D01*
G01X-1784600D02*
Y1250000D01*
G01X-1785440D02*
X-1783760D01*
G01X-1780440D02*
Y1256000D01*
X-1779040D01*
X-1778480Y1255700D01*
X-1778060Y1255300D01*
X-1777710Y1254700D01*
X-1777430Y1254000D01*
X-1777360Y1253000D01*
X-1777430Y1252000D01*
X-1777710Y1251300D01*
X-1778060Y1250700D01*
X-1778480Y1250300D01*
X-1779040Y1250000D01*
X-1780440D01*
G01X-1771800D02*
X-1774600D01*
Y1256000D01*
X-1771800D01*
G01X-1772920Y1253100D02*
X-1774600D01*
G01X-1769110Y1250000D02*
Y1256000D01*
X-1765890Y1250000D01*
Y1256000D01*
G01X-1760260Y1255500D02*
X-1760680Y1255800D01*
X-1761170Y1256000D01*
X-1761730D01*
X-1762360Y1255700D01*
X-1762850Y1255200D01*
X-1763200Y1254600D01*
X-1763480Y1253600D01*
X-1763550Y1252700D01*
X-1763410Y1251800D01*
X-1763200Y1251200D01*
X-1762780Y1250600D01*
X-1762290Y1250200D01*
X-1761800Y1250000D01*
X-1761310D01*
X-1760820Y1250200D01*
X-1760400Y1250500D01*
X-1760050Y1250900D01*
G01X-1754700Y1250000D02*
X-1757500D01*
Y1256000D01*
X-1754700D01*
G01X-1755820Y1253100D02*
X-1757500D01*
G01X-1746450Y1250000D02*
X-1744700Y1256000D01*
X-1742950Y1250000D01*
G01X-1743580Y1252100D02*
X-1745820D01*
G01X-1740610Y1250000D02*
Y1256000D01*
X-1737390Y1250000D01*
Y1256000D01*
G01X-1734840Y1250000D02*
Y1256000D01*
X-1733440D01*
X-1732880Y1255700D01*
X-1732460Y1255300D01*
X-1732110Y1254700D01*
X-1731830Y1254000D01*
X-1731760Y1253000D01*
X-1731830Y1252000D01*
X-1732110Y1251300D01*
X-1732460Y1250700D01*
X-1732880Y1250300D01*
X-1733440Y1250000D01*
X-1734840D01*
G01X-1722740Y1256000D02*
X-1721060D01*
G01X-1721900D02*
Y1250000D01*
G01X-1722740D02*
X-1721060D01*
G01X-1716200Y1256000D02*
Y1250000D01*
G01X-1717810Y1256000D02*
X-1714590D01*
G01X-1711970Y1250800D02*
X-1711410Y1250300D01*
X-1710780Y1250000D01*
X-1710220D01*
X-1709660Y1250300D01*
X-1709240Y1250800D01*
X-1709030Y1251500D01*
X-1709170Y1252200D01*
X-1709520Y1252800D01*
X-1710150Y1253200D01*
X-1710990Y1253400D01*
X-1711480Y1253800D01*
X-1711690Y1254500D01*
X-1711550Y1255200D01*
X-1711200Y1255700D01*
X-1710710Y1256000D01*
X-1710220D01*
X-1709730Y1255800D01*
X-1709310Y1255300D01*
G01X-1892900Y1262520D02*
X-1893460Y1262620D01*
X-1893950Y1263020D01*
X-1894370Y1263620D01*
X-1894650Y1264320D01*
X-1894790Y1265120D01*
Y1265920D01*
X-1894650Y1266720D01*
X-1894370Y1267420D01*
X-1893950Y1268020D01*
X-1893460Y1268420D01*
X-1892900Y1268520D01*
X-1892340Y1268420D01*
X-1891850Y1268020D01*
X-1891430Y1267420D01*
X-1891150Y1266720D01*
X-1891010Y1265920D01*
Y1265120D01*
X-1891150Y1264320D01*
X-1891430Y1263620D01*
X-1891850Y1263020D01*
X-1892340Y1262620D01*
X-1892900Y1262520D01*
G01X-1888530D02*
Y1268520D01*
X-1885870D01*
G01X-1886850Y1265620D02*
X-1888530D01*
G01X-1877620Y1262520D02*
Y1268520D01*
X-1875800Y1263520D01*
X-1873980Y1268520D01*
Y1262520D01*
G01X-1870940Y1268520D02*
X-1869260D01*
G01X-1870100D02*
Y1262520D01*
G01X-1870940D02*
X-1869260D01*
G01X-1862860Y1268020D02*
X-1863280Y1268320D01*
X-1863770Y1268520D01*
X-1864330D01*
X-1864960Y1268220D01*
X-1865450Y1267720D01*
X-1865800Y1267120D01*
X-1866080Y1266120D01*
X-1866150Y1265220D01*
X-1866010Y1264320D01*
X-1865800Y1263720D01*
X-1865380Y1263120D01*
X-1864890Y1262720D01*
X-1864400Y1262520D01*
X-1863910D01*
X-1863420Y1262720D01*
X-1863000Y1263020D01*
X-1862650Y1263420D01*
G01X-1860100Y1262520D02*
Y1268520D01*
X-1858350D01*
X-1857790Y1268220D01*
X-1857440Y1267820D01*
X-1857300Y1267020D01*
X-1857440Y1266220D01*
X-1857860Y1265720D01*
X-1858350Y1265420D01*
X-1860100D01*
G01X-1858350D02*
X-1857300Y1262520D01*
G01X-1853000D02*
X-1853560Y1262620D01*
X-1854050Y1263020D01*
X-1854470Y1263620D01*
X-1854750Y1264320D01*
X-1854890Y1265120D01*
Y1265920D01*
X-1854750Y1266720D01*
X-1854470Y1267420D01*
X-1854050Y1268020D01*
X-1853560Y1268420D01*
X-1853000Y1268520D01*
X-1852440Y1268420D01*
X-1851950Y1268020D01*
X-1851530Y1267420D01*
X-1851250Y1266720D01*
X-1851110Y1265920D01*
Y1265120D01*
X-1851250Y1264320D01*
X-1851530Y1263620D01*
X-1851950Y1263020D01*
X-1852440Y1262620D01*
X-1853000Y1262520D01*
G01X-1848770Y1263320D02*
X-1848210Y1262820D01*
X-1847580Y1262520D01*
X-1847020D01*
X-1846460Y1262820D01*
X-1846040Y1263320D01*
X-1845830Y1264020D01*
X-1845970Y1264720D01*
X-1846320Y1265320D01*
X-1846950Y1265720D01*
X-1847790Y1265920D01*
X-1848280Y1266320D01*
X-1848490Y1267020D01*
X-1848350Y1267720D01*
X-1848000Y1268220D01*
X-1847510Y1268520D01*
X-1847020D01*
X-1846530Y1268320D01*
X-1846110Y1267820D01*
G01X-1841600Y1262520D02*
X-1842160Y1262620D01*
X-1842650Y1263020D01*
X-1843070Y1263620D01*
X-1843350Y1264320D01*
X-1843490Y1265120D01*
Y1265920D01*
X-1843350Y1266720D01*
X-1843070Y1267420D01*
X-1842650Y1268020D01*
X-1842160Y1268420D01*
X-1841600Y1268520D01*
X-1841040Y1268420D01*
X-1840550Y1268020D01*
X-1840130Y1267420D01*
X-1839850Y1266720D01*
X-1839710Y1265920D01*
Y1265120D01*
X-1839850Y1264320D01*
X-1840130Y1263620D01*
X-1840550Y1263020D01*
X-1841040Y1262620D01*
X-1841600Y1262520D01*
G01X-1837230D02*
Y1268520D01*
X-1834570D01*
G01X-1835550Y1265620D02*
X-1837230D01*
G01X-1830200Y1268520D02*
Y1262520D01*
G01X-1831810Y1268520D02*
X-1828590D01*
G01X-1817260Y1268020D02*
X-1817680Y1268320D01*
X-1818170Y1268520D01*
X-1818730D01*
X-1819360Y1268220D01*
X-1819850Y1267720D01*
X-1820200Y1267120D01*
X-1820480Y1266120D01*
X-1820550Y1265220D01*
X-1820410Y1264320D01*
X-1820200Y1263720D01*
X-1819780Y1263120D01*
X-1819290Y1262720D01*
X-1818800Y1262520D01*
X-1818310D01*
X-1817820Y1262720D01*
X-1817400Y1263020D01*
X-1817050Y1263420D01*
G01X-1813100Y1262520D02*
X-1813660Y1262620D01*
X-1814150Y1263020D01*
X-1814570Y1263620D01*
X-1814850Y1264320D01*
X-1814990Y1265120D01*
Y1265920D01*
X-1814850Y1266720D01*
X-1814570Y1267420D01*
X-1814150Y1268020D01*
X-1813660Y1268420D01*
X-1813100Y1268520D01*
X-1812540Y1268420D01*
X-1812050Y1268020D01*
X-1811630Y1267420D01*
X-1811350Y1266720D01*
X-1811210Y1265920D01*
Y1265120D01*
X-1811350Y1264320D01*
X-1811630Y1263620D01*
X-1812050Y1263020D01*
X-1812540Y1262620D01*
X-1813100Y1262520D01*
G01X-1808800D02*
Y1268520D01*
X-1807050D01*
X-1806490Y1268220D01*
X-1806140Y1267820D01*
X-1806000Y1267020D01*
X-1806140Y1266220D01*
X-1806560Y1265720D01*
X-1807050Y1265420D01*
X-1808800D01*
G01X-1807050D02*
X-1806000Y1262520D01*
G01X-1803100D02*
Y1268520D01*
X-1801420D01*
X-1800860Y1268220D01*
X-1800440Y1267520D01*
X-1800300Y1266720D01*
X-1800440Y1265920D01*
X-1800790Y1265320D01*
X-1801420Y1265020D01*
X-1803100D01*
G01X-1796000Y1262520D02*
X-1796560Y1262620D01*
X-1797050Y1263020D01*
X-1797470Y1263620D01*
X-1797750Y1264320D01*
X-1797890Y1265120D01*
Y1265920D01*
X-1797750Y1266720D01*
X-1797470Y1267420D01*
X-1797050Y1268020D01*
X-1796560Y1268420D01*
X-1796000Y1268520D01*
X-1795440Y1268420D01*
X-1794950Y1268020D01*
X-1794530Y1267420D01*
X-1794250Y1266720D01*
X-1794110Y1265920D01*
Y1265120D01*
X-1794250Y1264320D01*
X-1794530Y1263620D01*
X-1794950Y1263020D01*
X-1795440Y1262620D01*
X-1796000Y1262520D01*
G01X-1791700D02*
Y1268520D01*
X-1789950D01*
X-1789390Y1268220D01*
X-1789040Y1267820D01*
X-1788900Y1267020D01*
X-1789040Y1266220D01*
X-1789460Y1265720D01*
X-1789950Y1265420D01*
X-1791700D01*
G01X-1789950D02*
X-1788900Y1262520D01*
G01X-1786350D02*
X-1784600Y1268520D01*
X-1782850Y1262520D01*
G01X-1783480Y1264620D02*
X-1785720D01*
G01X-1778900Y1268520D02*
Y1262520D01*
G01X-1780510Y1268520D02*
X-1777290D01*
G01X-1774040D02*
X-1772360D01*
G01X-1773200D02*
Y1262520D01*
G01X-1774040D02*
X-1772360D01*
G01X-1767500D02*
X-1768060Y1262620D01*
X-1768550Y1263020D01*
X-1768970Y1263620D01*
X-1769250Y1264320D01*
X-1769390Y1265120D01*
Y1265920D01*
X-1769250Y1266720D01*
X-1768970Y1267420D01*
X-1768550Y1268020D01*
X-1768060Y1268420D01*
X-1767500Y1268520D01*
X-1766940Y1268420D01*
X-1766450Y1268020D01*
X-1766030Y1267420D01*
X-1765750Y1266720D01*
X-1765610Y1265920D01*
Y1265120D01*
X-1765750Y1264320D01*
X-1766030Y1263620D01*
X-1766450Y1263020D01*
X-1766940Y1262620D01*
X-1767500Y1262520D01*
G01X-1763410D02*
Y1268520D01*
X-1760190Y1262520D01*
Y1268520D01*
G01X-1756100Y1262320D02*
X-1756240Y1262420D01*
Y1262620D01*
X-1756100Y1262720D01*
X-1755960Y1262620D01*
Y1262420D01*
X-1756100Y1262320D01*
G01X-1744700Y1268520D02*
Y1262520D01*
G01X-1746310Y1268520D02*
X-1743090D01*
G01X-1740470Y1262520D02*
Y1268520D01*
G01X-1737530D02*
Y1262520D01*
G01Y1265520D02*
X-1740470D01*
G01X-1734140Y1268520D02*
X-1732460D01*
G01X-1733300D02*
Y1262520D01*
G01X-1734140D02*
X-1732460D01*
G01X-1729070Y1263320D02*
X-1728510Y1262820D01*
X-1727880Y1262520D01*
X-1727320D01*
X-1726760Y1262820D01*
X-1726340Y1263320D01*
X-1726130Y1264020D01*
X-1726270Y1264720D01*
X-1726620Y1265320D01*
X-1727250Y1265720D01*
X-1728090Y1265920D01*
X-1728580Y1266320D01*
X-1728790Y1267020D01*
X-1728650Y1267720D01*
X-1728300Y1268220D01*
X-1727810Y1268520D01*
X-1727320D01*
X-1726830Y1268320D01*
X-1726410Y1267820D01*
G01X-1717740Y1262520D02*
Y1268520D01*
X-1716340D01*
X-1715780Y1268220D01*
X-1715360Y1267820D01*
X-1715010Y1267220D01*
X-1714730Y1266520D01*
X-1714660Y1265520D01*
X-1714730Y1264520D01*
X-1715010Y1263820D01*
X-1715360Y1263220D01*
X-1715780Y1262820D01*
X-1716340Y1262520D01*
X-1717740D01*
G01X-1711900D02*
Y1268520D01*
X-1710150D01*
X-1709590Y1268220D01*
X-1709240Y1267820D01*
X-1709100Y1267020D01*
X-1709240Y1266220D01*
X-1709660Y1265720D01*
X-1710150Y1265420D01*
X-1711900D01*
G01X-1710150D02*
X-1709100Y1262520D01*
G01X-1706550D02*
X-1704800Y1268520D01*
X-1703050Y1262520D01*
G01X-1703680Y1264620D02*
X-1705920D01*
G01X-1701200Y1268520D02*
X-1700220Y1262520D01*
X-1699100Y1268520D01*
X-1697980Y1262520D01*
X-1697000Y1268520D01*
G01X-1694240D02*
X-1692560D01*
G01X-1693400D02*
Y1262520D01*
G01X-1694240D02*
X-1692560D01*
G01X-1689310D02*
Y1268520D01*
X-1686090Y1262520D01*
Y1268520D01*
G01X-1681580Y1265520D02*
X-1680180D01*
Y1263720D01*
X-1680600Y1263120D01*
X-1681090Y1262720D01*
X-1681790Y1262520D01*
X-1682490Y1262720D01*
X-1682980Y1263120D01*
X-1683400Y1263720D01*
X-1683680Y1264420D01*
X-1683820Y1265220D01*
Y1265920D01*
X-1683680Y1266520D01*
X-1683400Y1267220D01*
X-1682980Y1267820D01*
X-1682560Y1268220D01*
X-1682000Y1268520D01*
X-1681510D01*
X-1680950Y1268320D01*
X-1680530Y1267920D01*
G01X-1895000Y1281000D02*
X-1894020Y1275000D01*
X-1892900Y1281000D01*
X-1891780Y1275000D01*
X-1890800Y1281000D01*
G01X-1888670Y1275000D02*
Y1281000D01*
G01X-1885730D02*
Y1275000D01*
G01Y1278000D02*
X-1888670D01*
G01X-1882340Y1281000D02*
X-1880660D01*
G01X-1881500D02*
Y1275000D01*
G01X-1882340D02*
X-1880660D01*
G01X-1874260Y1280500D02*
X-1874680Y1280800D01*
X-1875170Y1281000D01*
X-1875730D01*
X-1876360Y1280700D01*
X-1876850Y1280200D01*
X-1877200Y1279600D01*
X-1877480Y1278600D01*
X-1877550Y1277700D01*
X-1877410Y1276800D01*
X-1877200Y1276200D01*
X-1876780Y1275600D01*
X-1876290Y1275200D01*
X-1875800Y1275000D01*
X-1875310D01*
X-1874820Y1275200D01*
X-1874400Y1275500D01*
X-1874050Y1275900D01*
G01X-1871570Y1275000D02*
Y1281000D01*
G01X-1868630D02*
Y1275000D01*
G01Y1278000D02*
X-1871570D01*
G01X-1859540Y1281000D02*
X-1857860D01*
G01X-1858700D02*
Y1275000D01*
G01X-1859540D02*
X-1857860D01*
G01X-1854470Y1275800D02*
X-1853910Y1275300D01*
X-1853280Y1275000D01*
X-1852720D01*
X-1852160Y1275300D01*
X-1851740Y1275800D01*
X-1851530Y1276500D01*
X-1851670Y1277200D01*
X-1852020Y1277800D01*
X-1852650Y1278200D01*
X-1853490Y1278400D01*
X-1853980Y1278800D01*
X-1854190Y1279500D01*
X-1854050Y1280200D01*
X-1853700Y1280700D01*
X-1853210Y1281000D01*
X-1852720D01*
X-1852230Y1280800D01*
X-1851810Y1280300D01*
G01X-1841600Y1281000D02*
Y1275000D01*
G01X-1843210Y1281000D02*
X-1839990D01*
G01X-1837370Y1275000D02*
Y1281000D01*
G01X-1834430D02*
Y1275000D01*
G01Y1278000D02*
X-1837370D01*
G01X-1828800Y1275000D02*
X-1831600D01*
Y1281000D01*
X-1828800D01*
G01X-1829920Y1278100D02*
X-1831600D01*
G01X-1820200Y1275000D02*
Y1281000D01*
X-1818520D01*
X-1817960Y1280700D01*
X-1817540Y1280000D01*
X-1817400Y1279200D01*
X-1817540Y1278400D01*
X-1817890Y1277800D01*
X-1818520Y1277500D01*
X-1820200D01*
G01X-1814500Y1275000D02*
Y1281000D01*
X-1812750D01*
X-1812190Y1280700D01*
X-1811840Y1280300D01*
X-1811700Y1279500D01*
X-1811840Y1278700D01*
X-1812260Y1278200D01*
X-1812750Y1277900D01*
X-1814500D01*
G01X-1812750D02*
X-1811700Y1275000D01*
G01X-1807400D02*
X-1807960Y1275100D01*
X-1808450Y1275500D01*
X-1808870Y1276100D01*
X-1809150Y1276800D01*
X-1809290Y1277600D01*
Y1278400D01*
X-1809150Y1279200D01*
X-1808870Y1279900D01*
X-1808450Y1280500D01*
X-1807960Y1280900D01*
X-1807400Y1281000D01*
X-1806840Y1280900D01*
X-1806350Y1280500D01*
X-1805930Y1279900D01*
X-1805650Y1279200D01*
X-1805510Y1278400D01*
Y1277600D01*
X-1805650Y1276800D01*
X-1805930Y1276100D01*
X-1806350Y1275500D01*
X-1806840Y1275100D01*
X-1807400Y1275000D01*
G01X-1803100D02*
Y1281000D01*
X-1801420D01*
X-1800860Y1280700D01*
X-1800440Y1280000D01*
X-1800300Y1279200D01*
X-1800440Y1278400D01*
X-1800790Y1277800D01*
X-1801420Y1277500D01*
X-1803100D01*
G01X-1797400Y1275000D02*
Y1281000D01*
X-1795650D01*
X-1795090Y1280700D01*
X-1794740Y1280300D01*
X-1794600Y1279500D01*
X-1794740Y1278700D01*
X-1795160Y1278200D01*
X-1795650Y1277900D01*
X-1797400D01*
G01X-1795650D02*
X-1794600Y1275000D01*
G01X-1791140Y1281000D02*
X-1789460D01*
G01X-1790300D02*
Y1275000D01*
G01X-1791140D02*
X-1789460D01*
G01X-1783200D02*
X-1786000D01*
Y1281000D01*
X-1783200D01*
G01X-1784320Y1278100D02*
X-1786000D01*
G01X-1778900Y1281000D02*
Y1275000D01*
G01X-1780510Y1281000D02*
X-1777290D01*
G01X-1774950Y1275000D02*
X-1773200Y1281000D01*
X-1771450Y1275000D01*
G01X-1772080Y1277100D02*
X-1774320D01*
G01X-1768900Y1275000D02*
Y1281000D01*
X-1767150D01*
X-1766590Y1280700D01*
X-1766240Y1280300D01*
X-1766100Y1279500D01*
X-1766240Y1278700D01*
X-1766660Y1278200D01*
X-1767150Y1277900D01*
X-1768900D01*
G01X-1767150D02*
X-1766100Y1275000D01*
G01X-1761800D02*
Y1277700D01*
X-1763200Y1281000D01*
G01X-1760400D02*
X-1761800Y1277700D01*
G01X-1751800Y1275000D02*
Y1281000D01*
X-1750120D01*
X-1749560Y1280700D01*
X-1749140Y1280000D01*
X-1749000Y1279200D01*
X-1749140Y1278400D01*
X-1749490Y1277800D01*
X-1750120Y1277500D01*
X-1751800D01*
G01X-1746100Y1275000D02*
Y1281000D01*
X-1744350D01*
X-1743790Y1280700D01*
X-1743440Y1280300D01*
X-1743300Y1279500D01*
X-1743440Y1278700D01*
X-1743860Y1278200D01*
X-1744350Y1277900D01*
X-1746100D01*
G01X-1744350D02*
X-1743300Y1275000D01*
G01X-1739000D02*
X-1739560Y1275100D01*
X-1740050Y1275500D01*
X-1740470Y1276100D01*
X-1740750Y1276800D01*
X-1740890Y1277600D01*
Y1278400D01*
X-1740750Y1279200D01*
X-1740470Y1279900D01*
X-1740050Y1280500D01*
X-1739560Y1280900D01*
X-1739000Y1281000D01*
X-1738440Y1280900D01*
X-1737950Y1280500D01*
X-1737530Y1279900D01*
X-1737250Y1279200D01*
X-1737110Y1278400D01*
Y1277600D01*
X-1737250Y1276800D01*
X-1737530Y1276100D01*
X-1737950Y1275500D01*
X-1738440Y1275100D01*
X-1739000Y1275000D01*
G01X-1734700D02*
Y1281000D01*
X-1733020D01*
X-1732460Y1280700D01*
X-1732040Y1280000D01*
X-1731900Y1279200D01*
X-1732040Y1278400D01*
X-1732390Y1277800D01*
X-1733020Y1277500D01*
X-1734700D01*
G01X-1726200Y1275000D02*
X-1729000D01*
Y1281000D01*
X-1726200D01*
G01X-1727320Y1278100D02*
X-1729000D01*
G01X-1723300Y1275000D02*
Y1281000D01*
X-1721550D01*
X-1720990Y1280700D01*
X-1720640Y1280300D01*
X-1720500Y1279500D01*
X-1720640Y1278700D01*
X-1721060Y1278200D01*
X-1721550Y1277900D01*
X-1723300D01*
G01X-1721550D02*
X-1720500Y1275000D01*
G01X-1716200Y1281000D02*
Y1275000D01*
G01X-1717810Y1281000D02*
X-1714590D01*
G01X-1710500Y1275000D02*
Y1277700D01*
X-1711900Y1281000D01*
G01X-1709100D02*
X-1710500Y1277700D01*
G01X-1892900Y1293520D02*
Y1287520D01*
G01X-1894510Y1293520D02*
X-1891290D01*
G01X-1888670Y1287520D02*
Y1293520D01*
G01X-1885730D02*
Y1287520D01*
G01Y1290520D02*
X-1888670D01*
G01X-1882340Y1293520D02*
X-1880660D01*
G01X-1881500D02*
Y1287520D01*
G01X-1882340D02*
X-1880660D01*
G01X-1877270Y1288320D02*
X-1876710Y1287820D01*
X-1876080Y1287520D01*
X-1875520D01*
X-1874960Y1287820D01*
X-1874540Y1288320D01*
X-1874330Y1289020D01*
X-1874470Y1289720D01*
X-1874820Y1290320D01*
X-1875450Y1290720D01*
X-1876290Y1290920D01*
X-1876780Y1291320D01*
X-1876990Y1292020D01*
X-1876850Y1292720D01*
X-1876500Y1293220D01*
X-1876010Y1293520D01*
X-1875520D01*
X-1875030Y1293320D01*
X-1874610Y1292820D01*
G01X-1865940Y1287520D02*
Y1293520D01*
X-1864540D01*
X-1863980Y1293220D01*
X-1863560Y1292820D01*
X-1863210Y1292220D01*
X-1862930Y1291520D01*
X-1862860Y1290520D01*
X-1862930Y1289520D01*
X-1863210Y1288820D01*
X-1863560Y1288220D01*
X-1863980Y1287820D01*
X-1864540Y1287520D01*
X-1865940D01*
G01X-1860100D02*
Y1293520D01*
X-1858350D01*
X-1857790Y1293220D01*
X-1857440Y1292820D01*
X-1857300Y1292020D01*
X-1857440Y1291220D01*
X-1857860Y1290720D01*
X-1858350Y1290420D01*
X-1860100D01*
G01X-1858350D02*
X-1857300Y1287520D01*
G01X-1854750D02*
X-1853000Y1293520D01*
X-1851250Y1287520D01*
G01X-1851880Y1289620D02*
X-1854120D01*
G01X-1849400Y1293520D02*
X-1848420Y1287520D01*
X-1847300Y1293520D01*
X-1846180Y1287520D01*
X-1845200Y1293520D01*
G01X-1842440D02*
X-1840760D01*
G01X-1841600D02*
Y1287520D01*
G01X-1842440D02*
X-1840760D01*
G01X-1837510D02*
Y1293520D01*
X-1834290Y1287520D01*
Y1293520D01*
G01X-1829780Y1290520D02*
X-1828380D01*
Y1288720D01*
X-1828800Y1288120D01*
X-1829290Y1287720D01*
X-1829990Y1287520D01*
X-1830690Y1287720D01*
X-1831180Y1288120D01*
X-1831600Y1288720D01*
X-1831880Y1289420D01*
X-1832020Y1290220D01*
Y1290920D01*
X-1831880Y1291520D01*
X-1831600Y1292220D01*
X-1831180Y1292820D01*
X-1830760Y1293220D01*
X-1830200Y1293520D01*
X-1829710D01*
X-1829150Y1293320D01*
X-1828730Y1292920D01*
G01X-1817260Y1293020D02*
X-1817680Y1293320D01*
X-1818170Y1293520D01*
X-1818730D01*
X-1819360Y1293220D01*
X-1819850Y1292720D01*
X-1820200Y1292120D01*
X-1820480Y1291120D01*
X-1820550Y1290220D01*
X-1820410Y1289320D01*
X-1820200Y1288720D01*
X-1819780Y1288120D01*
X-1819290Y1287720D01*
X-1818800Y1287520D01*
X-1818310D01*
X-1817820Y1287720D01*
X-1817400Y1288020D01*
X-1817050Y1288420D01*
G01X-1813100Y1287520D02*
X-1813660Y1287620D01*
X-1814150Y1288020D01*
X-1814570Y1288620D01*
X-1814850Y1289320D01*
X-1814990Y1290120D01*
Y1290920D01*
X-1814850Y1291720D01*
X-1814570Y1292420D01*
X-1814150Y1293020D01*
X-1813660Y1293420D01*
X-1813100Y1293520D01*
X-1812540Y1293420D01*
X-1812050Y1293020D01*
X-1811630Y1292420D01*
X-1811350Y1291720D01*
X-1811210Y1290920D01*
Y1290120D01*
X-1811350Y1289320D01*
X-1811630Y1288620D01*
X-1812050Y1288020D01*
X-1812540Y1287620D01*
X-1813100Y1287520D01*
G01X-1809010D02*
Y1293520D01*
X-1805790Y1287520D01*
Y1293520D01*
G01X-1801700D02*
Y1287520D01*
G01X-1803310Y1293520D02*
X-1800090D01*
G01X-1797750Y1287520D02*
X-1796000Y1293520D01*
X-1794250Y1287520D01*
G01X-1794880Y1289620D02*
X-1797120D01*
G01X-1791140Y1293520D02*
X-1789460D01*
G01X-1790300D02*
Y1287520D01*
G01X-1791140D02*
X-1789460D01*
G01X-1786210D02*
Y1293520D01*
X-1782990Y1287520D01*
Y1293520D01*
G01X-1780370Y1288320D02*
X-1779810Y1287820D01*
X-1779180Y1287520D01*
X-1778620D01*
X-1778060Y1287820D01*
X-1777640Y1288320D01*
X-1777430Y1289020D01*
X-1777570Y1289720D01*
X-1777920Y1290320D01*
X-1778550Y1290720D01*
X-1779390Y1290920D01*
X-1779880Y1291320D01*
X-1780090Y1292020D01*
X-1779950Y1292720D01*
X-1779600Y1293220D01*
X-1779110Y1293520D01*
X-1778620D01*
X-1778130Y1293320D01*
X-1777710Y1292820D01*
G01X-1768340Y1293520D02*
X-1766660D01*
G01X-1767500D02*
Y1287520D01*
G01X-1768340D02*
X-1766660D01*
G01X-1763410D02*
Y1293520D01*
X-1760190Y1287520D01*
Y1293520D01*
G01X-1757430Y1287520D02*
Y1293520D01*
X-1754770D01*
G01X-1755750Y1290620D02*
X-1757430D01*
G01X-1750400Y1287520D02*
X-1750960Y1287620D01*
X-1751450Y1288020D01*
X-1751870Y1288620D01*
X-1752150Y1289320D01*
X-1752290Y1290120D01*
Y1290920D01*
X-1752150Y1291720D01*
X-1751870Y1292420D01*
X-1751450Y1293020D01*
X-1750960Y1293420D01*
X-1750400Y1293520D01*
X-1749840Y1293420D01*
X-1749350Y1293020D01*
X-1748930Y1292420D01*
X-1748650Y1291720D01*
X-1748510Y1290920D01*
Y1290120D01*
X-1748650Y1289320D01*
X-1748930Y1288620D01*
X-1749350Y1288020D01*
X-1749840Y1287620D01*
X-1750400Y1287520D01*
G01X-1746100D02*
Y1293520D01*
X-1744350D01*
X-1743790Y1293220D01*
X-1743440Y1292820D01*
X-1743300Y1292020D01*
X-1743440Y1291220D01*
X-1743860Y1290720D01*
X-1744350Y1290420D01*
X-1746100D01*
G01X-1744350D02*
X-1743300Y1287520D01*
G01X-1740820D02*
Y1293520D01*
X-1739000Y1288520D01*
X-1737180Y1293520D01*
Y1287520D01*
G01X-1735050D02*
X-1733300Y1293520D01*
X-1731550Y1287520D01*
G01X-1732180Y1289620D02*
X-1734420D01*
G01X-1727600Y1293520D02*
Y1287520D01*
G01X-1729210Y1293520D02*
X-1725990D01*
G01X-1722740D02*
X-1721060D01*
G01X-1721900D02*
Y1287520D01*
G01X-1722740D02*
X-1721060D01*
G01X-1716200D02*
X-1716760Y1287620D01*
X-1717250Y1288020D01*
X-1717670Y1288620D01*
X-1717950Y1289320D01*
X-1718090Y1290120D01*
Y1290920D01*
X-1717950Y1291720D01*
X-1717670Y1292420D01*
X-1717250Y1293020D01*
X-1716760Y1293420D01*
X-1716200Y1293520D01*
X-1715640Y1293420D01*
X-1715150Y1293020D01*
X-1714730Y1292420D01*
X-1714450Y1291720D01*
X-1714310Y1290920D01*
Y1290120D01*
X-1714450Y1289320D01*
X-1714730Y1288620D01*
X-1715150Y1288020D01*
X-1715640Y1287620D01*
X-1716200Y1287520D01*
G01X-1712110D02*
Y1293520D01*
X-1708890Y1287520D01*
Y1293520D01*
G01X-1690632Y875096D02*
X-1690212Y874596D01*
X-1689722Y874296D01*
X-1689092Y874196D01*
X-1688462Y874396D01*
X-1687972Y874796D01*
X-1687622Y875496D01*
X-1687552Y876296D01*
X-1687692Y877096D01*
X-1688042Y877596D01*
X-1688532Y877996D01*
X-1689022Y878096D01*
X-1689512Y877996D01*
X-1690142Y877596D01*
X-1689932Y880196D01*
X-1688042D01*
G54D29*
X-1670620Y785270D03*
X-1656000Y-135000D03*
X-1658500Y-31000D03*
X-1639488Y-27500D03*
X-1644488D03*
X-1654488Y-27300D03*
X-1649488Y-27400D03*
X-1633000Y-135500D03*
X-1634488Y-27600D03*
X-1629488Y-27700D03*
X-1618400Y-71600D03*
X-1618300Y-63100D03*
X-1621600Y-61100D03*
Y-65100D03*
X-1618500Y-67200D03*
X-1621600Y-69400D03*
X-1615000Y-37500D03*
Y-27500D03*
Y-32500D03*
X-1610000Y-37500D03*
Y-32500D03*
Y-27500D03*
X-1600000Y-37500D03*
Y-27500D03*
Y-32500D03*
X-1605000Y-37500D03*
Y-32500D03*
Y-27500D03*
X-1595000Y-37500D03*
Y-32500D03*
Y-27500D03*
X-1580000Y-42500D03*
Y-47500D03*
X-1585000Y-42500D03*
Y-47500D03*
X-1590000D03*
Y-42500D03*
X-1580000Y-27500D03*
Y-32500D03*
Y-37500D03*
X-1585000Y-32500D03*
Y-27500D03*
Y-37500D03*
X-1590000D03*
Y-32500D03*
Y-27500D03*
X-1565000Y-42500D03*
Y-47500D03*
X-1575000Y-42500D03*
Y-47500D03*
X-1570000Y-42500D03*
Y-47500D03*
X-1565000Y-27500D03*
Y-32500D03*
Y-37500D03*
X-1575000Y-27500D03*
Y-32500D03*
Y-37500D03*
X-1570000Y-32500D03*
Y-27500D03*
Y-37500D03*
X-1555000Y-47500D03*
Y-42500D03*
X-1550000Y-47500D03*
Y-42500D03*
X-1560000D03*
Y-47500D03*
X-1545000D03*
Y-42500D03*
Y-37500D03*
Y-32500D03*
Y-27500D03*
X-1555000Y-37500D03*
Y-32500D03*
Y-27500D03*
X-1550000Y-37500D03*
Y-32500D03*
Y-27500D03*
X-1560000D03*
Y-32500D03*
Y-37500D03*
X-1530000Y-120300D03*
X-1535000Y-42500D03*
Y-47500D03*
X-1540000Y-42500D03*
Y-47500D03*
X-1535063Y-22160D03*
X-1540000Y-37500D03*
Y-32500D03*
X-1535000Y-37500D03*
Y-32500D03*
X-1530063Y-12160D03*
Y-17160D03*
Y-22160D03*
X-1535063Y-12160D03*
Y-17160D03*
X-1524359Y-125359D03*
X-1515063Y-12160D03*
Y-17160D03*
Y-22160D03*
X-1525063Y-12160D03*
Y-17160D03*
X-1520063Y-12160D03*
Y-17160D03*
X-1525063Y-22160D03*
X-1520063D03*
X-1497043Y-169390D03*
X-1500063Y-12160D03*
Y-17160D03*
Y-22160D03*
X-1510063Y-12160D03*
Y-17160D03*
X-1505063Y-12160D03*
Y-17160D03*
X-1510063Y-22160D03*
X-1505063D03*
X-1497043Y-164390D03*
X-1486693Y-166890D03*
X-1497043Y-149390D03*
X-1486693Y-161890D03*
X-1491652Y-151849D03*
X-1491693Y-156890D03*
X-1486693Y-151890D03*
Y-156890D03*
X-1497043Y-144390D03*
X-1491693Y-136890D03*
X-1486693Y-141890D03*
Y-146890D03*
Y-136890D03*
X-1497043Y-124390D03*
Y-129390D03*
X-1486693Y-121890D03*
Y-126890D03*
X-1491693Y-131890D03*
X-1486693D03*
X-1497043Y-109390D03*
Y-104390D03*
X-1486693Y-101890D03*
Y-106890D03*
X-1491693Y-111890D03*
Y-116890D03*
X-1486693Y-111890D03*
Y-116890D03*
X-1497043Y-89390D03*
X-1486693Y-86890D03*
X-1491693Y-91890D03*
Y-96890D03*
X-1486693Y-91890D03*
Y-96890D03*
Y-76890D03*
X-1491693D03*
X-1486693Y-81890D03*
X-1497000Y-81700D03*
X-1496693Y-76890D03*
Y-71890D03*
X-1486693D03*
X-1491693D03*
X-1485063Y-12160D03*
Y-17160D03*
Y-22160D03*
X-1495063Y-12160D03*
Y-17160D03*
X-1490063Y-12160D03*
Y-17160D03*
X-1495063Y-22160D03*
X-1490063D03*
X-1466693Y-166890D03*
X-1476693D03*
X-1471693D03*
X-1481693D03*
X-1476693Y-161890D03*
X-1481693Y-156890D03*
Y-151890D03*
X-1471693D03*
Y-156890D03*
X-1466693Y-161890D03*
Y-151890D03*
X-1476693D03*
X-1471693Y-161890D03*
X-1466693Y-156890D03*
X-1476693D03*
X-1481693Y-161890D03*
Y-136890D03*
X-1471693D03*
X-1466693Y-141890D03*
X-1476693D03*
X-1466693Y-146890D03*
X-1476693D03*
X-1471693Y-141890D03*
X-1466693Y-136890D03*
X-1476693D03*
X-1471693Y-146890D03*
X-1481693Y-141890D03*
Y-146890D03*
Y-131890D03*
X-1466693Y-121890D03*
X-1476693D03*
X-1466693Y-126890D03*
X-1476693D03*
X-1471693Y-131890D03*
X-1466693D03*
X-1471693Y-121890D03*
X-1476693Y-131890D03*
X-1471693Y-126890D03*
X-1481693Y-121890D03*
Y-126890D03*
Y-111890D03*
Y-116890D03*
X-1466693Y-101890D03*
X-1476693D03*
X-1466693Y-106890D03*
X-1476693D03*
X-1471693Y-111890D03*
Y-116890D03*
X-1466693Y-111890D03*
X-1471693Y-101890D03*
X-1476693Y-111890D03*
X-1466693Y-116890D03*
X-1471693Y-106890D03*
X-1476693Y-116890D03*
X-1481693Y-101890D03*
Y-106890D03*
Y-86890D03*
X-1471693D03*
X-1481693Y-91890D03*
Y-96890D03*
X-1466693Y-86890D03*
X-1476693D03*
X-1471693Y-91890D03*
Y-96890D03*
X-1476693Y-91890D03*
X-1466693D03*
X-1476693Y-96890D03*
X-1466693D03*
X-1481693Y-81890D03*
X-1471693D03*
X-1476693D03*
Y-71890D03*
X-1481693D03*
X-1471693D03*
X-1476693Y-76890D03*
X-1481693D03*
X-1471693D03*
X-1466693D03*
Y-81890D03*
Y-71890D03*
X-1475063Y-22160D03*
X-1470063Y-12160D03*
Y-17160D03*
Y-22160D03*
X-1480063Y-12160D03*
Y-17160D03*
X-1475063Y-12160D03*
Y-17160D03*
X-1480063Y-22160D03*
X-1461693Y-166890D03*
Y-151890D03*
Y-156890D03*
Y-161890D03*
Y-136890D03*
Y-141890D03*
Y-146890D03*
Y-131890D03*
Y-121890D03*
Y-126890D03*
X-1450000Y-112500D03*
X-1461693Y-111890D03*
Y-116890D03*
Y-101890D03*
Y-106890D03*
Y-86890D03*
Y-91890D03*
Y-96890D03*
Y-81890D03*
Y-71890D03*
X-1452000Y-74000D03*
X-1461693Y-76890D03*
X-1452000Y-78200D03*
X-1452100Y-82200D03*
X-1451700Y-65700D03*
X-1451500Y-61800D03*
X-1451800Y-69600D03*
X-1465063Y-12160D03*
Y-17160D03*
Y-22160D03*
X-1437500Y-175000D03*
X-1450000D03*
Y-162500D03*
X-1437500D03*
X-1450000Y-150000D03*
Y-137500D03*
Y-125000D03*
X-1437500Y-100000D03*
X-1436500Y-87500D03*
X-1450000D03*
X-1443500Y-94000D03*
X-1450000Y-100000D03*
X-1449100Y-71800D03*
X-1448900Y-76100D03*
X-1449000Y-80300D03*
X-1448800Y-63800D03*
X-1448700Y-59900D03*
X-1448800Y-67700D03*
X-1434892Y-40389D03*
Y-50389D03*
Y-45389D03*
Y-35389D03*
X-1435000Y1000D03*
X-1425000Y-175000D03*
Y-162500D03*
X-1430500Y-93500D03*
X-1424500Y-100000D03*
X-1425000Y-87500D03*
X-1430000Y-75400D03*
X-1421250Y-81250D03*
X-1431500Y-81000D03*
X-1425000Y-62500D03*
X-1419892Y-50389D03*
Y-40389D03*
Y-45389D03*
X-1427392Y-50389D03*
Y-45389D03*
Y-40389D03*
X-1419892Y-35389D03*
X-1427392D03*
X-1419500Y-18000D03*
X-1432000D03*
X-1420000Y14500D03*
X-1412500Y-175000D03*
Y-162500D03*
X-1406250Y-106250D03*
X-1412000Y-100500D03*
X-1418500Y-93500D03*
X-1412000Y-87000D03*
X-1406250Y-82500D03*
X-1412500Y-75000D03*
Y-62500D03*
X-1404892Y-50389D03*
Y-45389D03*
Y-40389D03*
X-1412392Y-50389D03*
Y-45389D03*
Y-40389D03*
X-1404892Y-35389D03*
X-1412392D03*
X-1407000Y-18000D03*
X-1407500Y14500D03*
X-1387500Y-175000D03*
X-1400000D03*
X-1387500Y-150000D03*
X-1400000Y-162500D03*
X-1387500D03*
X-1400000Y-150000D03*
X-1387300Y-133200D03*
X-1387500Y-137500D03*
Y-125000D03*
X-1400100Y-131550D03*
X-1400000Y-125000D03*
X-1395000Y-106250D03*
X-1400000Y-112500D03*
X-1387500D03*
X-1400500Y-96500D03*
Y-87000D03*
X-1391000Y-96500D03*
X-1393750Y-82500D03*
X-1400000Y-75000D03*
X-1387500D03*
Y-62500D03*
X-1400000D03*
X-1389892Y-40389D03*
Y-45389D03*
Y-50389D03*
X-1397392Y-40389D03*
Y-45389D03*
Y-50389D03*
X-1389892Y-35389D03*
X-1397392D03*
X-1394500Y-18000D03*
X-1395000Y-8000D03*
Y-500D03*
X-1395518Y14053D03*
X-1371250Y-112500D03*
X-1380000Y-106250D03*
X-1381250Y-82500D03*
X-1375000Y-75000D03*
Y-62500D03*
X-1373800Y-52900D03*
X-1382392Y-40389D03*
Y-45389D03*
Y-50389D03*
Y-35389D03*
X-1382500Y-8000D03*
Y-18000D03*
Y7000D03*
Y-500D03*
Y14500D03*
X-1363750Y-106250D03*
X-1356250Y-82500D03*
X-1368750D03*
X-1362500Y-75000D03*
Y-62500D03*
X-1356700Y-25600D03*
X-1357500Y-8000D03*
X-1370000D03*
Y-500D03*
X-1357500Y7000D03*
Y-500D03*
X-1370000Y7000D03*
Y14500D03*
X-1357500D03*
X-1350600Y-75000D03*
X-1343200Y-82700D03*
X-1350000Y-62500D03*
X-1345000Y-8000D03*
Y-500D03*
Y7000D03*
Y14500D03*
X-1330400Y-74900D03*
X-1324840Y-82120D03*
X-1335400Y-75000D03*
X-1337500Y-62500D03*
X-1324500Y-26959D03*
X-1332500Y-27500D03*
X-1335400Y-37600D03*
X-1332500Y7000D03*
Y-500D03*
Y14500D03*
X-1322228Y-88400D03*
X-1316728Y-89200D03*
X-1321000Y-94850D03*
X-1313040Y-80810D03*
X-1317700Y-72700D03*
X-1310559Y-74200D03*
X-1317700Y-60200D03*
X-1310559Y-68700D03*
Y-63200D03*
Y-57700D03*
X-1310600Y-46690D03*
X-1310559Y-41200D03*
Y-52200D03*
X-1311200Y-30200D03*
X-1310559Y-35700D03*
X-1320000Y-500D03*
Y7000D03*
X-1318500Y-6000D03*
X-1320000Y14500D03*
X-1306850Y-95000D03*
X-1300350Y-88500D03*
X-1293500Y-80000D03*
X-1302400Y-84100D03*
X-1297995Y-58405D03*
X-1298400Y-63200D03*
X-1298780Y-52200D03*
X-1298000Y-41200D03*
X-1298700Y-35700D03*
X-1298800Y-30200D03*
X-1295400Y-13400D03*
X-1307500Y7000D03*
X-1295000Y14500D03*
X-1307500D03*
X-1279429Y-180579D03*
X-1282500Y14500D03*
X-1269513Y-183637D03*
X-1266313D03*
X-1271813Y-181337D03*
X-1264267Y-181074D03*
X-1271813Y-185937D03*
X-1264013D03*
X-1276860Y-178030D03*
X-1263189Y-177998D03*
X-1272638D03*
X-1271088Y-151780D03*
X-1267888D03*
X-1274213Y-157350D03*
X-1264764D03*
X-1265588Y-154080D03*
X-1273388D03*
Y-149480D03*
X-1265588D03*
X-1261625Y-144435D03*
X-1263925Y-146735D03*
X-1264060Y-141950D03*
X-1270000Y14500D03*
X-1245710Y-189905D03*
Y-186705D03*
X-1248010Y-184405D03*
Y-192205D03*
X-1247979Y-177933D03*
X-1250591Y-179920D03*
X-1253740Y-177998D03*
X-1248860Y-150200D03*
X-1255315Y-157350D03*
X-1246390Y-153490D03*
X-1258425Y-144435D03*
X-1249016Y-144800D03*
X-1250660Y-140480D03*
X-1256125Y-146735D03*
Y-142135D03*
X-1257500Y-57500D03*
Y-45000D03*
Y-20000D03*
Y14500D03*
X-1232340Y-185380D03*
X-1235540D03*
X-1230040Y-183080D03*
Y-187680D03*
X-1237840Y-183080D03*
Y-187680D03*
X-1243410Y-184405D03*
Y-192205D03*
X-1237992Y-179850D03*
X-1234843Y-177998D03*
X-1241142Y-178998D03*
X-1244291Y-177998D03*
X-1236418Y-157350D03*
X-1236310Y-140390D03*
X-1230093Y-134350D03*
X-1233293D03*
X-1235593Y-136650D03*
Y-132050D03*
X-1245000Y-70000D03*
X-1232500Y-57500D03*
Y-45000D03*
X-1245000D03*
Y-20000D03*
X-1232500D03*
X-1245000Y14500D03*
X-1232500D03*
X-1215945Y-177998D03*
X-1225394D03*
X-1220590Y-149900D03*
X-1223790D03*
X-1217520Y-157350D03*
X-1226969D03*
X-1218290Y-152200D03*
X-1226090D03*
X-1218290Y-147600D03*
X-1226090D03*
X-1227793Y-136650D03*
Y-132050D03*
X-1220000Y14500D03*
X-1202580Y-176300D03*
X-1209420Y-167360D03*
X-1206220D03*
X-1211720Y-169660D03*
Y-165060D03*
X-1203920D03*
Y-169660D03*
X-1202100Y-103200D03*
X-1199500Y5400D03*
Y-3000D03*
X-1207500Y14500D03*
X-1191200Y-40500D03*
X-1191000Y-46500D03*
X-1191500Y-34000D03*
X-1191900Y-29500D03*
X-1190800Y-23450D03*
X-1191000Y-18250D03*
X-1191200Y-12128D03*
X-1192359Y-5800D03*
X-1191500Y0D03*
X-1195000Y14500D03*
X-1176100Y-114800D03*
X-1170300Y-114600D03*
X-1172500Y-44000D03*
X-1173200Y-49700D03*
X-1178900Y-46700D03*
X-1179000Y-40500D03*
X-1172500Y-38500D03*
X-1178950Y-23250D03*
X-1171800Y-26950D03*
X-1178800Y-34800D03*
X-1177800Y-12100D03*
X-1172000Y-10750D03*
X-1171500Y-21750D03*
X-1171800Y-16250D03*
X-1178800Y-5800D03*
X-1172100Y-5400D03*
X-1170000Y14500D03*
X-1182500D03*
X-1160000Y-115100D03*
X-1154200Y-103100D03*
X-1154400Y-107900D03*
X-1160000Y-38500D03*
X-1159700Y-43900D03*
X-1160150Y-26750D03*
X-1159800Y-33100D03*
X-1158700Y-16250D03*
X-1151500Y-15000D03*
X-1159700Y-5750D03*
X-1157500Y14500D03*
X-1137500Y-15000D03*
Y-2500D03*
X-1145000Y14500D03*
X-1124700Y-180000D03*
X-1124878Y-175150D03*
X-1124900Y-170650D03*
X-1134579Y-179850D03*
X-1123450Y-155183D03*
X-1120250D03*
X-1125750Y-152883D03*
Y-157483D03*
X-1126575Y-147990D03*
Y-136730D03*
X-1124800Y-129000D03*
X-1120400D03*
X-1125000Y-101700D03*
X-1121870Y-104330D03*
X-1128810Y-104171D03*
X-1126000Y-15000D03*
Y-2500D03*
X-1120000Y14500D03*
X-1132500D03*
X-1113328Y-182209D03*
X-1107828Y-182300D03*
X-1114979Y-170700D03*
X-1106979D03*
X-1117950Y-157483D03*
Y-152883D03*
X-1117126Y-136730D03*
X-1107677Y-148090D03*
Y-136730D03*
X-1117126Y-148090D03*
X-1108703Y-118455D03*
Y-121655D03*
X-1111003Y-123960D03*
X-1106403D03*
X-1114500Y-129000D03*
X-1110500D03*
X-1115490Y-104240D03*
X-1118701Y-101759D03*
X-1112402Y-101600D03*
X-1109300Y-104200D03*
X-1106102Y-102100D03*
X-1106403Y-116160D03*
X-1111003D03*
X-1107700Y-73400D03*
Y-63100D03*
X-1107800Y-68200D03*
X-1111500Y-15000D03*
Y-2500D03*
X-1107500Y14500D03*
X-1095600Y-179600D03*
X-1096278Y-170650D03*
X-1096200Y-175150D03*
X-1098228Y-148090D03*
Y-136730D03*
X-1102953Y-104200D03*
X-1099010Y-104183D03*
X-1099400Y-90200D03*
X-1093400D03*
X-1100000Y-15000D03*
Y-2500D03*
X-1095000Y14500D03*
X-1084600Y-179850D03*
X-1073000Y-90300D03*
X-1082500Y14500D03*
X-1056900Y-56300D03*
X-1063600Y-56600D03*
X-1062000Y-29200D03*
X-1061900Y-5200D03*
X-1070000Y14500D03*
X-1045100Y-52900D03*
X-1044300Y-47661D03*
X-1051200Y-44100D03*
X-1054900Y-29800D03*
X-1045400Y-38000D03*
X-1051400Y-26000D03*
X-1047289Y-26300D03*
X-1041300Y-10100D03*
Y-16500D03*
X-1054600Y-5100D03*
X-1050811Y2600D03*
X-1047300Y-2700D03*
X-1045000Y14500D03*
X-1033843Y-128576D03*
X-1032500Y14500D03*
X-1017670Y-123250D03*
X-1022140Y-122960D03*
X-1015729Y-100550D03*
X-1012638Y-85886D03*
X-1015179Y-74100D03*
X-1012638Y-70873D03*
Y-56060D03*
X-1012860Y-41250D03*
X-1012500Y-7500D03*
X-1020000Y14500D03*
X-1003380Y-86986D03*
X-1008429Y-91400D03*
X-999960Y-90706D03*
X-996670Y-75460D03*
X-1008719Y-75998D03*
X-999860Y-75848D03*
Y-60885D03*
X-1003780Y-56060D03*
X-994280Y-40890D03*
X-997500Y-7500D03*
X-1007500Y14500D03*
X-995000D03*
X-983000Y-7500D03*
X-982500Y14500D03*
X-969331Y-100849D03*
Y-85886D03*
X-965512Y-90706D03*
X-971779Y-73800D03*
X-965412Y-75848D03*
Y-45922D03*
X-970000Y-7500D03*
Y14500D03*
X-956653Y-90706D03*
X-960273Y-101049D03*
X-953250Y-75340D03*
X-956553Y-75848D03*
X-957779Y-57700D03*
X-956553Y-60885D03*
Y-45922D03*
X-957500Y-7500D03*
Y14500D03*
X-932500Y-7500D03*
X-945000D03*
X-932500Y14500D03*
X-945000D03*
X-922500Y-170000D03*
Y-159500D03*
Y-120000D03*
Y-132500D03*
Y-107500D03*
Y-95000D03*
Y-70000D03*
Y-82500D03*
Y-57500D03*
Y-45000D03*
Y-20000D03*
Y-7500D03*
Y5000D03*
X-922000Y14500D03*
X-910000Y-170000D03*
Y-159500D03*
Y-132500D03*
Y-107500D03*
Y-95000D03*
Y-82500D03*
Y-70000D03*
Y-57500D03*
Y-45000D03*
Y-7500D03*
Y-20000D03*
Y5000D03*
X-909500Y14500D03*
X-897500Y-170000D03*
X-885000D03*
Y-159500D03*
X-897500D03*
X-885000Y-132500D03*
X-897500D03*
X-885000Y-107500D03*
X-897500D03*
Y-95000D03*
X-885000D03*
Y-82500D03*
X-897500Y-70000D03*
Y-82500D03*
X-885000Y-70000D03*
Y-57500D03*
X-897500D03*
Y-45000D03*
X-885000D03*
Y-7500D03*
X-897500Y-20000D03*
X-885000D03*
X-897500Y-7500D03*
Y5000D03*
X-885000D03*
Y14500D03*
X-897500D03*
X-872500Y-170000D03*
Y-159500D03*
Y-132500D03*
Y-107500D03*
Y-95000D03*
Y-70000D03*
Y-82500D03*
Y-57500D03*
Y-45000D03*
Y-20000D03*
Y-7500D03*
Y5000D03*
Y14500D03*
X-860000Y-170000D03*
Y-159500D03*
Y-132500D03*
Y-107500D03*
Y-95000D03*
Y-82500D03*
Y-70000D03*
Y-57500D03*
Y-45000D03*
Y-7500D03*
Y-20000D03*
Y5000D03*
Y14500D03*
X-847500Y-170000D03*
Y-159500D03*
Y-132500D03*
Y-107500D03*
Y-95000D03*
Y-70000D03*
Y-82500D03*
Y-57500D03*
Y-45000D03*
Y-20000D03*
Y-7500D03*
Y5000D03*
X-848000Y14500D03*
X-822500Y-170000D03*
X-835000Y-159500D03*
X-822500D03*
Y-145000D03*
X-835000Y-132500D03*
X-822500Y-120000D03*
Y-132500D03*
X-835000Y-120000D03*
Y-107500D03*
X-822500D03*
Y-95000D03*
X-835000D03*
Y-82500D03*
X-822500Y-70000D03*
Y-82500D03*
X-835000Y-70000D03*
Y-57500D03*
X-822500D03*
Y-45000D03*
X-835000D03*
X-822500Y-20000D03*
Y-7500D03*
X-835000Y-20000D03*
X-822500Y5000D03*
X-835500Y14500D03*
X-822500D03*
X-810000Y-170000D03*
Y-157500D03*
Y-145000D03*
Y-132500D03*
Y-120000D03*
Y-70000D03*
Y-57500D03*
Y-45000D03*
Y-7500D03*
Y-20000D03*
Y5000D03*
Y14500D03*
X-797500Y-120000D03*
Y-70000D03*
Y-57500D03*
Y-45000D03*
Y-20000D03*
Y-7500D03*
Y5000D03*
Y14500D03*
X-785500Y-120000D03*
X-785000Y-70000D03*
Y-57500D03*
Y-45000D03*
Y-7500D03*
Y-20000D03*
Y5000D03*
Y14500D03*
X-772500Y-170000D03*
Y-145000D03*
X-760000D03*
Y-132500D03*
X-772500Y-120000D03*
Y-132500D03*
X-760000Y-120000D03*
Y-107500D03*
X-772500D03*
Y-95000D03*
X-760000D03*
Y-82500D03*
X-772500Y-70000D03*
Y-82500D03*
X-760000Y-70000D03*
Y-57500D03*
X-772500D03*
Y-45000D03*
X-760000D03*
Y-7500D03*
X-772500Y-20000D03*
X-760000D03*
X-772500Y-7500D03*
Y5000D03*
X-760000D03*
Y14500D03*
X-772500D03*
X-747500Y-57500D03*
Y-45000D03*
Y-20000D03*
Y-7500D03*
Y5000D03*
Y14500D03*
X-735000Y-57500D03*
Y-45000D03*
Y-7500D03*
Y-20000D03*
Y5000D03*
Y14500D03*
X-722500Y-57500D03*
Y-45000D03*
Y-20000D03*
Y-7500D03*
Y5000D03*
Y14500D03*
X-697500Y-45000D03*
X-710000D03*
X-697500Y-20000D03*
X-710000Y-7500D03*
X-697500D03*
X-710000Y-20000D03*
X-697500Y5000D03*
X-710000D03*
Y14500D03*
X-697500D03*
X-685000Y-45000D03*
Y-7500D03*
Y-20000D03*
Y5000D03*
Y14500D03*
X-672500Y-45000D03*
Y-20000D03*
Y-7500D03*
Y5000D03*
Y14500D03*
X-649700Y-117200D03*
X-655500Y-37500D03*
Y-25500D03*
Y-12500D03*
Y-500D03*
X-660000Y14500D03*
X-643700Y-125400D03*
X-642500Y-25500D03*
Y-37500D03*
Y-12500D03*
X-632500Y14500D03*
X-645000D03*
X-626964Y-169390D03*
Y-164390D03*
X-616614Y-166890D03*
X-621614Y-156890D03*
X-621573Y-151849D03*
X-616614Y-161890D03*
X-627200Y-151300D03*
X-616614Y-151890D03*
Y-156890D03*
X-621614Y-136890D03*
X-616614Y-146890D03*
Y-141890D03*
X-626900Y-141300D03*
X-616614Y-136890D03*
X-621614Y-131890D03*
X-616614Y-126890D03*
Y-121890D03*
X-621614D03*
X-628700Y-130100D03*
X-616614Y-131890D03*
X-621614Y-116890D03*
Y-111890D03*
X-626964Y-104390D03*
Y-109390D03*
X-616614Y-106890D03*
Y-101890D03*
Y-111890D03*
Y-116890D03*
X-621614Y-96890D03*
Y-91890D03*
X-626964Y-89390D03*
X-616614Y-86890D03*
Y-91890D03*
Y-96890D03*
Y-76890D03*
X-621614D03*
X-616614Y-81890D03*
X-626625Y-81614D03*
X-626614Y-76890D03*
Y-71890D03*
X-621614D03*
X-616614D03*
X-616000Y-37500D03*
X-630000Y-25500D03*
Y-37500D03*
X-616000Y-25500D03*
X-630000Y-12500D03*
X-616000D03*
Y14500D03*
X-606614Y-166890D03*
X-601614D03*
X-611614D03*
X-601614Y-156890D03*
Y-151890D03*
X-611614D03*
Y-156890D03*
X-606614Y-161890D03*
Y-151890D03*
X-601614Y-161890D03*
X-606614Y-156890D03*
X-611614Y-161890D03*
X-606614Y-146890D03*
Y-141890D03*
X-601614Y-136890D03*
X-611614D03*
X-601614Y-141890D03*
X-606614Y-136890D03*
X-601614Y-146890D03*
X-611614Y-141890D03*
Y-146890D03*
X-601614Y-131890D03*
X-606614Y-126890D03*
Y-121890D03*
X-611614Y-131890D03*
X-601614Y-121890D03*
X-606614Y-131890D03*
X-601614Y-126890D03*
X-611614Y-121890D03*
Y-126890D03*
X-601614Y-116890D03*
Y-111890D03*
X-606614Y-106890D03*
Y-101890D03*
X-611614Y-116890D03*
Y-111890D03*
X-601614Y-101890D03*
X-606614Y-111890D03*
X-601614Y-106890D03*
X-606614Y-116890D03*
X-611614Y-101890D03*
Y-106890D03*
Y-86890D03*
X-601614D03*
Y-96890D03*
Y-91890D03*
X-606614Y-86890D03*
X-611614Y-96890D03*
Y-91890D03*
X-606614D03*
Y-96890D03*
X-611614Y-81890D03*
X-601614D03*
X-606614D03*
Y-71890D03*
X-611614D03*
X-601614D03*
X-606614Y-76890D03*
X-611614D03*
X-601614D03*
X-602500Y-37500D03*
Y-25000D03*
Y-12500D03*
Y0D03*
Y12500D03*
X-596614Y-166890D03*
X-591614D03*
X-591200Y-179700D03*
X-591614Y-156890D03*
Y-151890D03*
X-596614Y-161890D03*
Y-151890D03*
X-591614Y-161890D03*
X-596614Y-156890D03*
X-591614Y-136890D03*
X-596614Y-146890D03*
Y-141890D03*
X-591614D03*
X-596614Y-136890D03*
X-591614Y-146890D03*
Y-131890D03*
X-596614Y-126890D03*
Y-121890D03*
X-591614D03*
X-596614Y-131890D03*
X-591614Y-126890D03*
Y-116890D03*
Y-111890D03*
X-596614Y-106890D03*
Y-101890D03*
Y-111890D03*
X-591614Y-101890D03*
X-596614Y-116890D03*
X-591614Y-106890D03*
Y-86890D03*
Y-96890D03*
Y-91890D03*
X-596614Y-86890D03*
Y-91890D03*
Y-96890D03*
X-591614Y-81890D03*
Y-71890D03*
X-596614Y-76890D03*
Y-81890D03*
X-591614Y-76890D03*
X-596614Y-71890D03*
X-590000Y-25000D03*
Y-37500D03*
Y-12500D03*
Y0D03*
Y12500D03*
X-577500Y-177500D03*
Y-165000D03*
Y-152500D03*
Y-140000D03*
Y-127500D03*
Y-115000D03*
Y-65000D03*
Y-37500D03*
Y-25000D03*
Y-12500D03*
Y0D03*
Y12500D03*
X-565000Y-165000D03*
Y-177500D03*
Y-152500D03*
Y-140000D03*
Y-65000D03*
Y-25000D03*
Y-37500D03*
Y-12500D03*
Y0D03*
Y12500D03*
X-540000Y-165000D03*
X-552500Y-177500D03*
X-540000D03*
X-552500Y-165000D03*
Y-152500D03*
X-540000D03*
Y-140000D03*
X-552500D03*
X-540000Y-127500D03*
Y-115000D03*
Y-102500D03*
Y-90000D03*
Y-77500D03*
Y-65000D03*
X-552500D03*
X-540000Y-25000D03*
X-552500Y-37500D03*
Y-25000D03*
X-540000Y-37500D03*
X-552500Y-12500D03*
X-540000D03*
Y0D03*
X-552500D03*
Y12500D03*
X-540000D03*
X-527500Y-177500D03*
Y-165000D03*
Y-152500D03*
Y-140000D03*
Y-127500D03*
Y-102500D03*
Y-115000D03*
Y-90000D03*
Y-77500D03*
Y-65000D03*
Y-37500D03*
Y-25000D03*
Y-12500D03*
Y0D03*
Y12500D03*
X-515000Y-165000D03*
Y-177500D03*
Y-152500D03*
Y-140000D03*
Y-127500D03*
Y-115000D03*
Y-102500D03*
Y-90000D03*
Y-77500D03*
Y-65000D03*
Y-25000D03*
Y-37500D03*
Y-12500D03*
Y0D03*
Y12500D03*
X-502500Y-102500D03*
X-490000D03*
Y-90000D03*
X-502500D03*
Y-77500D03*
X-490000D03*
X-502500Y-65000D03*
Y-37500D03*
X-490000D03*
X-502500Y-25000D03*
Y-12500D03*
X-490000D03*
Y0D03*
X-502500D03*
Y12500D03*
X-490000D03*
X-486421Y-26159D03*
X-477500Y-37500D03*
Y-25000D03*
Y0D03*
Y12500D03*
X-462000Y-73500D03*
X-465000Y-25000D03*
Y-37500D03*
X-461441Y6559D03*
X-465000Y12500D03*
X-453628Y-88300D03*
X-448128Y-88800D03*
X-456240Y-82020D03*
X-444440Y-80710D03*
X-452700Y-69000D03*
X-449100Y-60841D03*
X-442800Y-46600D03*
X-454421Y-26959D03*
X-443941Y6559D03*
X-449000Y6500D03*
X-448600Y-5900D03*
X-452500Y12500D03*
X-432118Y-87082D03*
X-436771Y-92400D03*
X-441959Y-74100D03*
X-429900Y-79600D03*
X-441959Y-68600D03*
X-429000Y-57600D03*
X-430700Y-63100D03*
X-441959D03*
Y-57600D03*
X-430180Y-52100D03*
X-429400Y-41100D03*
X-441959D03*
Y-52100D03*
X-430400Y-35600D03*
X-442000Y-29480D03*
X-441959Y-35600D03*
X-431000Y6500D03*
X-427500Y12500D03*
X-440000D03*
X-424500Y-26500D03*
X-424600Y-14400D03*
X-413500Y12500D03*
X-405540Y-183080D03*
X-399435Y-183637D03*
X-396235D03*
X-401735Y-181337D03*
Y-185937D03*
X-405540Y-179630D03*
X-402559Y-177998D03*
X-401009Y-151780D03*
X-397809D03*
X-403309Y-149480D03*
Y-154080D03*
X-395509Y-149480D03*
Y-154080D03*
X-404134Y-157350D03*
X-402500Y12500D03*
X-379521Y-181100D03*
X-394188Y-181074D03*
X-393935Y-185937D03*
X-383661Y-177998D03*
X-393110D03*
X-385237Y-157350D03*
X-394685D03*
X-380421Y-147000D03*
X-391547Y-144435D03*
X-388347D03*
X-393847Y-146735D03*
X-393981Y-141950D03*
X-386047Y-142135D03*
Y-146735D03*
X-389600Y-123640D03*
X-389770Y-127220D03*
X-386500Y-56500D03*
Y-44000D03*
Y-31500D03*
Y-19000D03*
Y-5500D03*
X-390000Y12500D03*
X-375631Y-189905D03*
Y-186705D03*
X-365461Y-185380D03*
X-367761Y-183080D03*
Y-187680D03*
X-377931Y-184405D03*
Y-192205D03*
X-373331D03*
Y-184405D03*
X-377900Y-177933D03*
X-367913Y-179850D03*
X-364764Y-177998D03*
X-371063Y-178998D03*
X-374213Y-177998D03*
X-366339Y-157350D03*
X-375800Y-154000D03*
X-365514Y-136650D03*
X-373620Y-124430D03*
X-365514Y-132050D03*
X-374800Y-105700D03*
X-374000Y-56500D03*
Y-44000D03*
Y-31500D03*
Y-19000D03*
X-365000Y12500D03*
X-377500D03*
X-362261Y-185380D03*
X-359961Y-183080D03*
Y-187680D03*
X-355315Y-177998D03*
X-350511Y-149900D03*
X-353711D03*
X-347441Y-157350D03*
X-356011Y-152200D03*
X-348211D03*
X-356890Y-157350D03*
X-360014Y-134350D03*
X-363214D03*
X-357714Y-136650D03*
X-356011Y-147600D03*
X-348211D03*
X-357714Y-132050D03*
X-360500Y-87100D03*
X-353700Y-87600D03*
X-361500Y-56500D03*
X-348000Y-57000D03*
X-361500Y-44000D03*
X-348000D03*
Y-31500D03*
X-361500D03*
Y-19000D03*
X-348000D03*
X-352500Y12500D03*
X-333450Y-174950D03*
X-339341Y-167360D03*
X-336141D03*
X-341641Y-169660D03*
Y-165060D03*
X-333841D03*
Y-169660D03*
X-345866Y-177998D03*
X-347850Y-87050D03*
X-342400Y-87500D03*
X-336000Y-53000D03*
Y-28000D03*
Y-15500D03*
X-340000Y12500D03*
X-321600Y-113500D03*
X-316500D03*
X-323500Y-65500D03*
X-321700Y-42000D03*
X-321500Y-47500D03*
X-322400Y-31000D03*
X-321300Y-24950D03*
X-321800Y-7300D03*
X-321700Y-13628D03*
X-321859Y-1500D03*
X-327500Y12500D03*
X-312100Y-113500D03*
X-303200Y-43300D03*
Y-48800D03*
X-309400Y-47700D03*
X-302300Y-25950D03*
X-302900Y-37900D03*
X-309400Y-25100D03*
X-308500Y-36400D03*
X-308800Y-7400D03*
X-302500Y-15200D03*
X-307900Y-13628D03*
X-302300Y-4450D03*
X-315000Y12500D03*
X-302500D03*
X-285000Y-107400D03*
Y-103100D03*
X-286500Y-113700D03*
X-296400Y-113500D03*
X-290400Y-43200D03*
X-289500Y-32500D03*
X-290800Y-26000D03*
X-290700Y-9750D03*
X-290300Y-4400D03*
X-290000Y12500D03*
X-274400Y-178200D03*
X-278100D03*
X-282300Y-113700D03*
X-277500Y12500D03*
X-254800Y-180000D03*
Y-170650D03*
X-254800Y-175150D03*
X-265200Y-179850D03*
X-255672Y-157483D03*
Y-152883D03*
X-256496Y-147990D03*
Y-136730D03*
X-254721Y-129000D03*
X-254921Y-101700D03*
X-258732Y-104171D03*
X-255500Y-25500D03*
X-268000Y-13000D03*
X-255500D03*
Y-500D03*
X-268000D03*
X-265000Y12500D03*
X-237750Y-182300D03*
X-243250Y-182209D03*
X-244900Y-170700D03*
X-253372Y-155183D03*
X-250172D03*
X-247872Y-152883D03*
Y-157483D03*
X-247047Y-148090D03*
Y-136730D03*
X-238624Y-118455D03*
Y-121655D03*
X-240924Y-123960D03*
X-250321Y-129000D03*
X-244300Y-129300D03*
X-240300D03*
X-245411Y-104240D03*
X-248622Y-101759D03*
X-251792Y-104330D03*
X-242323Y-101600D03*
X-239222Y-104200D03*
X-240924Y-116160D03*
X-243000Y-40500D03*
Y-25500D03*
Y-13000D03*
Y-500D03*
X-240000Y12500D03*
X-252500D03*
X-225400Y-179800D03*
X-226200Y-170650D03*
X-226121Y-175150D03*
X-236900Y-170700D03*
X-237598Y-136730D03*
X-228150D03*
Y-148090D03*
X-237598D03*
X-236324Y-123960D03*
X-236024Y-102100D03*
X-232874Y-104200D03*
X-236324Y-116160D03*
X-228932Y-104183D03*
X-230000Y-13500D03*
X-230500Y-500D03*
X-227500Y12500D03*
X-214500Y-179800D03*
X-215000Y12500D03*
X-196900Y-176500D03*
X-201600Y-176600D03*
X-206100D03*
X-191000Y-56400D03*
X-190300Y-28900D03*
Y-4200D03*
X-202500Y12500D03*
X-185900Y-56200D03*
X-179800Y-43500D03*
X-182900Y-29800D03*
X-176350Y-27200D03*
X-179811Y-21300D03*
X-183200Y-4600D03*
X-179011Y4500D03*
X-175100Y-1800D03*
X-177500Y12500D03*
X-190390Y12740D03*
X-163764Y-128576D03*
X-173800Y-47300D03*
X-173200Y-52400D03*
X-170200Y-34470D03*
X-170500Y-10000D03*
X-170300Y-16500D03*
X-165000Y12500D03*
X-150900Y-121100D03*
X-152400Y-125050D03*
X-145650Y-100550D03*
X-145100Y-74100D03*
X-152500Y12500D03*
X-138440Y-91390D03*
X-133301Y-86986D03*
X-142559Y-85886D03*
X-129882Y-90706D03*
X-129782Y-75998D03*
X-138640D03*
X-142559Y-70873D03*
X-133701Y-56060D03*
X-129782Y-60885D03*
X-142559Y-56060D03*
X-142130Y-41290D03*
X-139000Y-8500D03*
Y-21000D03*
X-140000Y12500D03*
X-127500D03*
X-126600Y-75410D03*
X-124590Y-41500D03*
X-114000Y-33500D03*
X-126500Y-21000D03*
X-114000Y-8500D03*
Y-21000D03*
X-126500Y-8500D03*
X-115000Y12500D03*
X-99252Y-100849D03*
Y-85886D03*
X-101700Y-73800D03*
X-101500Y-33500D03*
Y-21000D03*
Y-8500D03*
X-102500Y12500D03*
X-95433Y-90706D03*
X-86575D03*
X-90194Y-101049D03*
X-83310Y-75360D03*
X-95333Y-75848D03*
X-86475D03*
Y-60885D03*
X-87700Y-57700D03*
X-95333Y-45922D03*
X-86475D03*
X-89000Y-8500D03*
Y-21000D03*
X-90000Y12500D03*
X-74921Y-171500D03*
X-71500Y-158500D03*
Y-146000D03*
Y-133500D03*
X-71700Y-121000D03*
X-70500Y-108600D03*
X-76500Y-33500D03*
Y-21000D03*
Y-8500D03*
X-77500Y12500D03*
X-65000D03*
X-59500Y-173500D03*
Y-161000D03*
Y-136000D03*
Y-148500D03*
Y-123500D03*
Y-108500D03*
Y-96000D03*
Y-83500D03*
Y-71000D03*
Y-58500D03*
Y-46000D03*
Y-33500D03*
Y-8500D03*
Y-21000D03*
X-54500Y1500D03*
X-52500Y12500D03*
X-42500Y-173500D03*
X-43000Y-158500D03*
Y-146000D03*
X-47000Y-71000D03*
X-34500Y-83500D03*
Y-71000D03*
X-47000Y-83500D03*
X-34500Y-58500D03*
X-47000D03*
Y-46000D03*
X-34500D03*
Y-33500D03*
X-47000D03*
Y-21000D03*
X-34500Y-8500D03*
X-47000D03*
X-34500Y-21000D03*
X-42000Y1500D03*
X-40000Y12500D03*
X-18000Y-173500D03*
Y-158500D03*
X-30500D03*
Y-146000D03*
X-18000D03*
X-21150Y-83600D03*
X-22000Y-71000D03*
Y-58500D03*
Y-46000D03*
Y-33500D03*
Y-21000D03*
Y-8500D03*
X-27500Y12500D03*
X-9500Y-120000D03*
Y-108500D03*
Y-96000D03*
X-9350Y-83500D03*
X-9500Y-71000D03*
Y-58500D03*
Y-46000D03*
Y-33500D03*
Y-8500D03*
Y-21000D03*
X-17000Y1500D03*
X-2500Y12500D03*
X-15000D03*
X3000Y-120000D03*
Y-108500D03*
Y-96000D03*
Y-83500D03*
Y-71000D03*
Y-58500D03*
Y-46000D03*
Y-33500D03*
Y-21000D03*
Y-8500D03*
G54D39*
G01X-1778792Y74690D02*
X-1778828Y81690D01*
X-1781886Y76658D01*
X-1777719Y76679D01*
G01X-1774831Y75760D02*
X-1774328Y75180D01*
X-1773743Y74833D01*
X-1772992Y74720D01*
X-1772243Y74957D01*
X-1771662Y75427D01*
X-1771250Y76246D01*
X-1771171Y77179D01*
X-1771343Y78112D01*
X-1771763Y78693D01*
X-1772348Y79157D01*
X-1772932Y79270D01*
X-1773515Y79151D01*
X-1774263Y78680D01*
X-1774028Y81715D01*
X-1771778Y81726D01*
G01X-1761142Y74781D02*
X-1757678Y81799D01*
G01X-1761178Y81781D02*
X-1757642Y74799D01*
G01X-1752629Y81825D02*
X-1753294Y81588D01*
X-1753791Y81002D01*
X-1754121Y80301D01*
X-1754366Y79366D01*
X-1754444Y78315D01*
X-1754355Y77266D01*
X-1754100Y76334D01*
X-1753763Y75636D01*
X-1753260Y75055D01*
X-1752592Y74825D01*
X-1751927Y75062D01*
X-1751430Y75648D01*
X-1751100Y76349D01*
X-1750855Y77284D01*
X-1750777Y78334D01*
X-1750866Y79384D01*
X-1751121Y80316D01*
X-1751458Y81014D01*
X-1751961Y81595D01*
X-1752629Y81825D01*
G01X-1745791Y74627D02*
X-1745959Y74743D01*
X-1745960Y74976D01*
X-1745794Y75093D01*
X-1745626Y74978D01*
X-1745625Y74744D01*
X-1745791Y74627D01*
G01X-1739029Y81895D02*
X-1739694Y81658D01*
X-1740191Y81072D01*
X-1740521Y80371D01*
X-1740766Y79436D01*
X-1740844Y78385D01*
X-1740755Y77336D01*
X-1740500Y76404D01*
X-1740163Y75706D01*
X-1739661Y75125D01*
X-1738993Y74895D01*
X-1738327Y75132D01*
X-1737830Y75718D01*
X-1737500Y76419D01*
X-1737255Y77354D01*
X-1737177Y78404D01*
X-1737266Y79454D01*
X-1737521Y80386D01*
X-1737858Y81084D01*
X-1738361Y81665D01*
X-1739029Y81895D01*
G01X-1734033Y76321D02*
X-1733529Y75506D01*
X-1732860Y75043D01*
X-1732109Y74931D01*
X-1731443Y75051D01*
X-1730780Y75637D01*
X-1730367Y76339D01*
X-1730287Y77040D01*
X-1730458Y77856D01*
X-1731044Y78436D01*
X-1731629Y78666D01*
X-1732379Y78663D01*
G01X-1731629Y78666D02*
X-1731130Y79019D01*
X-1730717Y79604D01*
X-1730554Y80305D01*
X-1730724Y81004D01*
X-1731144Y81585D01*
X-1731895Y81932D01*
X-1732645Y81811D01*
X-1733392Y81341D01*
G01X-1726814Y75774D02*
X-1726227Y75194D01*
X-1725559Y74964D01*
X-1724894Y75201D01*
X-1724314Y75904D01*
X-1723903Y76956D01*
X-1723742Y78007D01*
X-1723748Y79290D01*
X-1723920Y80339D01*
X-1724342Y81271D01*
X-1724844Y81735D01*
X-1725429Y81965D01*
X-1726094Y81728D01*
X-1726592Y81259D01*
X-1726922Y80557D01*
X-1727083Y79623D01*
X-1726913Y78807D01*
X-1726492Y77993D01*
X-1725989Y77529D01*
X-1725405Y77415D01*
X-1724740Y77652D01*
X-1724243Y78238D01*
X-1723748Y79290D01*
G01X-1785167Y114000D02*
Y121000D01*
X-1783083D01*
X-1782417Y120650D01*
X-1782000Y120183D01*
X-1781833Y119250D01*
X-1782000Y118317D01*
X-1782500Y117733D01*
X-1783083Y117383D01*
X-1785167D01*
G01X-1783083D02*
X-1781833Y114000D01*
G01X-1776700Y121000D02*
X-1777367Y120767D01*
X-1777867Y120183D01*
X-1778200Y119483D01*
X-1778450Y118550D01*
X-1778533Y117500D01*
X-1778450Y116450D01*
X-1778200Y115517D01*
X-1777867Y114816D01*
X-1777367Y114233D01*
X-1776700Y114000D01*
X-1776033Y114233D01*
X-1775533Y114816D01*
X-1775200Y115517D01*
X-1774950Y116450D01*
X-1774867Y117500D01*
X-1774950Y118550D01*
X-1775200Y119483D01*
X-1775533Y120183D01*
X-1776033Y120767D01*
X-1776700Y121000D01*
G01X-1769900Y113767D02*
X-1770067Y113883D01*
Y114117D01*
X-1769900Y114233D01*
X-1769733Y114117D01*
Y113883D01*
X-1769900Y113767D01*
G01X-1763100Y121000D02*
X-1763767Y120767D01*
X-1764267Y120183D01*
X-1764600Y119483D01*
X-1764850Y118550D01*
X-1764933Y117500D01*
X-1764850Y116450D01*
X-1764600Y115517D01*
X-1764267Y114816D01*
X-1763767Y114233D01*
X-1763100Y114000D01*
X-1762433Y114233D01*
X-1761933Y114816D01*
X-1761600Y115517D01*
X-1761350Y116450D01*
X-1761267Y117500D01*
X-1761350Y118550D01*
X-1761600Y119483D01*
X-1761933Y120183D01*
X-1762433Y120767D01*
X-1763100Y121000D01*
G01X-1756300Y114000D02*
Y121000D01*
X-1757300Y119600D01*
G01Y114000D02*
X-1755300D01*
G01X-1748500D02*
Y121000D01*
X-1751583Y115983D01*
X-1747417D01*
G01X-1779267Y46755D02*
X-1780106Y47917D01*
X-1780529Y49081D01*
X-1780553Y53748D01*
X-1780142Y54917D01*
X-1779315Y56088D01*
G01X-1771062Y49130D02*
X-1771098Y56130D01*
X-1774156Y51097D01*
X-1769989Y51119D01*
G01X-1766536Y53820D02*
X-1764012Y49166D01*
G01X-1764036Y53833D02*
X-1766512Y49153D01*
G01X-1758034Y46864D02*
X-1757206Y48035D01*
X-1756796Y49203D01*
X-1756820Y53870D01*
X-1757242Y55035D01*
X-1758082Y56197D01*
G01X-1775145Y60709D02*
X-1775181Y67709D01*
X-1778239Y62676D01*
X-1774072Y62698D01*
G01X-1771184Y61779D02*
X-1770681Y61198D01*
X-1770096Y60851D01*
X-1769345Y60739D01*
X-1768596Y60976D01*
X-1768015Y61445D01*
X-1767603Y62264D01*
X-1767524Y63198D01*
X-1767696Y64130D01*
X-1768116Y64712D01*
X-1768701Y65175D01*
X-1769285Y65289D01*
X-1769868Y65169D01*
X-1770615Y64699D01*
X-1770381Y67733D01*
X-1768131Y67745D01*
G01X-1757495Y60800D02*
X-1754031Y67818D01*
G01X-1757531Y67800D02*
X-1753995Y60818D01*
G01X-1748945Y60844D02*
X-1748982Y67844D01*
X-1749974Y66439D01*
G01X-1749945Y60838D02*
X-1747946Y60849D01*
G01X-1742144Y60645D02*
X-1742312Y60761D01*
X-1742313Y60994D01*
X-1742147Y61112D01*
X-1741979Y60996D01*
X-1741978Y60763D01*
X-1742144Y60645D01*
G01X-1735382Y67914D02*
X-1736047Y67677D01*
X-1736544Y67091D01*
X-1736874Y66389D01*
X-1737119Y65454D01*
X-1737197Y64404D01*
X-1737108Y63355D01*
X-1736853Y62422D01*
X-1736516Y61724D01*
X-1736014Y61144D01*
X-1735346Y60914D01*
X-1734680Y61150D01*
X-1734183Y61736D01*
X-1733853Y62438D01*
X-1733608Y63373D01*
X-1733530Y64423D01*
X-1733619Y65472D01*
X-1733874Y66405D01*
X-1734211Y67103D01*
X-1734714Y67684D01*
X-1735382Y67914D01*
G01X-1728582Y67949D02*
X-1729247Y67712D01*
X-1729744Y67126D01*
X-1730074Y66424D01*
X-1730319Y65489D01*
X-1730397Y64439D01*
X-1730308Y63390D01*
X-1730054Y62457D01*
X-1729716Y61759D01*
X-1729214Y61179D01*
X-1728546Y60949D01*
X-1727880Y61185D01*
X-1727383Y61771D01*
X-1727053Y62473D01*
X-1726808Y63408D01*
X-1726730Y64458D01*
X-1726819Y65508D01*
X-1727074Y66440D01*
X-1727411Y67138D01*
X-1727914Y67719D01*
X-1728582Y67949D01*
G01X-1776525Y107000D02*
X-1777192Y106767D01*
X-1777692Y106183D01*
X-1778025Y105483D01*
X-1778275Y104550D01*
X-1778358Y103500D01*
X-1778275Y102450D01*
X-1778025Y101517D01*
X-1777692Y100816D01*
X-1777192Y100233D01*
X-1776525Y100000D01*
X-1775858Y100233D01*
X-1775358Y100816D01*
X-1775025Y101517D01*
X-1774775Y102450D01*
X-1774692Y103500D01*
X-1774775Y104550D01*
X-1775025Y105483D01*
X-1775358Y106183D01*
X-1775858Y106767D01*
X-1776525Y107000D01*
G01X-1769725Y99767D02*
X-1769892Y99883D01*
Y100117D01*
X-1769725Y100233D01*
X-1769558Y100117D01*
Y99883D01*
X-1769725Y99767D01*
G01X-1764758Y101400D02*
X-1764258Y100583D01*
X-1763592Y100117D01*
X-1762842Y100000D01*
X-1762175Y100117D01*
X-1761508Y100700D01*
X-1761092Y101400D01*
X-1761008Y102100D01*
X-1761175Y102916D01*
X-1761758Y103500D01*
X-1762342Y103733D01*
X-1763092D01*
G01X-1762342D02*
X-1761842Y104083D01*
X-1761425Y104667D01*
X-1761258Y105367D01*
X-1761425Y106067D01*
X-1761842Y106650D01*
X-1762592Y107000D01*
X-1763342Y106883D01*
X-1764092Y106417D01*
G01X-1757958Y101050D02*
X-1757458Y100467D01*
X-1756875Y100117D01*
X-1756125Y100000D01*
X-1755375Y100233D01*
X-1754792Y100700D01*
X-1754375Y101517D01*
X-1754292Y102450D01*
X-1754458Y103383D01*
X-1754875Y103967D01*
X-1755458Y104433D01*
X-1756042Y104550D01*
X-1756625Y104433D01*
X-1757375Y103967D01*
X-1757125Y107000D01*
X-1754875D01*
G01X-1745333Y-167200D02*
X-1744833Y-168017D01*
X-1744167Y-168483D01*
X-1743417Y-168600D01*
X-1742750Y-168483D01*
X-1742083Y-167900D01*
X-1741667Y-167200D01*
X-1741583Y-166500D01*
X-1741750Y-165684D01*
X-1742333Y-165100D01*
X-1742917Y-164867D01*
X-1743667D01*
G01X-1742917D02*
X-1742417Y-164517D01*
X-1742000Y-163933D01*
X-1741833Y-163233D01*
X-1742000Y-162533D01*
X-1742417Y-161950D01*
X-1743167Y-161600D01*
X-1743917Y-161717D01*
X-1744667Y-162183D01*
G01X-1736700Y-168600D02*
Y-161600D01*
X-1737700Y-163000D01*
G01Y-168600D02*
X-1735700D01*
G01X-1729900Y-168833D02*
X-1730067Y-168717D01*
Y-168483D01*
X-1729900Y-168367D01*
X-1729733Y-168483D01*
Y-168717D01*
X-1729900Y-168833D01*
G01X-1723100Y-161600D02*
X-1723767Y-161833D01*
X-1724267Y-162417D01*
X-1724600Y-163117D01*
X-1724850Y-164050D01*
X-1724933Y-165100D01*
X-1724850Y-166150D01*
X-1724600Y-167083D01*
X-1724267Y-167784D01*
X-1723767Y-168367D01*
X-1723100Y-168600D01*
X-1722433Y-168367D01*
X-1721933Y-167784D01*
X-1721600Y-167083D01*
X-1721350Y-166150D01*
X-1721267Y-165100D01*
X-1721350Y-164050D01*
X-1721600Y-163117D01*
X-1721933Y-162417D01*
X-1722433Y-161833D01*
X-1723100Y-161600D01*
G01X-1716300D02*
X-1716967Y-161833D01*
X-1717467Y-162417D01*
X-1717800Y-163117D01*
X-1718050Y-164050D01*
X-1718133Y-165100D01*
X-1718050Y-166150D01*
X-1717800Y-167083D01*
X-1717467Y-167784D01*
X-1716967Y-168367D01*
X-1716300Y-168600D01*
X-1715633Y-168367D01*
X-1715133Y-167784D01*
X-1714800Y-167083D01*
X-1714550Y-166150D01*
X-1714467Y-165100D01*
X-1714550Y-164050D01*
X-1714800Y-163117D01*
X-1715133Y-162417D01*
X-1715633Y-161833D01*
X-1716300Y-161600D01*
G01X-1743675Y-154600D02*
Y-147600D01*
X-1744675Y-149000D01*
G01Y-154600D02*
X-1742675D01*
G01X-1736875Y-154833D02*
X-1737042Y-154717D01*
Y-154483D01*
X-1736875Y-154367D01*
X-1736708Y-154483D01*
Y-154717D01*
X-1736875Y-154833D01*
G01X-1731658Y-148767D02*
X-1731158Y-148067D01*
X-1730575Y-147717D01*
X-1729908Y-147600D01*
X-1729075Y-147833D01*
X-1728492Y-148417D01*
X-1728325Y-149117D01*
X-1728408Y-149817D01*
X-1728742Y-150400D01*
X-1730408Y-151567D01*
X-1731158Y-152383D01*
X-1731658Y-153550D01*
X-1731825Y-154600D01*
X-1728325D01*
G01X-1724858Y-148767D02*
X-1724358Y-148067D01*
X-1723775Y-147717D01*
X-1723108Y-147600D01*
X-1722275Y-147833D01*
X-1721692Y-148417D01*
X-1721525Y-149117D01*
X-1721608Y-149817D01*
X-1721942Y-150400D01*
X-1723608Y-151567D01*
X-1724358Y-152383D01*
X-1724858Y-153550D01*
X-1725025Y-154600D01*
X-1721525D01*
G01X-1716475Y-147600D02*
X-1717142Y-147833D01*
X-1717642Y-148417D01*
X-1717975Y-149117D01*
X-1718225Y-150050D01*
X-1718308Y-151100D01*
X-1718225Y-152150D01*
X-1717975Y-153083D01*
X-1717642Y-153784D01*
X-1717142Y-154367D01*
X-1716475Y-154600D01*
X-1715808Y-154367D01*
X-1715308Y-153784D01*
X-1714975Y-153083D01*
X-1714725Y-152150D01*
X-1714642Y-151100D01*
X-1714725Y-150050D01*
X-1714975Y-149117D01*
X-1715308Y-148417D01*
X-1715808Y-147833D01*
X-1716475Y-147600D01*
G01X-1741683Y-134267D02*
X-1741183Y-133567D01*
X-1740600Y-133217D01*
X-1739933Y-133100D01*
X-1739100Y-133333D01*
X-1738517Y-133917D01*
X-1738350Y-134617D01*
X-1738433Y-135317D01*
X-1738767Y-135900D01*
X-1740433Y-137067D01*
X-1741183Y-137883D01*
X-1741683Y-139050D01*
X-1741850Y-140100D01*
X-1738350D01*
G01X-1735133Y-138700D02*
X-1734633Y-139517D01*
X-1733967Y-139983D01*
X-1733217Y-140100D01*
X-1732550Y-139983D01*
X-1731883Y-139400D01*
X-1731467Y-138700D01*
X-1731383Y-138000D01*
X-1731550Y-137184D01*
X-1732133Y-136600D01*
X-1732717Y-136367D01*
X-1733467D01*
G01X-1732717D02*
X-1732217Y-136017D01*
X-1731800Y-135433D01*
X-1731633Y-134733D01*
X-1731800Y-134033D01*
X-1732217Y-133450D01*
X-1732967Y-133100D01*
X-1733717Y-133217D01*
X-1734467Y-133683D01*
G01X-1726500Y-140333D02*
X-1726667Y-140217D01*
Y-139983D01*
X-1726500Y-139867D01*
X-1726333Y-139983D01*
Y-140217D01*
X-1726500Y-140333D01*
G01X-1718700Y-140100D02*
Y-133100D01*
X-1721783Y-138117D01*
X-1717617D01*
G01X-1714483Y-137184D02*
X-1713900Y-136367D01*
X-1713400Y-135900D01*
X-1712733Y-135667D01*
X-1712150Y-135900D01*
X-1711733Y-136367D01*
X-1711400Y-137067D01*
X-1711317Y-137883D01*
X-1711400Y-138583D01*
X-1711733Y-139284D01*
X-1712233Y-139867D01*
X-1712817Y-140100D01*
X-1713483Y-139867D01*
X-1714067Y-139167D01*
X-1714400Y-138117D01*
X-1714483Y-136950D01*
X-1714317Y-135433D01*
X-1714067Y-134617D01*
X-1713650Y-133800D01*
X-1713067Y-133217D01*
X-1712483Y-133100D01*
X-1711900Y-133333D01*
X-1711483Y-133917D01*
G01X-1740275Y-119100D02*
X-1740942Y-119333D01*
X-1741442Y-119917D01*
X-1741775Y-120617D01*
X-1742025Y-121550D01*
X-1742108Y-122600D01*
X-1742025Y-123650D01*
X-1741775Y-124583D01*
X-1741442Y-125284D01*
X-1740942Y-125867D01*
X-1740275Y-126100D01*
X-1739608Y-125867D01*
X-1739108Y-125284D01*
X-1738775Y-124583D01*
X-1738525Y-123650D01*
X-1738442Y-122600D01*
X-1738525Y-121550D01*
X-1738775Y-120617D01*
X-1739108Y-119917D01*
X-1739608Y-119333D01*
X-1740275Y-119100D01*
G01X-1733475Y-126333D02*
X-1733642Y-126217D01*
Y-125983D01*
X-1733475Y-125867D01*
X-1733308Y-125983D01*
Y-126217D01*
X-1733475Y-126333D01*
G01X-1728092Y-125284D02*
X-1727508Y-125867D01*
X-1726842Y-126100D01*
X-1726175Y-125867D01*
X-1725592Y-125167D01*
X-1725175Y-124117D01*
X-1725008Y-123067D01*
Y-121783D01*
X-1725175Y-120733D01*
X-1725592Y-119800D01*
X-1726092Y-119333D01*
X-1726675Y-119100D01*
X-1727342Y-119333D01*
X-1727842Y-119800D01*
X-1728175Y-120500D01*
X-1728342Y-121433D01*
X-1728175Y-122250D01*
X-1727758Y-123067D01*
X-1727258Y-123533D01*
X-1726675Y-123650D01*
X-1726008Y-123417D01*
X-1725508Y-122833D01*
X-1725008Y-121783D01*
G01X-1721458Y-120267D02*
X-1720958Y-119567D01*
X-1720375Y-119217D01*
X-1719708Y-119100D01*
X-1718875Y-119333D01*
X-1718292Y-119917D01*
X-1718125Y-120617D01*
X-1718208Y-121317D01*
X-1718542Y-121900D01*
X-1720208Y-123067D01*
X-1720958Y-123883D01*
X-1721458Y-125050D01*
X-1721625Y-126100D01*
X-1718125D01*
G01X-1712075D02*
Y-119100D01*
X-1715158Y-124117D01*
X-1710992D01*
G01X-1736405Y-114822D02*
X-1737244Y-113660D01*
X-1737667Y-112496D01*
X-1737691Y-107829D01*
X-1737280Y-106660D01*
X-1736453Y-105489D01*
G01X-1730814Y-106627D02*
X-1730317Y-105925D01*
X-1729736Y-105571D01*
X-1729069Y-105451D01*
X-1728235Y-105680D01*
X-1727649Y-106261D01*
X-1727478Y-106960D01*
X-1727558Y-107660D01*
X-1727888Y-108245D01*
X-1729549Y-109421D01*
X-1730295Y-110241D01*
X-1730789Y-111411D01*
X-1730950Y-112461D01*
X-1727450Y-112443D01*
G01X-1723674Y-107757D02*
X-1721150Y-112411D01*
G01X-1721174Y-107744D02*
X-1723650Y-112424D01*
G01X-1715172Y-114713D02*
X-1714344Y-113542D01*
X-1713934Y-112374D01*
X-1713958Y-107707D01*
X-1714380Y-106542D01*
X-1715220Y-105380D01*
G01X-1740600Y-101000D02*
Y-94000D01*
X-1741600Y-95400D01*
G01Y-101000D02*
X-1739600D01*
G01X-1733967D02*
X-1733800Y-99483D01*
X-1733550Y-98200D01*
X-1733217Y-97033D01*
X-1732800Y-95750D01*
X-1732133Y-94000D01*
X-1735467D01*
G01X-1727000Y-101233D02*
X-1727167Y-101117D01*
Y-100883D01*
X-1727000Y-100767D01*
X-1726833Y-100883D01*
Y-101117D01*
X-1727000Y-101233D01*
G01X-1719200Y-101000D02*
Y-94000D01*
X-1722283Y-99017D01*
X-1718117D01*
G01X-1714983Y-98084D02*
X-1714400Y-97267D01*
X-1713900Y-96800D01*
X-1713233Y-96567D01*
X-1712650Y-96800D01*
X-1712233Y-97267D01*
X-1711900Y-97967D01*
X-1711817Y-98783D01*
X-1711900Y-99483D01*
X-1712233Y-100184D01*
X-1712733Y-100767D01*
X-1713317Y-101000D01*
X-1713983Y-100767D01*
X-1714567Y-100067D01*
X-1714900Y-99017D01*
X-1714983Y-97850D01*
X-1714817Y-96333D01*
X-1714567Y-95517D01*
X-1714150Y-94700D01*
X-1713567Y-94117D01*
X-1712983Y-94000D01*
X-1712400Y-94233D01*
X-1711983Y-94817D01*
G01X-1740775Y-80000D02*
X-1741442Y-80233D01*
X-1741942Y-80817D01*
X-1742275Y-81517D01*
X-1742525Y-82450D01*
X-1742608Y-83500D01*
X-1742525Y-84550D01*
X-1742275Y-85483D01*
X-1741942Y-86184D01*
X-1741442Y-86767D01*
X-1740775Y-87000D01*
X-1740108Y-86767D01*
X-1739608Y-86184D01*
X-1739275Y-85483D01*
X-1739025Y-84550D01*
X-1738942Y-83500D01*
X-1739025Y-82450D01*
X-1739275Y-81517D01*
X-1739608Y-80817D01*
X-1740108Y-80233D01*
X-1740775Y-80000D01*
G01X-1733975Y-87233D02*
X-1734142Y-87117D01*
Y-86883D01*
X-1733975Y-86767D01*
X-1733808Y-86883D01*
Y-87117D01*
X-1733975Y-87233D01*
G01X-1728758Y-84084D02*
X-1728175Y-83267D01*
X-1727675Y-82800D01*
X-1727008Y-82567D01*
X-1726425Y-82800D01*
X-1726008Y-83267D01*
X-1725675Y-83967D01*
X-1725592Y-84783D01*
X-1725675Y-85483D01*
X-1726008Y-86184D01*
X-1726508Y-86767D01*
X-1727092Y-87000D01*
X-1727758Y-86767D01*
X-1728342Y-86067D01*
X-1728675Y-85017D01*
X-1728758Y-83850D01*
X-1728592Y-82333D01*
X-1728342Y-81517D01*
X-1727925Y-80700D01*
X-1727342Y-80117D01*
X-1726758Y-80000D01*
X-1726175Y-80233D01*
X-1725758Y-80817D01*
G01X-1720375Y-87000D02*
X-1719792Y-86883D01*
X-1719125Y-86533D01*
X-1718708Y-85950D01*
X-1718542Y-85133D01*
X-1718708Y-84317D01*
X-1719208Y-83617D01*
X-1719958Y-83267D01*
X-1720792D01*
X-1721292Y-83033D01*
X-1721708Y-82450D01*
X-1721875Y-81633D01*
X-1721625Y-80817D01*
X-1721042Y-80233D01*
X-1720375Y-80000D01*
X-1719708Y-80233D01*
X-1719125Y-80817D01*
X-1718875Y-81633D01*
X-1719042Y-82450D01*
X-1719458Y-83033D01*
X-1719958Y-83267D01*
X-1720792D01*
X-1721542Y-83617D01*
X-1722042Y-84317D01*
X-1722208Y-85133D01*
X-1722042Y-85950D01*
X-1721625Y-86533D01*
X-1720958Y-86883D01*
X-1720375Y-87000D01*
G01X-1713742D02*
X-1713575Y-85483D01*
X-1713325Y-84200D01*
X-1712992Y-83033D01*
X-1712575Y-81750D01*
X-1711908Y-80000D01*
X-1715242D01*
G01X-1740900Y-72200D02*
Y-65200D01*
X-1741900Y-66600D01*
G01Y-72200D02*
X-1739900D01*
G01X-1735933Y-70800D02*
X-1735433Y-71617D01*
X-1734767Y-72083D01*
X-1734017Y-72200D01*
X-1733350Y-72083D01*
X-1732683Y-71500D01*
X-1732267Y-70800D01*
X-1732183Y-70100D01*
X-1732350Y-69284D01*
X-1732933Y-68700D01*
X-1733517Y-68467D01*
X-1734267D01*
G01X-1733517D02*
X-1733017Y-68117D01*
X-1732600Y-67533D01*
X-1732433Y-66833D01*
X-1732600Y-66133D01*
X-1733017Y-65550D01*
X-1733767Y-65200D01*
X-1734517Y-65317D01*
X-1735267Y-65783D01*
G01X-1727300Y-72433D02*
X-1727467Y-72317D01*
Y-72083D01*
X-1727300Y-71967D01*
X-1727133Y-72083D01*
Y-72317D01*
X-1727300Y-72433D01*
G01X-1720500Y-65200D02*
X-1721167Y-65433D01*
X-1721667Y-66017D01*
X-1722000Y-66717D01*
X-1722250Y-67650D01*
X-1722333Y-68700D01*
X-1722250Y-69750D01*
X-1722000Y-70683D01*
X-1721667Y-71384D01*
X-1721167Y-71967D01*
X-1720500Y-72200D01*
X-1719833Y-71967D01*
X-1719333Y-71384D01*
X-1719000Y-70683D01*
X-1718750Y-69750D01*
X-1718667Y-68700D01*
X-1718750Y-67650D01*
X-1719000Y-66717D01*
X-1719333Y-66017D01*
X-1719833Y-65433D01*
X-1720500Y-65200D01*
G01X-1713700D02*
X-1714367Y-65433D01*
X-1714867Y-66017D01*
X-1715200Y-66717D01*
X-1715450Y-67650D01*
X-1715533Y-68700D01*
X-1715450Y-69750D01*
X-1715200Y-70683D01*
X-1714867Y-71384D01*
X-1714367Y-71967D01*
X-1713700Y-72200D01*
X-1713033Y-71967D01*
X-1712533Y-71384D01*
X-1712200Y-70683D01*
X-1711950Y-69750D01*
X-1711867Y-68700D01*
X-1711950Y-67650D01*
X-1712200Y-66717D01*
X-1712533Y-66017D01*
X-1713033Y-65433D01*
X-1713700Y-65200D01*
G01X-1741075Y-51200D02*
X-1741742Y-51433D01*
X-1742242Y-52017D01*
X-1742575Y-52717D01*
X-1742825Y-53650D01*
X-1742908Y-54700D01*
X-1742825Y-55750D01*
X-1742575Y-56683D01*
X-1742242Y-57384D01*
X-1741742Y-57967D01*
X-1741075Y-58200D01*
X-1740408Y-57967D01*
X-1739908Y-57384D01*
X-1739575Y-56683D01*
X-1739325Y-55750D01*
X-1739242Y-54700D01*
X-1739325Y-53650D01*
X-1739575Y-52717D01*
X-1739908Y-52017D01*
X-1740408Y-51433D01*
X-1741075Y-51200D01*
G01X-1734275Y-58433D02*
X-1734442Y-58317D01*
Y-58083D01*
X-1734275Y-57967D01*
X-1734108Y-58083D01*
Y-58317D01*
X-1734275Y-58433D01*
G01X-1729308Y-57150D02*
X-1728808Y-57733D01*
X-1728225Y-58083D01*
X-1727475Y-58200D01*
X-1726725Y-57967D01*
X-1726142Y-57500D01*
X-1725725Y-56683D01*
X-1725642Y-55750D01*
X-1725808Y-54817D01*
X-1726225Y-54233D01*
X-1726808Y-53767D01*
X-1727392Y-53650D01*
X-1727975Y-53767D01*
X-1728725Y-54233D01*
X-1728475Y-51200D01*
X-1726225D01*
G01X-1720675Y-58200D02*
Y-51200D01*
X-1721675Y-52600D01*
G01Y-58200D02*
X-1719675D01*
G01X-1715458Y-52367D02*
X-1714958Y-51667D01*
X-1714375Y-51317D01*
X-1713708Y-51200D01*
X-1712875Y-51433D01*
X-1712292Y-52017D01*
X-1712125Y-52717D01*
X-1712208Y-53417D01*
X-1712542Y-54000D01*
X-1714208Y-55167D01*
X-1714958Y-55983D01*
X-1715458Y-57150D01*
X-1715625Y-58200D01*
X-1712125D01*
G01X-1738499Y-42982D02*
X-1739338Y-41819D01*
X-1739761Y-40655D01*
X-1739785Y-35988D01*
X-1739374Y-34819D01*
X-1738547Y-33648D01*
G01X-1732908Y-34786D02*
X-1732411Y-34084D01*
X-1731830Y-33730D01*
X-1731163Y-33610D01*
X-1730329Y-33839D01*
X-1729743Y-34420D01*
X-1729572Y-35119D01*
X-1729652Y-35819D01*
X-1729982Y-36404D01*
X-1731643Y-37580D01*
X-1732389Y-38400D01*
X-1732883Y-39570D01*
X-1733044Y-40620D01*
X-1729544Y-40602D01*
G01X-1725768Y-35916D02*
X-1723244Y-40570D01*
G01X-1723268Y-35903D02*
X-1725744Y-40583D01*
G01X-1717266Y-42872D02*
X-1716438Y-41701D01*
X-1716028Y-40533D01*
X-1716052Y-35866D01*
X-1716474Y-34701D01*
X-1717314Y-33539D01*
G01X-1740333Y-26870D02*
X-1739833Y-27453D01*
X-1739250Y-27803D01*
X-1738500Y-27920D01*
X-1737750Y-27687D01*
X-1737167Y-27220D01*
X-1736750Y-26403D01*
X-1736667Y-25470D01*
X-1736833Y-24537D01*
X-1737250Y-23953D01*
X-1737833Y-23487D01*
X-1738417Y-23370D01*
X-1739000Y-23487D01*
X-1739750Y-23953D01*
X-1739500Y-20920D01*
X-1737250D01*
G01X-1731700Y-28153D02*
X-1731867Y-28037D01*
Y-27803D01*
X-1731700Y-27687D01*
X-1731533Y-27803D01*
Y-28037D01*
X-1731700Y-28153D01*
G01X-1724900Y-27920D02*
Y-20920D01*
X-1725900Y-22320D01*
G01Y-27920D02*
X-1723900D01*
G01X-1719683Y-25004D02*
X-1719100Y-24187D01*
X-1718600Y-23720D01*
X-1717933Y-23487D01*
X-1717350Y-23720D01*
X-1716933Y-24187D01*
X-1716600Y-24887D01*
X-1716517Y-25703D01*
X-1716600Y-26403D01*
X-1716933Y-27104D01*
X-1717433Y-27687D01*
X-1718017Y-27920D01*
X-1718683Y-27687D01*
X-1719267Y-26987D01*
X-1719600Y-25937D01*
X-1719683Y-24770D01*
X-1719517Y-23253D01*
X-1719267Y-22437D01*
X-1718850Y-21620D01*
X-1718267Y-21037D01*
X-1717683Y-20920D01*
X-1717100Y-21153D01*
X-1716683Y-21737D01*
G01X-1742075Y-6920D02*
X-1742742Y-7153D01*
X-1743242Y-7737D01*
X-1743575Y-8437D01*
X-1743825Y-9370D01*
X-1743908Y-10420D01*
X-1743825Y-11470D01*
X-1743575Y-12403D01*
X-1743242Y-13104D01*
X-1742742Y-13687D01*
X-1742075Y-13920D01*
X-1741408Y-13687D01*
X-1740908Y-13104D01*
X-1740575Y-12403D01*
X-1740325Y-11470D01*
X-1740242Y-10420D01*
X-1740325Y-9370D01*
X-1740575Y-8437D01*
X-1740908Y-7737D01*
X-1741408Y-7153D01*
X-1742075Y-6920D01*
G01X-1735275Y-14153D02*
X-1735442Y-14037D01*
Y-13803D01*
X-1735275Y-13687D01*
X-1735108Y-13803D01*
Y-14037D01*
X-1735275Y-14153D01*
G01X-1730058Y-8087D02*
X-1729558Y-7387D01*
X-1728975Y-7037D01*
X-1728308Y-6920D01*
X-1727475Y-7153D01*
X-1726892Y-7737D01*
X-1726725Y-8437D01*
X-1726808Y-9137D01*
X-1727142Y-9720D01*
X-1728808Y-10887D01*
X-1729558Y-11703D01*
X-1730058Y-12870D01*
X-1730225Y-13920D01*
X-1726725D01*
G01X-1721675Y-6920D02*
X-1722342Y-7153D01*
X-1722842Y-7737D01*
X-1723175Y-8437D01*
X-1723425Y-9370D01*
X-1723508Y-10420D01*
X-1723425Y-11470D01*
X-1723175Y-12403D01*
X-1722842Y-13104D01*
X-1722342Y-13687D01*
X-1721675Y-13920D01*
X-1721008Y-13687D01*
X-1720508Y-13104D01*
X-1720175Y-12403D01*
X-1719925Y-11470D01*
X-1719842Y-10420D01*
X-1719925Y-9370D01*
X-1720175Y-8437D01*
X-1720508Y-7737D01*
X-1721008Y-7153D01*
X-1721675Y-6920D01*
G01X-1716708Y-12520D02*
X-1716208Y-13337D01*
X-1715542Y-13803D01*
X-1714792Y-13920D01*
X-1714125Y-13803D01*
X-1713458Y-13220D01*
X-1713042Y-12520D01*
X-1712958Y-11820D01*
X-1713125Y-11004D01*
X-1713708Y-10420D01*
X-1714292Y-10187D01*
X-1715042D01*
G01X-1714292D02*
X-1713792Y-9837D01*
X-1713375Y-9253D01*
X-1713208Y-8553D01*
X-1713375Y-7853D01*
X-1713792Y-7270D01*
X-1714542Y-6920D01*
X-1715292Y-7037D01*
X-1716042Y-7503D01*
G01X-1739380Y-2694D02*
X-1740219Y-1532D01*
X-1740642Y-368D01*
X-1740666Y4299D01*
X-1740255Y5468D01*
X-1739428Y6639D01*
G01X-1733789Y5501D02*
X-1733292Y6203D01*
X-1732711Y6557D01*
X-1732044Y6677D01*
X-1731210Y6448D01*
X-1730624Y5867D01*
X-1730453Y5168D01*
X-1730533Y4468D01*
X-1730863Y3883D01*
X-1732524Y2707D01*
X-1733270Y1887D01*
X-1733764Y717D01*
X-1733925Y-333D01*
X-1730425Y-315D01*
G01X-1726649Y4371D02*
X-1724125Y-283D01*
G01X-1724149Y4384D02*
X-1726625Y-296D01*
G01X-1718147Y-2585D02*
X-1717319Y-1414D01*
X-1716909Y-246D01*
X-1716933Y4421D01*
X-1717355Y5586D01*
X-1718195Y6748D01*
G01X-1740941Y11573D02*
X-1740441Y10990D01*
X-1739858Y10640D01*
X-1739108Y10524D01*
X-1738358Y10757D01*
X-1737775Y11223D01*
X-1737358Y12040D01*
X-1737275Y12974D01*
X-1737441Y13907D01*
X-1737858Y14490D01*
X-1738441Y14957D01*
X-1739025Y15074D01*
X-1739608Y14957D01*
X-1740358Y14490D01*
X-1740108Y17524D01*
X-1737858D01*
G01X-1732308Y10290D02*
X-1732475Y10407D01*
Y10640D01*
X-1732308Y10757D01*
X-1732141Y10640D01*
Y10407D01*
X-1732308Y10290D01*
G01X-1727341Y11924D02*
X-1726841Y11107D01*
X-1726175Y10640D01*
X-1725425Y10524D01*
X-1724758Y10640D01*
X-1724091Y11223D01*
X-1723675Y11924D01*
X-1723591Y12624D01*
X-1723758Y13440D01*
X-1724341Y14024D01*
X-1724925Y14257D01*
X-1725675D01*
G01X-1724925D02*
X-1724425Y14607D01*
X-1724008Y15190D01*
X-1723841Y15890D01*
X-1724008Y16590D01*
X-1724425Y17173D01*
X-1725175Y17524D01*
X-1725925Y17407D01*
X-1726675Y16940D01*
G01X-1717708Y10524D02*
Y17524D01*
X-1720791Y12507D01*
X-1716625D01*
G01X-1742683Y31524D02*
X-1743350Y31290D01*
X-1743850Y30707D01*
X-1744183Y30007D01*
X-1744433Y29074D01*
X-1744516Y28024D01*
X-1744433Y26974D01*
X-1744183Y26040D01*
X-1743850Y25340D01*
X-1743350Y24757D01*
X-1742683Y24524D01*
X-1742016Y24757D01*
X-1741516Y25340D01*
X-1741183Y26040D01*
X-1740933Y26974D01*
X-1740850Y28024D01*
X-1740933Y29074D01*
X-1741183Y30007D01*
X-1741516Y30707D01*
X-1742016Y31290D01*
X-1742683Y31524D01*
G01X-1735883Y24290D02*
X-1736050Y24407D01*
Y24640D01*
X-1735883Y24757D01*
X-1735716Y24640D01*
Y24407D01*
X-1735883Y24290D01*
G01X-1730666Y30357D02*
X-1730166Y31057D01*
X-1729583Y31407D01*
X-1728916Y31524D01*
X-1728083Y31290D01*
X-1727500Y30707D01*
X-1727333Y30007D01*
X-1727416Y29307D01*
X-1727750Y28724D01*
X-1729416Y27557D01*
X-1730166Y26740D01*
X-1730666Y25573D01*
X-1730833Y24524D01*
X-1727333D01*
G01X-1722283D02*
Y31524D01*
X-1723283Y30124D01*
G01Y24524D02*
X-1721283D01*
G01X-1715483Y31524D02*
X-1716150Y31290D01*
X-1716650Y30707D01*
X-1716983Y30007D01*
X-1717233Y29074D01*
X-1717316Y28024D01*
X-1717233Y26974D01*
X-1716983Y26040D01*
X-1716650Y25340D01*
X-1716150Y24757D01*
X-1715483Y24524D01*
X-1714816Y24757D01*
X-1714316Y25340D01*
X-1713983Y26040D01*
X-1713733Y26974D01*
X-1713650Y28024D01*
X-1713733Y29074D01*
X-1713983Y30007D01*
X-1714316Y30707D01*
X-1714816Y31290D01*
X-1715483Y31524D01*
G01X-1689203Y803970D02*
Y810970D01*
X-1686037D01*
G01X-1687203Y807587D02*
X-1689203D01*
G01X-1681820Y810970D02*
X-1679820D01*
G01X-1680820D02*
Y803970D01*
G01X-1681820D02*
X-1679820D01*
G01X-1673520Y807470D02*
X-1671853D01*
Y805370D01*
X-1672353Y804670D01*
X-1672937Y804203D01*
X-1673770Y803970D01*
X-1674603Y804203D01*
X-1675187Y804670D01*
X-1675687Y805370D01*
X-1676020Y806187D01*
X-1676187Y807120D01*
Y807937D01*
X-1676020Y808637D01*
X-1675687Y809453D01*
X-1675187Y810153D01*
X-1674687Y810620D01*
X-1674020Y810970D01*
X-1673437D01*
X-1672770Y810737D01*
X-1672270Y810270D01*
G01X-1669053Y810970D02*
Y805953D01*
X-1668720Y804903D01*
X-1668053Y804203D01*
X-1667220Y803970D01*
X-1666387Y804203D01*
X-1665720Y804903D01*
X-1665387Y805953D01*
Y810970D01*
G01X-1662087Y803970D02*
Y810970D01*
X-1660003D01*
X-1659337Y810620D01*
X-1658920Y810153D01*
X-1658753Y809220D01*
X-1658920Y808287D01*
X-1659420Y807703D01*
X-1660003Y807353D01*
X-1662087D01*
G01X-1660003D02*
X-1658753Y803970D01*
G01X-1651953D02*
X-1655287D01*
Y810970D01*
X-1651953D01*
G01X-1653287Y807587D02*
X-1655287D01*
G01X-1665700Y-258675D02*
X-1672700D01*
X-1671300Y-259675D01*
G01X-1665700D02*
Y-257675D01*
G01X-1668616Y-253458D02*
X-1669433Y-252875D01*
X-1669900Y-252375D01*
X-1670133Y-251708D01*
X-1669900Y-251125D01*
X-1669433Y-250708D01*
X-1668733Y-250375D01*
X-1667917Y-250292D01*
X-1667217Y-250375D01*
X-1666516Y-250708D01*
X-1665933Y-251208D01*
X-1665700Y-251792D01*
X-1665933Y-252458D01*
X-1666633Y-253042D01*
X-1667683Y-253375D01*
X-1668850Y-253458D01*
X-1670367Y-253292D01*
X-1671183Y-253042D01*
X-1672000Y-252625D01*
X-1672583Y-252042D01*
X-1672700Y-251458D01*
X-1672467Y-250875D01*
X-1671883Y-250458D01*
G01X-1665467Y-245075D02*
X-1665583Y-245242D01*
X-1665817D01*
X-1665933Y-245075D01*
X-1665817Y-244908D01*
X-1665583D01*
X-1665467Y-245075D01*
G01X-1668616Y-239858D02*
X-1669433Y-239275D01*
X-1669900Y-238775D01*
X-1670133Y-238108D01*
X-1669900Y-237525D01*
X-1669433Y-237108D01*
X-1668733Y-236775D01*
X-1667917Y-236692D01*
X-1667217Y-236775D01*
X-1666516Y-237108D01*
X-1665933Y-237608D01*
X-1665700Y-238192D01*
X-1665933Y-238858D01*
X-1666633Y-239442D01*
X-1667683Y-239775D01*
X-1668850Y-239858D01*
X-1670367Y-239692D01*
X-1671183Y-239442D01*
X-1672000Y-239025D01*
X-1672583Y-238442D01*
X-1672700Y-237858D01*
X-1672467Y-237275D01*
X-1671883Y-236858D01*
G01X-1667100Y-233308D02*
X-1666283Y-232808D01*
X-1665817Y-232142D01*
X-1665700Y-231392D01*
X-1665817Y-230725D01*
X-1666400Y-230058D01*
X-1667100Y-229642D01*
X-1667800Y-229558D01*
X-1668616Y-229725D01*
X-1669200Y-230308D01*
X-1669433Y-230892D01*
Y-231642D01*
G01Y-230892D02*
X-1669783Y-230392D01*
X-1670367Y-229975D01*
X-1671067Y-229808D01*
X-1671767Y-229975D01*
X-1672350Y-230392D01*
X-1672700Y-231142D01*
X-1672583Y-231892D01*
X-1672117Y-232642D01*
G01X-1665700Y-224675D02*
X-1672700D01*
X-1671300Y-225675D01*
G01X-1665700D02*
Y-223675D01*
G01X-1651700Y-257500D02*
X-1658700D01*
X-1653683Y-260583D01*
Y-256417D01*
G01X-1657533Y-253283D02*
X-1658233Y-252783D01*
X-1658583Y-252200D01*
X-1658700Y-251533D01*
X-1658467Y-250700D01*
X-1657883Y-250117D01*
X-1657183Y-249950D01*
X-1656483Y-250033D01*
X-1655900Y-250367D01*
X-1654733Y-252033D01*
X-1653917Y-252783D01*
X-1652750Y-253283D01*
X-1651700Y-253450D01*
Y-249950D01*
G01X-1657533Y-246483D02*
X-1658233Y-245983D01*
X-1658583Y-245400D01*
X-1658700Y-244733D01*
X-1658467Y-243900D01*
X-1657883Y-243317D01*
X-1657183Y-243150D01*
X-1656483Y-243233D01*
X-1655900Y-243567D01*
X-1654733Y-245233D01*
X-1653917Y-245983D01*
X-1652750Y-246483D01*
X-1651700Y-246650D01*
Y-243150D01*
G01X-1651467Y-238100D02*
X-1651583Y-238267D01*
X-1651817D01*
X-1651933Y-238100D01*
X-1651817Y-237933D01*
X-1651583D01*
X-1651467Y-238100D01*
G01X-1651700Y-230300D02*
X-1658700D01*
X-1653683Y-233383D01*
Y-229217D01*
G01X-1653100Y-226333D02*
X-1652283Y-225833D01*
X-1651817Y-225167D01*
X-1651700Y-224417D01*
X-1651817Y-223750D01*
X-1652400Y-223083D01*
X-1653100Y-222667D01*
X-1653800Y-222583D01*
X-1654616Y-222750D01*
X-1655200Y-223333D01*
X-1655433Y-223917D01*
Y-224667D01*
G01Y-223917D02*
X-1655783Y-223417D01*
X-1656367Y-223000D01*
X-1657067Y-222833D01*
X-1657767Y-223000D01*
X-1658350Y-223417D01*
X-1658700Y-224167D01*
X-1658583Y-224917D01*
X-1658117Y-225667D01*
G01X-1643687Y85722D02*
X-1650687D01*
X-1649287Y84722D01*
G01X-1643687D02*
Y86722D01*
G01X-1646603Y90939D02*
X-1647420Y91522D01*
X-1647887Y92022D01*
X-1648120Y92689D01*
X-1647887Y93272D01*
X-1647420Y93689D01*
X-1646720Y94022D01*
X-1645904Y94105D01*
X-1645204Y94022D01*
X-1644503Y93689D01*
X-1643920Y93189D01*
X-1643687Y92605D01*
X-1643920Y91939D01*
X-1644620Y91355D01*
X-1645670Y91022D01*
X-1646837Y90939D01*
X-1648354Y91105D01*
X-1649170Y91355D01*
X-1649987Y91772D01*
X-1650570Y92355D01*
X-1650687Y92939D01*
X-1650454Y93522D01*
X-1649870Y93939D01*
G01X-1643454Y99322D02*
X-1643570Y99155D01*
X-1643804D01*
X-1643920Y99322D01*
X-1643804Y99489D01*
X-1643570D01*
X-1643454Y99322D01*
G01X-1649520Y104539D02*
X-1650220Y105039D01*
X-1650570Y105622D01*
X-1650687Y106289D01*
X-1650454Y107122D01*
X-1649870Y107705D01*
X-1649170Y107872D01*
X-1648470Y107789D01*
X-1647887Y107455D01*
X-1646720Y105789D01*
X-1645904Y105039D01*
X-1644737Y104539D01*
X-1643687Y104372D01*
Y107872D01*
G01X-1649520Y111339D02*
X-1650220Y111839D01*
X-1650570Y112422D01*
X-1650687Y113089D01*
X-1650454Y113922D01*
X-1649870Y114505D01*
X-1649170Y114672D01*
X-1648470Y114589D01*
X-1647887Y114255D01*
X-1646720Y112589D01*
X-1645904Y111839D01*
X-1644737Y111339D01*
X-1643687Y111172D01*
Y114672D01*
G01Y119722D02*
X-1650687D01*
X-1649287Y118722D01*
G01X-1643687D02*
Y120722D01*
G01X-1629687Y86897D02*
X-1636687D01*
X-1631670Y83814D01*
Y87980D01*
G01X-1629687Y92697D02*
X-1636687D01*
X-1635287Y91697D01*
G01X-1629687D02*
Y93697D01*
G01X-1635520Y97914D02*
X-1636220Y98414D01*
X-1636570Y98997D01*
X-1636687Y99664D01*
X-1636454Y100497D01*
X-1635870Y101080D01*
X-1635170Y101247D01*
X-1634470Y101164D01*
X-1633887Y100830D01*
X-1632720Y99164D01*
X-1631904Y98414D01*
X-1630737Y97914D01*
X-1629687Y97747D01*
Y101247D01*
G01X-1629454Y106297D02*
X-1629570Y106130D01*
X-1629804D01*
X-1629920Y106297D01*
X-1629804Y106464D01*
X-1629570D01*
X-1629454Y106297D01*
G01X-1636687Y113097D02*
X-1636454Y112430D01*
X-1635870Y111930D01*
X-1635170Y111597D01*
X-1634237Y111347D01*
X-1633187Y111264D01*
X-1632137Y111347D01*
X-1631204Y111597D01*
X-1630503Y111930D01*
X-1629920Y112430D01*
X-1629687Y113097D01*
X-1629920Y113764D01*
X-1630503Y114264D01*
X-1631204Y114597D01*
X-1632137Y114847D01*
X-1633187Y114930D01*
X-1634237Y114847D01*
X-1635170Y114597D01*
X-1635870Y114264D01*
X-1636454Y113764D01*
X-1636687Y113097D01*
G01X-1629687Y119897D02*
X-1636687D01*
X-1635287Y118897D01*
G01X-1629687D02*
Y120897D01*
G01X-1613694Y-257742D02*
X-1620694D01*
X-1619294Y-258742D01*
G01X-1613694D02*
Y-256742D01*
G01X-1616610Y-252525D02*
X-1617427Y-251942D01*
X-1617894Y-251442D01*
X-1618127Y-250775D01*
X-1617894Y-250192D01*
X-1617427Y-249775D01*
X-1616727Y-249442D01*
X-1615911Y-249359D01*
X-1615211Y-249442D01*
X-1614510Y-249775D01*
X-1613927Y-250275D01*
X-1613694Y-250859D01*
X-1613927Y-251525D01*
X-1614627Y-252109D01*
X-1615677Y-252442D01*
X-1616844Y-252525D01*
X-1618361Y-252359D01*
X-1619177Y-252109D01*
X-1619994Y-251692D01*
X-1620577Y-251109D01*
X-1620694Y-250525D01*
X-1620461Y-249942D01*
X-1619877Y-249525D01*
G01X-1613461Y-244142D02*
X-1613577Y-244309D01*
X-1613811D01*
X-1613927Y-244142D01*
X-1613811Y-243975D01*
X-1613577D01*
X-1613461Y-244142D01*
G01X-1613694Y-236342D02*
X-1620694D01*
X-1615677Y-239425D01*
Y-235259D01*
G01X-1615094Y-232375D02*
X-1614277Y-231875D01*
X-1613811Y-231209D01*
X-1613694Y-230459D01*
X-1613811Y-229792D01*
X-1614394Y-229125D01*
X-1615094Y-228709D01*
X-1615794Y-228625D01*
X-1616610Y-228792D01*
X-1617194Y-229375D01*
X-1617427Y-229959D01*
Y-230709D01*
G01Y-229959D02*
X-1617777Y-229459D01*
X-1618361Y-229042D01*
X-1619061Y-228875D01*
X-1619761Y-229042D01*
X-1620344Y-229459D01*
X-1620694Y-230209D01*
X-1620577Y-230959D01*
X-1620111Y-231709D01*
G01X-1614744Y-225575D02*
X-1614161Y-225075D01*
X-1613811Y-224492D01*
X-1613694Y-223742D01*
X-1613927Y-222992D01*
X-1614394Y-222409D01*
X-1615211Y-221992D01*
X-1616144Y-221909D01*
X-1617077Y-222075D01*
X-1617661Y-222492D01*
X-1618127Y-223075D01*
X-1618244Y-223659D01*
X-1618127Y-224242D01*
X-1617661Y-224992D01*
X-1620694Y-224742D01*
Y-222492D01*
G01X-1608103Y87634D02*
X-1615103D01*
X-1613703Y86634D01*
G01X-1608103D02*
Y88634D01*
G01X-1611019Y92851D02*
X-1611836Y93434D01*
X-1612303Y93934D01*
X-1612536Y94601D01*
X-1612303Y95184D01*
X-1611836Y95601D01*
X-1611136Y95934D01*
X-1610320Y96017D01*
X-1609620Y95934D01*
X-1608919Y95601D01*
X-1608336Y95101D01*
X-1608103Y94517D01*
X-1608336Y93851D01*
X-1609036Y93267D01*
X-1610086Y92934D01*
X-1611253Y92851D01*
X-1612770Y93017D01*
X-1613586Y93267D01*
X-1614403Y93684D01*
X-1614986Y94267D01*
X-1615103Y94851D01*
X-1614870Y95434D01*
X-1614286Y95851D01*
G01X-1607870Y101234D02*
X-1607986Y101067D01*
X-1608220D01*
X-1608336Y101234D01*
X-1608220Y101401D01*
X-1607986D01*
X-1607870Y101234D01*
G01X-1608103Y108034D02*
X-1615103D01*
X-1613703Y107034D01*
G01X-1608103D02*
Y109034D01*
G01X-1608919Y113417D02*
X-1608336Y114001D01*
X-1608103Y114667D01*
X-1608336Y115334D01*
X-1609036Y115917D01*
X-1610086Y116334D01*
X-1611136Y116501D01*
X-1612420D01*
X-1613470Y116334D01*
X-1614403Y115917D01*
X-1614870Y115417D01*
X-1615103Y114834D01*
X-1614870Y114167D01*
X-1614403Y113667D01*
X-1613703Y113334D01*
X-1612770Y113167D01*
X-1611953Y113334D01*
X-1611136Y113751D01*
X-1610670Y114251D01*
X-1610553Y114834D01*
X-1610786Y115501D01*
X-1611370Y116001D01*
X-1612420Y116501D01*
G01X-1609503Y119801D02*
X-1608686Y120301D01*
X-1608220Y120967D01*
X-1608103Y121717D01*
X-1608220Y122384D01*
X-1608803Y123051D01*
X-1609503Y123467D01*
X-1610203Y123551D01*
X-1611019Y123384D01*
X-1611603Y122801D01*
X-1611836Y122217D01*
Y121467D01*
G01Y122217D02*
X-1612186Y122717D01*
X-1612770Y123134D01*
X-1613470Y123301D01*
X-1614170Y123134D01*
X-1614753Y122717D01*
X-1615103Y121967D01*
X-1614986Y121217D01*
X-1614520Y120467D01*
G01X-1614420Y337170D02*
Y344170D01*
X-1615420Y342770D01*
G01Y337170D02*
X-1613420D01*
G01X-1609453Y338220D02*
X-1608953Y337637D01*
X-1608370Y337287D01*
X-1607620Y337170D01*
X-1606870Y337403D01*
X-1606287Y337870D01*
X-1605870Y338687D01*
X-1605787Y339620D01*
X-1605953Y340553D01*
X-1606370Y341137D01*
X-1606953Y341603D01*
X-1607537Y341720D01*
X-1608120Y341603D01*
X-1608870Y341137D01*
X-1608620Y344170D01*
X-1606370D01*
G01X-1602403Y340086D02*
X-1601820Y340903D01*
X-1601320Y341370D01*
X-1600653Y341603D01*
X-1600070Y341370D01*
X-1599653Y340903D01*
X-1599320Y340203D01*
X-1599237Y339387D01*
X-1599320Y338687D01*
X-1599653Y337986D01*
X-1600153Y337403D01*
X-1600737Y337170D01*
X-1601403Y337403D01*
X-1601987Y338103D01*
X-1602320Y339153D01*
X-1602403Y340320D01*
X-1602237Y341837D01*
X-1601987Y342653D01*
X-1601570Y343470D01*
X-1600987Y344053D01*
X-1600403Y344170D01*
X-1599820Y343937D01*
X-1599403Y343353D01*
G01X-1594020Y336937D02*
X-1594187Y337053D01*
Y337287D01*
X-1594020Y337403D01*
X-1593853Y337287D01*
Y337053D01*
X-1594020Y336937D01*
G01X-1587220Y344170D02*
X-1587887Y343937D01*
X-1588387Y343353D01*
X-1588720Y342653D01*
X-1588970Y341720D01*
X-1589053Y340670D01*
X-1588970Y339620D01*
X-1588720Y338687D01*
X-1588387Y337986D01*
X-1587887Y337403D01*
X-1587220Y337170D01*
X-1586553Y337403D01*
X-1586053Y337986D01*
X-1585720Y338687D01*
X-1585470Y339620D01*
X-1585387Y340670D01*
X-1585470Y341720D01*
X-1585720Y342653D01*
X-1586053Y343353D01*
X-1586553Y343937D01*
X-1587220Y344170D01*
G01X-1580420D02*
X-1581087Y343937D01*
X-1581587Y343353D01*
X-1581920Y342653D01*
X-1582170Y341720D01*
X-1582253Y340670D01*
X-1582170Y339620D01*
X-1581920Y338687D01*
X-1581587Y337986D01*
X-1581087Y337403D01*
X-1580420Y337170D01*
X-1579753Y337403D01*
X-1579253Y337986D01*
X-1578920Y338687D01*
X-1578670Y339620D01*
X-1578587Y340670D01*
X-1578670Y341720D01*
X-1578920Y342653D01*
X-1579253Y343353D01*
X-1579753Y343937D01*
X-1580420Y344170D01*
G01X-1573620D02*
X-1574287Y343937D01*
X-1574787Y343353D01*
X-1575120Y342653D01*
X-1575370Y341720D01*
X-1575453Y340670D01*
X-1575370Y339620D01*
X-1575120Y338687D01*
X-1574787Y337986D01*
X-1574287Y337403D01*
X-1573620Y337170D01*
X-1572953Y337403D01*
X-1572453Y337986D01*
X-1572120Y338687D01*
X-1571870Y339620D01*
X-1571787Y340670D01*
X-1571870Y341720D01*
X-1572120Y342653D01*
X-1572453Y343353D01*
X-1572953Y343937D01*
X-1573620Y344170D01*
G01X-1614420Y360570D02*
Y367570D01*
X-1615420Y366170D01*
G01Y360570D02*
X-1613420D01*
G01X-1609203Y366403D02*
X-1608703Y367103D01*
X-1608120Y367453D01*
X-1607453Y367570D01*
X-1606620Y367337D01*
X-1606037Y366753D01*
X-1605870Y366053D01*
X-1605953Y365353D01*
X-1606287Y364770D01*
X-1607953Y363603D01*
X-1608703Y362787D01*
X-1609203Y361620D01*
X-1609370Y360570D01*
X-1605870D01*
G01X-1602653Y361620D02*
X-1602153Y361037D01*
X-1601570Y360687D01*
X-1600820Y360570D01*
X-1600070Y360803D01*
X-1599487Y361270D01*
X-1599070Y362087D01*
X-1598987Y363020D01*
X-1599153Y363953D01*
X-1599570Y364537D01*
X-1600153Y365003D01*
X-1600737Y365120D01*
X-1601320Y365003D01*
X-1602070Y364537D01*
X-1601820Y367570D01*
X-1599570D01*
G01X-1594020Y360337D02*
X-1594187Y360453D01*
Y360687D01*
X-1594020Y360803D01*
X-1593853Y360687D01*
Y360453D01*
X-1594020Y360337D01*
G01X-1587220Y367570D02*
X-1587887Y367337D01*
X-1588387Y366753D01*
X-1588720Y366053D01*
X-1588970Y365120D01*
X-1589053Y364070D01*
X-1588970Y363020D01*
X-1588720Y362087D01*
X-1588387Y361386D01*
X-1587887Y360803D01*
X-1587220Y360570D01*
X-1586553Y360803D01*
X-1586053Y361386D01*
X-1585720Y362087D01*
X-1585470Y363020D01*
X-1585387Y364070D01*
X-1585470Y365120D01*
X-1585720Y366053D01*
X-1586053Y366753D01*
X-1586553Y367337D01*
X-1587220Y367570D01*
G01X-1580420D02*
X-1581087Y367337D01*
X-1581587Y366753D01*
X-1581920Y366053D01*
X-1582170Y365120D01*
X-1582253Y364070D01*
X-1582170Y363020D01*
X-1581920Y362087D01*
X-1581587Y361386D01*
X-1581087Y360803D01*
X-1580420Y360570D01*
X-1579753Y360803D01*
X-1579253Y361386D01*
X-1578920Y362087D01*
X-1578670Y363020D01*
X-1578587Y364070D01*
X-1578670Y365120D01*
X-1578920Y366053D01*
X-1579253Y366753D01*
X-1579753Y367337D01*
X-1580420Y367570D01*
G01X-1573620D02*
X-1574287Y367337D01*
X-1574787Y366753D01*
X-1575120Y366053D01*
X-1575370Y365120D01*
X-1575453Y364070D01*
X-1575370Y363020D01*
X-1575120Y362087D01*
X-1574787Y361386D01*
X-1574287Y360803D01*
X-1573620Y360570D01*
X-1572953Y360803D01*
X-1572453Y361386D01*
X-1572120Y362087D01*
X-1571870Y363020D01*
X-1571787Y364070D01*
X-1571870Y365120D01*
X-1572120Y366053D01*
X-1572453Y366753D01*
X-1572953Y367337D01*
X-1573620Y367570D01*
G01X-1611020Y383970D02*
X-1610437Y384087D01*
X-1609770Y384437D01*
X-1609353Y385020D01*
X-1609187Y385837D01*
X-1609353Y386653D01*
X-1609853Y387353D01*
X-1610603Y387703D01*
X-1611437D01*
X-1611937Y387937D01*
X-1612353Y388520D01*
X-1612520Y389337D01*
X-1612270Y390153D01*
X-1611687Y390737D01*
X-1611020Y390970D01*
X-1610353Y390737D01*
X-1609770Y390153D01*
X-1609520Y389337D01*
X-1609687Y388520D01*
X-1610103Y387937D01*
X-1610603Y387703D01*
X-1611437D01*
X-1612187Y387353D01*
X-1612687Y386653D01*
X-1612853Y385837D01*
X-1612687Y385020D01*
X-1612270Y384437D01*
X-1611603Y384087D01*
X-1611020Y383970D01*
G01X-1605803Y386886D02*
X-1605220Y387703D01*
X-1604720Y388170D01*
X-1604053Y388403D01*
X-1603470Y388170D01*
X-1603053Y387703D01*
X-1602720Y387003D01*
X-1602637Y386187D01*
X-1602720Y385487D01*
X-1603053Y384786D01*
X-1603553Y384203D01*
X-1604137Y383970D01*
X-1604803Y384203D01*
X-1605387Y384903D01*
X-1605720Y385953D01*
X-1605803Y387120D01*
X-1605637Y388637D01*
X-1605387Y389453D01*
X-1604970Y390270D01*
X-1604387Y390853D01*
X-1603803Y390970D01*
X-1603220Y390737D01*
X-1602803Y390153D01*
G01X-1597420Y383737D02*
X-1597587Y383853D01*
Y384087D01*
X-1597420Y384203D01*
X-1597253Y384087D01*
Y383853D01*
X-1597420Y383737D01*
G01X-1590620Y390970D02*
X-1591287Y390737D01*
X-1591787Y390153D01*
X-1592120Y389453D01*
X-1592370Y388520D01*
X-1592453Y387470D01*
X-1592370Y386420D01*
X-1592120Y385487D01*
X-1591787Y384786D01*
X-1591287Y384203D01*
X-1590620Y383970D01*
X-1589953Y384203D01*
X-1589453Y384786D01*
X-1589120Y385487D01*
X-1588870Y386420D01*
X-1588787Y387470D01*
X-1588870Y388520D01*
X-1589120Y389453D01*
X-1589453Y390153D01*
X-1589953Y390737D01*
X-1590620Y390970D01*
G01X-1583820D02*
X-1584487Y390737D01*
X-1584987Y390153D01*
X-1585320Y389453D01*
X-1585570Y388520D01*
X-1585653Y387470D01*
X-1585570Y386420D01*
X-1585320Y385487D01*
X-1584987Y384786D01*
X-1584487Y384203D01*
X-1583820Y383970D01*
X-1583153Y384203D01*
X-1582653Y384786D01*
X-1582320Y385487D01*
X-1582070Y386420D01*
X-1581987Y387470D01*
X-1582070Y388520D01*
X-1582320Y389453D01*
X-1582653Y390153D01*
X-1583153Y390737D01*
X-1583820Y390970D01*
G01X-1577020D02*
X-1577687Y390737D01*
X-1578187Y390153D01*
X-1578520Y389453D01*
X-1578770Y388520D01*
X-1578853Y387470D01*
X-1578770Y386420D01*
X-1578520Y385487D01*
X-1578187Y384786D01*
X-1577687Y384203D01*
X-1577020Y383970D01*
X-1576353Y384203D01*
X-1575853Y384786D01*
X-1575520Y385487D01*
X-1575270Y386420D01*
X-1575187Y387470D01*
X-1575270Y388520D01*
X-1575520Y389453D01*
X-1575853Y390153D01*
X-1576353Y390737D01*
X-1577020Y390970D01*
G01X-1612603Y410286D02*
X-1612020Y411103D01*
X-1611520Y411570D01*
X-1610853Y411803D01*
X-1610270Y411570D01*
X-1609853Y411103D01*
X-1609520Y410403D01*
X-1609437Y409587D01*
X-1609520Y408887D01*
X-1609853Y408186D01*
X-1610353Y407603D01*
X-1610937Y407370D01*
X-1611603Y407603D01*
X-1612187Y408303D01*
X-1612520Y409353D01*
X-1612603Y410520D01*
X-1612437Y412037D01*
X-1612187Y412853D01*
X-1611770Y413670D01*
X-1611187Y414253D01*
X-1610603Y414370D01*
X-1610020Y414137D01*
X-1609603Y413553D01*
G01X-1606053Y408770D02*
X-1605553Y407953D01*
X-1604887Y407487D01*
X-1604137Y407370D01*
X-1603470Y407487D01*
X-1602803Y408070D01*
X-1602387Y408770D01*
X-1602303Y409470D01*
X-1602470Y410286D01*
X-1603053Y410870D01*
X-1603637Y411103D01*
X-1604387D01*
G01X-1603637D02*
X-1603137Y411453D01*
X-1602720Y412037D01*
X-1602553Y412737D01*
X-1602720Y413437D01*
X-1603137Y414020D01*
X-1603887Y414370D01*
X-1604637Y414253D01*
X-1605387Y413787D01*
G01X-1597420Y407137D02*
X-1597587Y407253D01*
Y407487D01*
X-1597420Y407603D01*
X-1597253Y407487D01*
Y407253D01*
X-1597420Y407137D01*
G01X-1590620Y414370D02*
X-1591287Y414137D01*
X-1591787Y413553D01*
X-1592120Y412853D01*
X-1592370Y411920D01*
X-1592453Y410870D01*
X-1592370Y409820D01*
X-1592120Y408887D01*
X-1591787Y408186D01*
X-1591287Y407603D01*
X-1590620Y407370D01*
X-1589953Y407603D01*
X-1589453Y408186D01*
X-1589120Y408887D01*
X-1588870Y409820D01*
X-1588787Y410870D01*
X-1588870Y411920D01*
X-1589120Y412853D01*
X-1589453Y413553D01*
X-1589953Y414137D01*
X-1590620Y414370D01*
G01X-1583820D02*
X-1584487Y414137D01*
X-1584987Y413553D01*
X-1585320Y412853D01*
X-1585570Y411920D01*
X-1585653Y410870D01*
X-1585570Y409820D01*
X-1585320Y408887D01*
X-1584987Y408186D01*
X-1584487Y407603D01*
X-1583820Y407370D01*
X-1583153Y407603D01*
X-1582653Y408186D01*
X-1582320Y408887D01*
X-1582070Y409820D01*
X-1581987Y410870D01*
X-1582070Y411920D01*
X-1582320Y412853D01*
X-1582653Y413553D01*
X-1583153Y414137D01*
X-1583820Y414370D01*
G01X-1577020D02*
X-1577687Y414137D01*
X-1578187Y413553D01*
X-1578520Y412853D01*
X-1578770Y411920D01*
X-1578853Y410870D01*
X-1578770Y409820D01*
X-1578520Y408887D01*
X-1578187Y408186D01*
X-1577687Y407603D01*
X-1577020Y407370D01*
X-1576353Y407603D01*
X-1575853Y408186D01*
X-1575520Y408887D01*
X-1575270Y409820D01*
X-1575187Y410870D01*
X-1575270Y411920D01*
X-1575520Y412853D01*
X-1575853Y413553D01*
X-1576353Y414137D01*
X-1577020Y414370D01*
G01X-1612603Y433686D02*
X-1612020Y434503D01*
X-1611520Y434970D01*
X-1610853Y435203D01*
X-1610270Y434970D01*
X-1609853Y434503D01*
X-1609520Y433803D01*
X-1609437Y432987D01*
X-1609520Y432287D01*
X-1609853Y431586D01*
X-1610353Y431003D01*
X-1610937Y430770D01*
X-1611603Y431003D01*
X-1612187Y431703D01*
X-1612520Y432753D01*
X-1612603Y433920D01*
X-1612437Y435437D01*
X-1612187Y436253D01*
X-1611770Y437070D01*
X-1611187Y437653D01*
X-1610603Y437770D01*
X-1610020Y437537D01*
X-1609603Y436953D01*
G01X-1604220Y430770D02*
Y437770D01*
X-1605220Y436370D01*
G01Y430770D02*
X-1603220D01*
G01X-1597420Y430537D02*
X-1597587Y430653D01*
Y430887D01*
X-1597420Y431003D01*
X-1597253Y430887D01*
Y430653D01*
X-1597420Y430537D01*
G01X-1590620Y437770D02*
X-1591287Y437537D01*
X-1591787Y436953D01*
X-1592120Y436253D01*
X-1592370Y435320D01*
X-1592453Y434270D01*
X-1592370Y433220D01*
X-1592120Y432287D01*
X-1591787Y431586D01*
X-1591287Y431003D01*
X-1590620Y430770D01*
X-1589953Y431003D01*
X-1589453Y431586D01*
X-1589120Y432287D01*
X-1588870Y433220D01*
X-1588787Y434270D01*
X-1588870Y435320D01*
X-1589120Y436253D01*
X-1589453Y436953D01*
X-1589953Y437537D01*
X-1590620Y437770D01*
G01X-1583820D02*
X-1584487Y437537D01*
X-1584987Y436953D01*
X-1585320Y436253D01*
X-1585570Y435320D01*
X-1585653Y434270D01*
X-1585570Y433220D01*
X-1585320Y432287D01*
X-1584987Y431586D01*
X-1584487Y431003D01*
X-1583820Y430770D01*
X-1583153Y431003D01*
X-1582653Y431586D01*
X-1582320Y432287D01*
X-1582070Y433220D01*
X-1581987Y434270D01*
X-1582070Y435320D01*
X-1582320Y436253D01*
X-1582653Y436953D01*
X-1583153Y437537D01*
X-1583820Y437770D01*
G01X-1577020D02*
X-1577687Y437537D01*
X-1578187Y436953D01*
X-1578520Y436253D01*
X-1578770Y435320D01*
X-1578853Y434270D01*
X-1578770Y433220D01*
X-1578520Y432287D01*
X-1578187Y431586D01*
X-1577687Y431003D01*
X-1577020Y430770D01*
X-1576353Y431003D01*
X-1575853Y431586D01*
X-1575520Y432287D01*
X-1575270Y433220D01*
X-1575187Y434270D01*
X-1575270Y435320D01*
X-1575520Y436253D01*
X-1575853Y436953D01*
X-1576353Y437537D01*
X-1577020Y437770D01*
G01X-1612853Y455220D02*
X-1612353Y454637D01*
X-1611770Y454287D01*
X-1611020Y454170D01*
X-1610270Y454403D01*
X-1609687Y454870D01*
X-1609270Y455687D01*
X-1609187Y456620D01*
X-1609353Y457553D01*
X-1609770Y458137D01*
X-1610353Y458603D01*
X-1610937Y458720D01*
X-1611520Y458603D01*
X-1612270Y458137D01*
X-1612020Y461170D01*
X-1609770D01*
G01X-1604220D02*
X-1604887Y460937D01*
X-1605387Y460353D01*
X-1605720Y459653D01*
X-1605970Y458720D01*
X-1606053Y457670D01*
X-1605970Y456620D01*
X-1605720Y455687D01*
X-1605387Y454986D01*
X-1604887Y454403D01*
X-1604220Y454170D01*
X-1603553Y454403D01*
X-1603053Y454986D01*
X-1602720Y455687D01*
X-1602470Y456620D01*
X-1602387Y457670D01*
X-1602470Y458720D01*
X-1602720Y459653D01*
X-1603053Y460353D01*
X-1603553Y460937D01*
X-1604220Y461170D01*
G01X-1597420Y453937D02*
X-1597587Y454053D01*
Y454287D01*
X-1597420Y454403D01*
X-1597253Y454287D01*
Y454053D01*
X-1597420Y453937D01*
G01X-1590620Y461170D02*
X-1591287Y460937D01*
X-1591787Y460353D01*
X-1592120Y459653D01*
X-1592370Y458720D01*
X-1592453Y457670D01*
X-1592370Y456620D01*
X-1592120Y455687D01*
X-1591787Y454986D01*
X-1591287Y454403D01*
X-1590620Y454170D01*
X-1589953Y454403D01*
X-1589453Y454986D01*
X-1589120Y455687D01*
X-1588870Y456620D01*
X-1588787Y457670D01*
X-1588870Y458720D01*
X-1589120Y459653D01*
X-1589453Y460353D01*
X-1589953Y460937D01*
X-1590620Y461170D01*
G01X-1583820D02*
X-1584487Y460937D01*
X-1584987Y460353D01*
X-1585320Y459653D01*
X-1585570Y458720D01*
X-1585653Y457670D01*
X-1585570Y456620D01*
X-1585320Y455687D01*
X-1584987Y454986D01*
X-1584487Y454403D01*
X-1583820Y454170D01*
X-1583153Y454403D01*
X-1582653Y454986D01*
X-1582320Y455687D01*
X-1582070Y456620D01*
X-1581987Y457670D01*
X-1582070Y458720D01*
X-1582320Y459653D01*
X-1582653Y460353D01*
X-1583153Y460937D01*
X-1583820Y461170D01*
G01X-1577020D02*
X-1577687Y460937D01*
X-1578187Y460353D01*
X-1578520Y459653D01*
X-1578770Y458720D01*
X-1578853Y457670D01*
X-1578770Y456620D01*
X-1578520Y455687D01*
X-1578187Y454986D01*
X-1577687Y454403D01*
X-1577020Y454170D01*
X-1576353Y454403D01*
X-1575853Y454986D01*
X-1575520Y455687D01*
X-1575270Y456620D01*
X-1575187Y457670D01*
X-1575270Y458720D01*
X-1575520Y459653D01*
X-1575853Y460353D01*
X-1576353Y460937D01*
X-1577020Y461170D01*
G01X-1614420Y477570D02*
Y484570D01*
X-1615420Y483170D01*
G01Y477570D02*
X-1613420D01*
G01X-1609453Y478620D02*
X-1608953Y478037D01*
X-1608370Y477687D01*
X-1607620Y477570D01*
X-1606870Y477803D01*
X-1606287Y478270D01*
X-1605870Y479087D01*
X-1605787Y480020D01*
X-1605953Y480953D01*
X-1606370Y481537D01*
X-1606953Y482003D01*
X-1607537Y482120D01*
X-1608120Y482003D01*
X-1608870Y481537D01*
X-1608620Y484570D01*
X-1606370D01*
G01X-1602403Y480486D02*
X-1601820Y481303D01*
X-1601320Y481770D01*
X-1600653Y482003D01*
X-1600070Y481770D01*
X-1599653Y481303D01*
X-1599320Y480603D01*
X-1599237Y479787D01*
X-1599320Y479087D01*
X-1599653Y478386D01*
X-1600153Y477803D01*
X-1600737Y477570D01*
X-1601403Y477803D01*
X-1601987Y478503D01*
X-1602320Y479553D01*
X-1602403Y480720D01*
X-1602237Y482237D01*
X-1601987Y483053D01*
X-1601570Y483870D01*
X-1600987Y484453D01*
X-1600403Y484570D01*
X-1599820Y484337D01*
X-1599403Y483753D01*
G01X-1594020Y477337D02*
X-1594187Y477453D01*
Y477687D01*
X-1594020Y477803D01*
X-1593853Y477687D01*
Y477453D01*
X-1594020Y477337D01*
G01X-1587220Y484570D02*
X-1587887Y484337D01*
X-1588387Y483753D01*
X-1588720Y483053D01*
X-1588970Y482120D01*
X-1589053Y481070D01*
X-1588970Y480020D01*
X-1588720Y479087D01*
X-1588387Y478386D01*
X-1587887Y477803D01*
X-1587220Y477570D01*
X-1586553Y477803D01*
X-1586053Y478386D01*
X-1585720Y479087D01*
X-1585470Y480020D01*
X-1585387Y481070D01*
X-1585470Y482120D01*
X-1585720Y483053D01*
X-1586053Y483753D01*
X-1586553Y484337D01*
X-1587220Y484570D01*
G01X-1580420D02*
X-1581087Y484337D01*
X-1581587Y483753D01*
X-1581920Y483053D01*
X-1582170Y482120D01*
X-1582253Y481070D01*
X-1582170Y480020D01*
X-1581920Y479087D01*
X-1581587Y478386D01*
X-1581087Y477803D01*
X-1580420Y477570D01*
X-1579753Y477803D01*
X-1579253Y478386D01*
X-1578920Y479087D01*
X-1578670Y480020D01*
X-1578587Y481070D01*
X-1578670Y482120D01*
X-1578920Y483053D01*
X-1579253Y483753D01*
X-1579753Y484337D01*
X-1580420Y484570D01*
G01X-1573620D02*
X-1574287Y484337D01*
X-1574787Y483753D01*
X-1575120Y483053D01*
X-1575370Y482120D01*
X-1575453Y481070D01*
X-1575370Y480020D01*
X-1575120Y479087D01*
X-1574787Y478386D01*
X-1574287Y477803D01*
X-1573620Y477570D01*
X-1572953Y477803D01*
X-1572453Y478386D01*
X-1572120Y479087D01*
X-1571870Y480020D01*
X-1571787Y481070D01*
X-1571870Y482120D01*
X-1572120Y483053D01*
X-1572453Y483753D01*
X-1572953Y484337D01*
X-1573620Y484570D01*
G01X-1614420Y500970D02*
Y507970D01*
X-1615420Y506570D01*
G01Y500970D02*
X-1613420D01*
G01X-1609453Y502370D02*
X-1608953Y501553D01*
X-1608287Y501087D01*
X-1607537Y500970D01*
X-1606870Y501087D01*
X-1606203Y501670D01*
X-1605787Y502370D01*
X-1605703Y503070D01*
X-1605870Y503886D01*
X-1606453Y504470D01*
X-1607037Y504703D01*
X-1607787D01*
G01X-1607037D02*
X-1606537Y505053D01*
X-1606120Y505637D01*
X-1605953Y506337D01*
X-1606120Y507037D01*
X-1606537Y507620D01*
X-1607287Y507970D01*
X-1608037Y507853D01*
X-1608787Y507387D01*
G01X-1600820Y500970D02*
X-1600237Y501087D01*
X-1599570Y501437D01*
X-1599153Y502020D01*
X-1598987Y502837D01*
X-1599153Y503653D01*
X-1599653Y504353D01*
X-1600403Y504703D01*
X-1601237D01*
X-1601737Y504937D01*
X-1602153Y505520D01*
X-1602320Y506337D01*
X-1602070Y507153D01*
X-1601487Y507737D01*
X-1600820Y507970D01*
X-1600153Y507737D01*
X-1599570Y507153D01*
X-1599320Y506337D01*
X-1599487Y505520D01*
X-1599903Y504937D01*
X-1600403Y504703D01*
X-1601237D01*
X-1601987Y504353D01*
X-1602487Y503653D01*
X-1602653Y502837D01*
X-1602487Y502020D01*
X-1602070Y501437D01*
X-1601403Y501087D01*
X-1600820Y500970D01*
G01X-1594020Y500737D02*
X-1594187Y500853D01*
Y501087D01*
X-1594020Y501203D01*
X-1593853Y501087D01*
Y500853D01*
X-1594020Y500737D01*
G01X-1587220Y507970D02*
X-1587887Y507737D01*
X-1588387Y507153D01*
X-1588720Y506453D01*
X-1588970Y505520D01*
X-1589053Y504470D01*
X-1588970Y503420D01*
X-1588720Y502487D01*
X-1588387Y501786D01*
X-1587887Y501203D01*
X-1587220Y500970D01*
X-1586553Y501203D01*
X-1586053Y501786D01*
X-1585720Y502487D01*
X-1585470Y503420D01*
X-1585387Y504470D01*
X-1585470Y505520D01*
X-1585720Y506453D01*
X-1586053Y507153D01*
X-1586553Y507737D01*
X-1587220Y507970D01*
G01X-1580420D02*
X-1581087Y507737D01*
X-1581587Y507153D01*
X-1581920Y506453D01*
X-1582170Y505520D01*
X-1582253Y504470D01*
X-1582170Y503420D01*
X-1581920Y502487D01*
X-1581587Y501786D01*
X-1581087Y501203D01*
X-1580420Y500970D01*
X-1579753Y501203D01*
X-1579253Y501786D01*
X-1578920Y502487D01*
X-1578670Y503420D01*
X-1578587Y504470D01*
X-1578670Y505520D01*
X-1578920Y506453D01*
X-1579253Y507153D01*
X-1579753Y507737D01*
X-1580420Y507970D01*
G01X-1573620D02*
X-1574287Y507737D01*
X-1574787Y507153D01*
X-1575120Y506453D01*
X-1575370Y505520D01*
X-1575453Y504470D01*
X-1575370Y503420D01*
X-1575120Y502487D01*
X-1574787Y501786D01*
X-1574287Y501203D01*
X-1573620Y500970D01*
X-1572953Y501203D01*
X-1572453Y501786D01*
X-1572120Y502487D01*
X-1571870Y503420D01*
X-1571787Y504470D01*
X-1571870Y505520D01*
X-1572120Y506453D01*
X-1572453Y507153D01*
X-1572953Y507737D01*
X-1573620Y507970D01*
G01X-1611020Y524370D02*
X-1610437Y524487D01*
X-1609770Y524837D01*
X-1609353Y525420D01*
X-1609187Y526237D01*
X-1609353Y527053D01*
X-1609853Y527753D01*
X-1610603Y528103D01*
X-1611437D01*
X-1611937Y528337D01*
X-1612353Y528920D01*
X-1612520Y529737D01*
X-1612270Y530553D01*
X-1611687Y531137D01*
X-1611020Y531370D01*
X-1610353Y531137D01*
X-1609770Y530553D01*
X-1609520Y529737D01*
X-1609687Y528920D01*
X-1610103Y528337D01*
X-1610603Y528103D01*
X-1611437D01*
X-1612187Y527753D01*
X-1612687Y527053D01*
X-1612853Y526237D01*
X-1612687Y525420D01*
X-1612270Y524837D01*
X-1611603Y524487D01*
X-1611020Y524370D01*
G01X-1604387D02*
X-1604220Y525887D01*
X-1603970Y527170D01*
X-1603637Y528337D01*
X-1603220Y529620D01*
X-1602553Y531370D01*
X-1605887D01*
G01X-1597420Y524137D02*
X-1597587Y524253D01*
Y524487D01*
X-1597420Y524603D01*
X-1597253Y524487D01*
Y524253D01*
X-1597420Y524137D01*
G01X-1590620Y531370D02*
X-1591287Y531137D01*
X-1591787Y530553D01*
X-1592120Y529853D01*
X-1592370Y528920D01*
X-1592453Y527870D01*
X-1592370Y526820D01*
X-1592120Y525887D01*
X-1591787Y525186D01*
X-1591287Y524603D01*
X-1590620Y524370D01*
X-1589953Y524603D01*
X-1589453Y525186D01*
X-1589120Y525887D01*
X-1588870Y526820D01*
X-1588787Y527870D01*
X-1588870Y528920D01*
X-1589120Y529853D01*
X-1589453Y530553D01*
X-1589953Y531137D01*
X-1590620Y531370D01*
G01X-1583820D02*
X-1584487Y531137D01*
X-1584987Y530553D01*
X-1585320Y529853D01*
X-1585570Y528920D01*
X-1585653Y527870D01*
X-1585570Y526820D01*
X-1585320Y525887D01*
X-1584987Y525186D01*
X-1584487Y524603D01*
X-1583820Y524370D01*
X-1583153Y524603D01*
X-1582653Y525186D01*
X-1582320Y525887D01*
X-1582070Y526820D01*
X-1581987Y527870D01*
X-1582070Y528920D01*
X-1582320Y529853D01*
X-1582653Y530553D01*
X-1583153Y531137D01*
X-1583820Y531370D01*
G01X-1577020D02*
X-1577687Y531137D01*
X-1578187Y530553D01*
X-1578520Y529853D01*
X-1578770Y528920D01*
X-1578853Y527870D01*
X-1578770Y526820D01*
X-1578520Y525887D01*
X-1578187Y525186D01*
X-1577687Y524603D01*
X-1577020Y524370D01*
X-1576353Y524603D01*
X-1575853Y525186D01*
X-1575520Y525887D01*
X-1575270Y526820D01*
X-1575187Y527870D01*
X-1575270Y528920D01*
X-1575520Y529853D01*
X-1575853Y530553D01*
X-1576353Y531137D01*
X-1577020Y531370D01*
G01X-1612853Y548820D02*
X-1612353Y548237D01*
X-1611770Y547887D01*
X-1611020Y547770D01*
X-1610270Y548003D01*
X-1609687Y548470D01*
X-1609270Y549287D01*
X-1609187Y550220D01*
X-1609353Y551153D01*
X-1609770Y551737D01*
X-1610353Y552203D01*
X-1610937Y552320D01*
X-1611520Y552203D01*
X-1612270Y551737D01*
X-1612020Y554770D01*
X-1609770D01*
G01X-1606053Y548820D02*
X-1605553Y548237D01*
X-1604970Y547887D01*
X-1604220Y547770D01*
X-1603470Y548003D01*
X-1602887Y548470D01*
X-1602470Y549287D01*
X-1602387Y550220D01*
X-1602553Y551153D01*
X-1602970Y551737D01*
X-1603553Y552203D01*
X-1604137Y552320D01*
X-1604720Y552203D01*
X-1605470Y551737D01*
X-1605220Y554770D01*
X-1602970D01*
G01X-1597420Y547537D02*
X-1597587Y547653D01*
Y547887D01*
X-1597420Y548003D01*
X-1597253Y547887D01*
Y547653D01*
X-1597420Y547537D01*
G01X-1590620Y554770D02*
X-1591287Y554537D01*
X-1591787Y553953D01*
X-1592120Y553253D01*
X-1592370Y552320D01*
X-1592453Y551270D01*
X-1592370Y550220D01*
X-1592120Y549287D01*
X-1591787Y548586D01*
X-1591287Y548003D01*
X-1590620Y547770D01*
X-1589953Y548003D01*
X-1589453Y548586D01*
X-1589120Y549287D01*
X-1588870Y550220D01*
X-1588787Y551270D01*
X-1588870Y552320D01*
X-1589120Y553253D01*
X-1589453Y553953D01*
X-1589953Y554537D01*
X-1590620Y554770D01*
G01X-1583820D02*
X-1584487Y554537D01*
X-1584987Y553953D01*
X-1585320Y553253D01*
X-1585570Y552320D01*
X-1585653Y551270D01*
X-1585570Y550220D01*
X-1585320Y549287D01*
X-1584987Y548586D01*
X-1584487Y548003D01*
X-1583820Y547770D01*
X-1583153Y548003D01*
X-1582653Y548586D01*
X-1582320Y549287D01*
X-1582070Y550220D01*
X-1581987Y551270D01*
X-1582070Y552320D01*
X-1582320Y553253D01*
X-1582653Y553953D01*
X-1583153Y554537D01*
X-1583820Y554770D01*
G01X-1577020D02*
X-1577687Y554537D01*
X-1578187Y553953D01*
X-1578520Y553253D01*
X-1578770Y552320D01*
X-1578853Y551270D01*
X-1578770Y550220D01*
X-1578520Y549287D01*
X-1578187Y548586D01*
X-1577687Y548003D01*
X-1577020Y547770D01*
X-1576353Y548003D01*
X-1575853Y548586D01*
X-1575520Y549287D01*
X-1575270Y550220D01*
X-1575187Y551270D01*
X-1575270Y552320D01*
X-1575520Y553253D01*
X-1575853Y553953D01*
X-1576353Y554537D01*
X-1577020Y554770D01*
G01X-1610020Y571170D02*
Y578170D01*
X-1613103Y573153D01*
X-1608937D01*
G01X-1604220Y571170D02*
Y578170D01*
X-1605220Y576770D01*
G01Y571170D02*
X-1603220D01*
G01X-1597420Y570937D02*
X-1597587Y571053D01*
Y571287D01*
X-1597420Y571403D01*
X-1597253Y571287D01*
Y571053D01*
X-1597420Y570937D01*
G01X-1590620Y578170D02*
X-1591287Y577937D01*
X-1591787Y577353D01*
X-1592120Y576653D01*
X-1592370Y575720D01*
X-1592453Y574670D01*
X-1592370Y573620D01*
X-1592120Y572687D01*
X-1591787Y571986D01*
X-1591287Y571403D01*
X-1590620Y571170D01*
X-1589953Y571403D01*
X-1589453Y571986D01*
X-1589120Y572687D01*
X-1588870Y573620D01*
X-1588787Y574670D01*
X-1588870Y575720D01*
X-1589120Y576653D01*
X-1589453Y577353D01*
X-1589953Y577937D01*
X-1590620Y578170D01*
G01X-1583820D02*
X-1584487Y577937D01*
X-1584987Y577353D01*
X-1585320Y576653D01*
X-1585570Y575720D01*
X-1585653Y574670D01*
X-1585570Y573620D01*
X-1585320Y572687D01*
X-1584987Y571986D01*
X-1584487Y571403D01*
X-1583820Y571170D01*
X-1583153Y571403D01*
X-1582653Y571986D01*
X-1582320Y572687D01*
X-1582070Y573620D01*
X-1581987Y574670D01*
X-1582070Y575720D01*
X-1582320Y576653D01*
X-1582653Y577353D01*
X-1583153Y577937D01*
X-1583820Y578170D01*
G01X-1577020D02*
X-1577687Y577937D01*
X-1578187Y577353D01*
X-1578520Y576653D01*
X-1578770Y575720D01*
X-1578853Y574670D01*
X-1578770Y573620D01*
X-1578520Y572687D01*
X-1578187Y571986D01*
X-1577687Y571403D01*
X-1577020Y571170D01*
X-1576353Y571403D01*
X-1575853Y571986D01*
X-1575520Y572687D01*
X-1575270Y573620D01*
X-1575187Y574670D01*
X-1575270Y575720D01*
X-1575520Y576653D01*
X-1575853Y577353D01*
X-1576353Y577937D01*
X-1577020Y578170D01*
G01X-1610020Y594570D02*
Y601570D01*
X-1613103Y596553D01*
X-1608937D01*
G01X-1604220Y601570D02*
X-1604887Y601337D01*
X-1605387Y600753D01*
X-1605720Y600053D01*
X-1605970Y599120D01*
X-1606053Y598070D01*
X-1605970Y597020D01*
X-1605720Y596087D01*
X-1605387Y595386D01*
X-1604887Y594803D01*
X-1604220Y594570D01*
X-1603553Y594803D01*
X-1603053Y595386D01*
X-1602720Y596087D01*
X-1602470Y597020D01*
X-1602387Y598070D01*
X-1602470Y599120D01*
X-1602720Y600053D01*
X-1603053Y600753D01*
X-1603553Y601337D01*
X-1604220Y601570D01*
G01X-1597420Y594337D02*
X-1597587Y594453D01*
Y594687D01*
X-1597420Y594803D01*
X-1597253Y594687D01*
Y594453D01*
X-1597420Y594337D01*
G01X-1590620Y601570D02*
X-1591287Y601337D01*
X-1591787Y600753D01*
X-1592120Y600053D01*
X-1592370Y599120D01*
X-1592453Y598070D01*
X-1592370Y597020D01*
X-1592120Y596087D01*
X-1591787Y595386D01*
X-1591287Y594803D01*
X-1590620Y594570D01*
X-1589953Y594803D01*
X-1589453Y595386D01*
X-1589120Y596087D01*
X-1588870Y597020D01*
X-1588787Y598070D01*
X-1588870Y599120D01*
X-1589120Y600053D01*
X-1589453Y600753D01*
X-1589953Y601337D01*
X-1590620Y601570D01*
G01X-1583820D02*
X-1584487Y601337D01*
X-1584987Y600753D01*
X-1585320Y600053D01*
X-1585570Y599120D01*
X-1585653Y598070D01*
X-1585570Y597020D01*
X-1585320Y596087D01*
X-1584987Y595386D01*
X-1584487Y594803D01*
X-1583820Y594570D01*
X-1583153Y594803D01*
X-1582653Y595386D01*
X-1582320Y596087D01*
X-1582070Y597020D01*
X-1581987Y598070D01*
X-1582070Y599120D01*
X-1582320Y600053D01*
X-1582653Y600753D01*
X-1583153Y601337D01*
X-1583820Y601570D01*
G01X-1577020D02*
X-1577687Y601337D01*
X-1578187Y600753D01*
X-1578520Y600053D01*
X-1578770Y599120D01*
X-1578853Y598070D01*
X-1578770Y597020D01*
X-1578520Y596087D01*
X-1578187Y595386D01*
X-1577687Y594803D01*
X-1577020Y594570D01*
X-1576353Y594803D01*
X-1575853Y595386D01*
X-1575520Y596087D01*
X-1575270Y597020D01*
X-1575187Y598070D01*
X-1575270Y599120D01*
X-1575520Y600053D01*
X-1575853Y600753D01*
X-1576353Y601337D01*
X-1577020Y601570D01*
G01X-1612853Y619370D02*
X-1612353Y618553D01*
X-1611687Y618087D01*
X-1610937Y617970D01*
X-1610270Y618087D01*
X-1609603Y618670D01*
X-1609187Y619370D01*
X-1609103Y620070D01*
X-1609270Y620886D01*
X-1609853Y621470D01*
X-1610437Y621703D01*
X-1611187D01*
G01X-1610437D02*
X-1609937Y622053D01*
X-1609520Y622637D01*
X-1609353Y623337D01*
X-1609520Y624037D01*
X-1609937Y624620D01*
X-1610687Y624970D01*
X-1611437Y624853D01*
X-1612187Y624387D01*
G01X-1604220Y617970D02*
X-1603637Y618087D01*
X-1602970Y618437D01*
X-1602553Y619020D01*
X-1602387Y619837D01*
X-1602553Y620653D01*
X-1603053Y621353D01*
X-1603803Y621703D01*
X-1604637D01*
X-1605137Y621937D01*
X-1605553Y622520D01*
X-1605720Y623337D01*
X-1605470Y624153D01*
X-1604887Y624737D01*
X-1604220Y624970D01*
X-1603553Y624737D01*
X-1602970Y624153D01*
X-1602720Y623337D01*
X-1602887Y622520D01*
X-1603303Y621937D01*
X-1603803Y621703D01*
X-1604637D01*
X-1605387Y621353D01*
X-1605887Y620653D01*
X-1606053Y619837D01*
X-1605887Y619020D01*
X-1605470Y618437D01*
X-1604803Y618087D01*
X-1604220Y617970D01*
G01X-1597420Y617737D02*
X-1597587Y617853D01*
Y618087D01*
X-1597420Y618203D01*
X-1597253Y618087D01*
Y617853D01*
X-1597420Y617737D01*
G01X-1590620Y624970D02*
X-1591287Y624737D01*
X-1591787Y624153D01*
X-1592120Y623453D01*
X-1592370Y622520D01*
X-1592453Y621470D01*
X-1592370Y620420D01*
X-1592120Y619487D01*
X-1591787Y618786D01*
X-1591287Y618203D01*
X-1590620Y617970D01*
X-1589953Y618203D01*
X-1589453Y618786D01*
X-1589120Y619487D01*
X-1588870Y620420D01*
X-1588787Y621470D01*
X-1588870Y622520D01*
X-1589120Y623453D01*
X-1589453Y624153D01*
X-1589953Y624737D01*
X-1590620Y624970D01*
G01X-1583820D02*
X-1584487Y624737D01*
X-1584987Y624153D01*
X-1585320Y623453D01*
X-1585570Y622520D01*
X-1585653Y621470D01*
X-1585570Y620420D01*
X-1585320Y619487D01*
X-1584987Y618786D01*
X-1584487Y618203D01*
X-1583820Y617970D01*
X-1583153Y618203D01*
X-1582653Y618786D01*
X-1582320Y619487D01*
X-1582070Y620420D01*
X-1581987Y621470D01*
X-1582070Y622520D01*
X-1582320Y623453D01*
X-1582653Y624153D01*
X-1583153Y624737D01*
X-1583820Y624970D01*
G01X-1577020D02*
X-1577687Y624737D01*
X-1578187Y624153D01*
X-1578520Y623453D01*
X-1578770Y622520D01*
X-1578853Y621470D01*
X-1578770Y620420D01*
X-1578520Y619487D01*
X-1578187Y618786D01*
X-1577687Y618203D01*
X-1577020Y617970D01*
X-1576353Y618203D01*
X-1575853Y618786D01*
X-1575520Y619487D01*
X-1575270Y620420D01*
X-1575187Y621470D01*
X-1575270Y622520D01*
X-1575520Y623453D01*
X-1575853Y624153D01*
X-1576353Y624737D01*
X-1577020Y624970D01*
G01X-1612853Y642770D02*
X-1612353Y641953D01*
X-1611687Y641487D01*
X-1610937Y641370D01*
X-1610270Y641487D01*
X-1609603Y642070D01*
X-1609187Y642770D01*
X-1609103Y643470D01*
X-1609270Y644286D01*
X-1609853Y644870D01*
X-1610437Y645103D01*
X-1611187D01*
G01X-1610437D02*
X-1609937Y645453D01*
X-1609520Y646037D01*
X-1609353Y646737D01*
X-1609520Y647437D01*
X-1609937Y648020D01*
X-1610687Y648370D01*
X-1611437Y648253D01*
X-1612187Y647787D01*
G01X-1606053Y642770D02*
X-1605553Y641953D01*
X-1604887Y641487D01*
X-1604137Y641370D01*
X-1603470Y641487D01*
X-1602803Y642070D01*
X-1602387Y642770D01*
X-1602303Y643470D01*
X-1602470Y644286D01*
X-1603053Y644870D01*
X-1603637Y645103D01*
X-1604387D01*
G01X-1603637D02*
X-1603137Y645453D01*
X-1602720Y646037D01*
X-1602553Y646737D01*
X-1602720Y647437D01*
X-1603137Y648020D01*
X-1603887Y648370D01*
X-1604637Y648253D01*
X-1605387Y647787D01*
G01X-1597420Y641137D02*
X-1597587Y641253D01*
Y641487D01*
X-1597420Y641603D01*
X-1597253Y641487D01*
Y641253D01*
X-1597420Y641137D01*
G01X-1590620Y648370D02*
X-1591287Y648137D01*
X-1591787Y647553D01*
X-1592120Y646853D01*
X-1592370Y645920D01*
X-1592453Y644870D01*
X-1592370Y643820D01*
X-1592120Y642887D01*
X-1591787Y642186D01*
X-1591287Y641603D01*
X-1590620Y641370D01*
X-1589953Y641603D01*
X-1589453Y642186D01*
X-1589120Y642887D01*
X-1588870Y643820D01*
X-1588787Y644870D01*
X-1588870Y645920D01*
X-1589120Y646853D01*
X-1589453Y647553D01*
X-1589953Y648137D01*
X-1590620Y648370D01*
G01X-1583820D02*
X-1584487Y648137D01*
X-1584987Y647553D01*
X-1585320Y646853D01*
X-1585570Y645920D01*
X-1585653Y644870D01*
X-1585570Y643820D01*
X-1585320Y642887D01*
X-1584987Y642186D01*
X-1584487Y641603D01*
X-1583820Y641370D01*
X-1583153Y641603D01*
X-1582653Y642186D01*
X-1582320Y642887D01*
X-1582070Y643820D01*
X-1581987Y644870D01*
X-1582070Y645920D01*
X-1582320Y646853D01*
X-1582653Y647553D01*
X-1583153Y648137D01*
X-1583820Y648370D01*
G01X-1577020D02*
X-1577687Y648137D01*
X-1578187Y647553D01*
X-1578520Y646853D01*
X-1578770Y645920D01*
X-1578853Y644870D01*
X-1578770Y643820D01*
X-1578520Y642887D01*
X-1578187Y642186D01*
X-1577687Y641603D01*
X-1577020Y641370D01*
X-1576353Y641603D01*
X-1575853Y642186D01*
X-1575520Y642887D01*
X-1575270Y643820D01*
X-1575187Y644870D01*
X-1575270Y645920D01*
X-1575520Y646853D01*
X-1575853Y647553D01*
X-1576353Y648137D01*
X-1577020Y648370D01*
G01X-1612853Y666170D02*
X-1612353Y665353D01*
X-1611687Y664887D01*
X-1610937Y664770D01*
X-1610270Y664887D01*
X-1609603Y665470D01*
X-1609187Y666170D01*
X-1609103Y666870D01*
X-1609270Y667686D01*
X-1609853Y668270D01*
X-1610437Y668503D01*
X-1611187D01*
G01X-1610437D02*
X-1609937Y668853D01*
X-1609520Y669437D01*
X-1609353Y670137D01*
X-1609520Y670837D01*
X-1609937Y671420D01*
X-1610687Y671770D01*
X-1611437Y671653D01*
X-1612187Y671187D01*
G01X-1604220Y671770D02*
X-1604887Y671537D01*
X-1605387Y670953D01*
X-1605720Y670253D01*
X-1605970Y669320D01*
X-1606053Y668270D01*
X-1605970Y667220D01*
X-1605720Y666287D01*
X-1605387Y665586D01*
X-1604887Y665003D01*
X-1604220Y664770D01*
X-1603553Y665003D01*
X-1603053Y665586D01*
X-1602720Y666287D01*
X-1602470Y667220D01*
X-1602387Y668270D01*
X-1602470Y669320D01*
X-1602720Y670253D01*
X-1603053Y670953D01*
X-1603553Y671537D01*
X-1604220Y671770D01*
G01X-1597420Y664537D02*
X-1597587Y664653D01*
Y664887D01*
X-1597420Y665003D01*
X-1597253Y664887D01*
Y664653D01*
X-1597420Y664537D01*
G01X-1590620Y671770D02*
X-1591287Y671537D01*
X-1591787Y670953D01*
X-1592120Y670253D01*
X-1592370Y669320D01*
X-1592453Y668270D01*
X-1592370Y667220D01*
X-1592120Y666287D01*
X-1591787Y665586D01*
X-1591287Y665003D01*
X-1590620Y664770D01*
X-1589953Y665003D01*
X-1589453Y665586D01*
X-1589120Y666287D01*
X-1588870Y667220D01*
X-1588787Y668270D01*
X-1588870Y669320D01*
X-1589120Y670253D01*
X-1589453Y670953D01*
X-1589953Y671537D01*
X-1590620Y671770D01*
G01X-1583820D02*
X-1584487Y671537D01*
X-1584987Y670953D01*
X-1585320Y670253D01*
X-1585570Y669320D01*
X-1585653Y668270D01*
X-1585570Y667220D01*
X-1585320Y666287D01*
X-1584987Y665586D01*
X-1584487Y665003D01*
X-1583820Y664770D01*
X-1583153Y665003D01*
X-1582653Y665586D01*
X-1582320Y666287D01*
X-1582070Y667220D01*
X-1581987Y668270D01*
X-1582070Y669320D01*
X-1582320Y670253D01*
X-1582653Y670953D01*
X-1583153Y671537D01*
X-1583820Y671770D01*
G01X-1577020D02*
X-1577687Y671537D01*
X-1578187Y670953D01*
X-1578520Y670253D01*
X-1578770Y669320D01*
X-1578853Y668270D01*
X-1578770Y667220D01*
X-1578520Y666287D01*
X-1578187Y665586D01*
X-1577687Y665003D01*
X-1577020Y664770D01*
X-1576353Y665003D01*
X-1575853Y665586D01*
X-1575520Y666287D01*
X-1575270Y667220D01*
X-1575187Y668270D01*
X-1575270Y669320D01*
X-1575520Y670253D01*
X-1575853Y670953D01*
X-1576353Y671537D01*
X-1577020Y671770D01*
G01X-1612603Y694003D02*
X-1612103Y694703D01*
X-1611520Y695053D01*
X-1610853Y695170D01*
X-1610020Y694937D01*
X-1609437Y694353D01*
X-1609270Y693653D01*
X-1609353Y692953D01*
X-1609687Y692370D01*
X-1611353Y691203D01*
X-1612103Y690387D01*
X-1612603Y689220D01*
X-1612770Y688170D01*
X-1609270D01*
G01X-1603220D02*
Y695170D01*
X-1606303Y690153D01*
X-1602137D01*
G01X-1597420Y687937D02*
X-1597587Y688053D01*
Y688287D01*
X-1597420Y688403D01*
X-1597253Y688287D01*
Y688053D01*
X-1597420Y687937D01*
G01X-1590620Y695170D02*
X-1591287Y694937D01*
X-1591787Y694353D01*
X-1592120Y693653D01*
X-1592370Y692720D01*
X-1592453Y691670D01*
X-1592370Y690620D01*
X-1592120Y689687D01*
X-1591787Y688986D01*
X-1591287Y688403D01*
X-1590620Y688170D01*
X-1589953Y688403D01*
X-1589453Y688986D01*
X-1589120Y689687D01*
X-1588870Y690620D01*
X-1588787Y691670D01*
X-1588870Y692720D01*
X-1589120Y693653D01*
X-1589453Y694353D01*
X-1589953Y694937D01*
X-1590620Y695170D01*
G01X-1583820D02*
X-1584487Y694937D01*
X-1584987Y694353D01*
X-1585320Y693653D01*
X-1585570Y692720D01*
X-1585653Y691670D01*
X-1585570Y690620D01*
X-1585320Y689687D01*
X-1584987Y688986D01*
X-1584487Y688403D01*
X-1583820Y688170D01*
X-1583153Y688403D01*
X-1582653Y688986D01*
X-1582320Y689687D01*
X-1582070Y690620D01*
X-1581987Y691670D01*
X-1582070Y692720D01*
X-1582320Y693653D01*
X-1582653Y694353D01*
X-1583153Y694937D01*
X-1583820Y695170D01*
G01X-1577020D02*
X-1577687Y694937D01*
X-1578187Y694353D01*
X-1578520Y693653D01*
X-1578770Y692720D01*
X-1578853Y691670D01*
X-1578770Y690620D01*
X-1578520Y689687D01*
X-1578187Y688986D01*
X-1577687Y688403D01*
X-1577020Y688170D01*
X-1576353Y688403D01*
X-1575853Y688986D01*
X-1575520Y689687D01*
X-1575270Y690620D01*
X-1575187Y691670D01*
X-1575270Y692720D01*
X-1575520Y693653D01*
X-1575853Y694353D01*
X-1576353Y694937D01*
X-1577020Y695170D01*
G01X-1612603Y717403D02*
X-1612103Y718103D01*
X-1611520Y718453D01*
X-1610853Y718570D01*
X-1610020Y718337D01*
X-1609437Y717753D01*
X-1609270Y717053D01*
X-1609353Y716353D01*
X-1609687Y715770D01*
X-1611353Y714603D01*
X-1612103Y713787D01*
X-1612603Y712620D01*
X-1612770Y711570D01*
X-1609270D01*
G01X-1604220Y718570D02*
X-1604887Y718337D01*
X-1605387Y717753D01*
X-1605720Y717053D01*
X-1605970Y716120D01*
X-1606053Y715070D01*
X-1605970Y714020D01*
X-1605720Y713087D01*
X-1605387Y712386D01*
X-1604887Y711803D01*
X-1604220Y711570D01*
X-1603553Y711803D01*
X-1603053Y712386D01*
X-1602720Y713087D01*
X-1602470Y714020D01*
X-1602387Y715070D01*
X-1602470Y716120D01*
X-1602720Y717053D01*
X-1603053Y717753D01*
X-1603553Y718337D01*
X-1604220Y718570D01*
G01X-1597420Y711337D02*
X-1597587Y711453D01*
Y711687D01*
X-1597420Y711803D01*
X-1597253Y711687D01*
Y711453D01*
X-1597420Y711337D01*
G01X-1590620Y718570D02*
X-1591287Y718337D01*
X-1591787Y717753D01*
X-1592120Y717053D01*
X-1592370Y716120D01*
X-1592453Y715070D01*
X-1592370Y714020D01*
X-1592120Y713087D01*
X-1591787Y712386D01*
X-1591287Y711803D01*
X-1590620Y711570D01*
X-1589953Y711803D01*
X-1589453Y712386D01*
X-1589120Y713087D01*
X-1588870Y714020D01*
X-1588787Y715070D01*
X-1588870Y716120D01*
X-1589120Y717053D01*
X-1589453Y717753D01*
X-1589953Y718337D01*
X-1590620Y718570D01*
G01X-1583820D02*
X-1584487Y718337D01*
X-1584987Y717753D01*
X-1585320Y717053D01*
X-1585570Y716120D01*
X-1585653Y715070D01*
X-1585570Y714020D01*
X-1585320Y713087D01*
X-1584987Y712386D01*
X-1584487Y711803D01*
X-1583820Y711570D01*
X-1583153Y711803D01*
X-1582653Y712386D01*
X-1582320Y713087D01*
X-1582070Y714020D01*
X-1581987Y715070D01*
X-1582070Y716120D01*
X-1582320Y717053D01*
X-1582653Y717753D01*
X-1583153Y718337D01*
X-1583820Y718570D01*
G01X-1577020D02*
X-1577687Y718337D01*
X-1578187Y717753D01*
X-1578520Y717053D01*
X-1578770Y716120D01*
X-1578853Y715070D01*
X-1578770Y714020D01*
X-1578520Y713087D01*
X-1578187Y712386D01*
X-1577687Y711803D01*
X-1577020Y711570D01*
X-1576353Y711803D01*
X-1575853Y712386D01*
X-1575520Y713087D01*
X-1575270Y714020D01*
X-1575187Y715070D01*
X-1575270Y716120D01*
X-1575520Y717053D01*
X-1575853Y717753D01*
X-1576353Y718337D01*
X-1577020Y718570D01*
G01X-1611020Y734970D02*
Y741970D01*
X-1612020Y740570D01*
G01Y734970D02*
X-1610020D01*
G01X-1606053Y736020D02*
X-1605553Y735437D01*
X-1604970Y735087D01*
X-1604220Y734970D01*
X-1603470Y735203D01*
X-1602887Y735670D01*
X-1602470Y736487D01*
X-1602387Y737420D01*
X-1602553Y738353D01*
X-1602970Y738937D01*
X-1603553Y739403D01*
X-1604137Y739520D01*
X-1604720Y739403D01*
X-1605470Y738937D01*
X-1605220Y741970D01*
X-1602970D01*
G01X-1597420Y734737D02*
X-1597587Y734853D01*
Y735087D01*
X-1597420Y735203D01*
X-1597253Y735087D01*
Y734853D01*
X-1597420Y734737D01*
G01X-1590620Y741970D02*
X-1591287Y741737D01*
X-1591787Y741153D01*
X-1592120Y740453D01*
X-1592370Y739520D01*
X-1592453Y738470D01*
X-1592370Y737420D01*
X-1592120Y736487D01*
X-1591787Y735786D01*
X-1591287Y735203D01*
X-1590620Y734970D01*
X-1589953Y735203D01*
X-1589453Y735786D01*
X-1589120Y736487D01*
X-1588870Y737420D01*
X-1588787Y738470D01*
X-1588870Y739520D01*
X-1589120Y740453D01*
X-1589453Y741153D01*
X-1589953Y741737D01*
X-1590620Y741970D01*
G01X-1583820D02*
X-1584487Y741737D01*
X-1584987Y741153D01*
X-1585320Y740453D01*
X-1585570Y739520D01*
X-1585653Y738470D01*
X-1585570Y737420D01*
X-1585320Y736487D01*
X-1584987Y735786D01*
X-1584487Y735203D01*
X-1583820Y734970D01*
X-1583153Y735203D01*
X-1582653Y735786D01*
X-1582320Y736487D01*
X-1582070Y737420D01*
X-1581987Y738470D01*
X-1582070Y739520D01*
X-1582320Y740453D01*
X-1582653Y741153D01*
X-1583153Y741737D01*
X-1583820Y741970D01*
G01X-1577020D02*
X-1577687Y741737D01*
X-1578187Y741153D01*
X-1578520Y740453D01*
X-1578770Y739520D01*
X-1578853Y738470D01*
X-1578770Y737420D01*
X-1578520Y736487D01*
X-1578187Y735786D01*
X-1577687Y735203D01*
X-1577020Y734970D01*
X-1576353Y735203D01*
X-1575853Y735786D01*
X-1575520Y736487D01*
X-1575270Y737420D01*
X-1575187Y738470D01*
X-1575270Y739520D01*
X-1575520Y740453D01*
X-1575853Y741153D01*
X-1576353Y741737D01*
X-1577020Y741970D01*
G01X-1611020Y758370D02*
Y765370D01*
X-1612020Y763970D01*
G01Y758370D02*
X-1610020D01*
G01X-1603220D02*
Y765370D01*
X-1606303Y760353D01*
X-1602137D01*
G01X-1597420Y758137D02*
X-1597587Y758253D01*
Y758487D01*
X-1597420Y758603D01*
X-1597253Y758487D01*
Y758253D01*
X-1597420Y758137D01*
G01X-1590620Y765370D02*
X-1591287Y765137D01*
X-1591787Y764553D01*
X-1592120Y763853D01*
X-1592370Y762920D01*
X-1592453Y761870D01*
X-1592370Y760820D01*
X-1592120Y759887D01*
X-1591787Y759186D01*
X-1591287Y758603D01*
X-1590620Y758370D01*
X-1589953Y758603D01*
X-1589453Y759186D01*
X-1589120Y759887D01*
X-1588870Y760820D01*
X-1588787Y761870D01*
X-1588870Y762920D01*
X-1589120Y763853D01*
X-1589453Y764553D01*
X-1589953Y765137D01*
X-1590620Y765370D01*
G01X-1583820D02*
X-1584487Y765137D01*
X-1584987Y764553D01*
X-1585320Y763853D01*
X-1585570Y762920D01*
X-1585653Y761870D01*
X-1585570Y760820D01*
X-1585320Y759887D01*
X-1584987Y759186D01*
X-1584487Y758603D01*
X-1583820Y758370D01*
X-1583153Y758603D01*
X-1582653Y759186D01*
X-1582320Y759887D01*
X-1582070Y760820D01*
X-1581987Y761870D01*
X-1582070Y762920D01*
X-1582320Y763853D01*
X-1582653Y764553D01*
X-1583153Y765137D01*
X-1583820Y765370D01*
G01X-1577020D02*
X-1577687Y765137D01*
X-1578187Y764553D01*
X-1578520Y763853D01*
X-1578770Y762920D01*
X-1578853Y761870D01*
X-1578770Y760820D01*
X-1578520Y759887D01*
X-1578187Y759186D01*
X-1577687Y758603D01*
X-1577020Y758370D01*
X-1576353Y758603D01*
X-1575853Y759186D01*
X-1575520Y759887D01*
X-1575270Y760820D01*
X-1575187Y761870D01*
X-1575270Y762920D01*
X-1575520Y763853D01*
X-1575853Y764553D01*
X-1576353Y765137D01*
X-1577020Y765370D01*
G01X-1611020Y781770D02*
Y788770D01*
X-1612020Y787370D01*
G01Y781770D02*
X-1610020D01*
G01X-1604220Y788770D02*
X-1604887Y788537D01*
X-1605387Y787953D01*
X-1605720Y787253D01*
X-1605970Y786320D01*
X-1606053Y785270D01*
X-1605970Y784220D01*
X-1605720Y783287D01*
X-1605387Y782586D01*
X-1604887Y782003D01*
X-1604220Y781770D01*
X-1603553Y782003D01*
X-1603053Y782586D01*
X-1602720Y783287D01*
X-1602470Y784220D01*
X-1602387Y785270D01*
X-1602470Y786320D01*
X-1602720Y787253D01*
X-1603053Y787953D01*
X-1603553Y788537D01*
X-1604220Y788770D01*
G01X-1597420Y781537D02*
X-1597587Y781653D01*
Y781887D01*
X-1597420Y782003D01*
X-1597253Y781887D01*
Y781653D01*
X-1597420Y781537D01*
G01X-1590620Y788770D02*
X-1591287Y788537D01*
X-1591787Y787953D01*
X-1592120Y787253D01*
X-1592370Y786320D01*
X-1592453Y785270D01*
X-1592370Y784220D01*
X-1592120Y783287D01*
X-1591787Y782586D01*
X-1591287Y782003D01*
X-1590620Y781770D01*
X-1589953Y782003D01*
X-1589453Y782586D01*
X-1589120Y783287D01*
X-1588870Y784220D01*
X-1588787Y785270D01*
X-1588870Y786320D01*
X-1589120Y787253D01*
X-1589453Y787953D01*
X-1589953Y788537D01*
X-1590620Y788770D01*
G01X-1583820D02*
X-1584487Y788537D01*
X-1584987Y787953D01*
X-1585320Y787253D01*
X-1585570Y786320D01*
X-1585653Y785270D01*
X-1585570Y784220D01*
X-1585320Y783287D01*
X-1584987Y782586D01*
X-1584487Y782003D01*
X-1583820Y781770D01*
X-1583153Y782003D01*
X-1582653Y782586D01*
X-1582320Y783287D01*
X-1582070Y784220D01*
X-1581987Y785270D01*
X-1582070Y786320D01*
X-1582320Y787253D01*
X-1582653Y787953D01*
X-1583153Y788537D01*
X-1583820Y788770D01*
G01X-1577020D02*
X-1577687Y788537D01*
X-1578187Y787953D01*
X-1578520Y787253D01*
X-1578770Y786320D01*
X-1578853Y785270D01*
X-1578770Y784220D01*
X-1578520Y783287D01*
X-1578187Y782586D01*
X-1577687Y782003D01*
X-1577020Y781770D01*
X-1576353Y782003D01*
X-1575853Y782586D01*
X-1575520Y783287D01*
X-1575270Y784220D01*
X-1575187Y785270D01*
X-1575270Y786320D01*
X-1575520Y787253D01*
X-1575853Y787953D01*
X-1576353Y788537D01*
X-1577020Y788770D01*
G01X-1599694Y-256567D02*
X-1606694D01*
X-1601677Y-259650D01*
Y-255484D01*
G01X-1599694Y-250767D02*
X-1606694D01*
X-1605294Y-251767D01*
G01X-1599694D02*
Y-249767D01*
G01Y-244134D02*
X-1601211Y-243967D01*
X-1602494Y-243717D01*
X-1603661Y-243384D01*
X-1604944Y-242967D01*
X-1606694Y-242300D01*
Y-245634D01*
G01X-1599461Y-237167D02*
X-1599577Y-237334D01*
X-1599811D01*
X-1599927Y-237167D01*
X-1599811Y-237000D01*
X-1599577D01*
X-1599461Y-237167D01*
G01X-1599694Y-229367D02*
X-1606694D01*
X-1601677Y-232450D01*
Y-228284D01*
G01X-1602610Y-225150D02*
X-1603427Y-224567D01*
X-1603894Y-224067D01*
X-1604127Y-223400D01*
X-1603894Y-222817D01*
X-1603427Y-222400D01*
X-1602727Y-222067D01*
X-1601911Y-221984D01*
X-1601211Y-222067D01*
X-1600510Y-222400D01*
X-1599927Y-222900D01*
X-1599694Y-223484D01*
X-1599927Y-224150D01*
X-1600627Y-224734D01*
X-1601677Y-225067D01*
X-1602844Y-225150D01*
X-1604361Y-224984D01*
X-1605177Y-224734D01*
X-1605994Y-224317D01*
X-1606577Y-223734D01*
X-1606694Y-223150D01*
X-1606461Y-222567D01*
X-1605877Y-222150D01*
G01X-1594103Y88809D02*
X-1601103D01*
X-1596086Y85726D01*
Y89892D01*
G01X-1594103Y94609D02*
X-1601103D01*
X-1599703Y93609D01*
G01X-1594103D02*
Y95609D01*
G01Y101409D02*
X-1601103D01*
X-1599703Y100409D01*
G01X-1594103D02*
Y102409D01*
G01X-1593870Y108209D02*
X-1593986Y108042D01*
X-1594220D01*
X-1594336Y108209D01*
X-1594220Y108376D01*
X-1593986D01*
X-1593870Y108209D01*
G01X-1595503Y113176D02*
X-1594686Y113676D01*
X-1594220Y114342D01*
X-1594103Y115092D01*
X-1594220Y115759D01*
X-1594803Y116426D01*
X-1595503Y116842D01*
X-1596203Y116926D01*
X-1597019Y116759D01*
X-1597603Y116176D01*
X-1597836Y115592D01*
Y114842D01*
G01Y115592D02*
X-1598186Y116092D01*
X-1598770Y116509D01*
X-1599470Y116676D01*
X-1600170Y116509D01*
X-1600753Y116092D01*
X-1601103Y115342D01*
X-1600986Y114592D01*
X-1600520Y113842D01*
G01X-1594103Y121809D02*
X-1601103D01*
X-1599703Y120809D01*
G01X-1594103D02*
Y122809D01*
G01X-1605970Y804903D02*
X-1605303Y804320D01*
X-1604553Y803970D01*
X-1603887D01*
X-1603220Y804320D01*
X-1602720Y804903D01*
X-1602470Y805720D01*
X-1602637Y806537D01*
X-1603053Y807237D01*
X-1603803Y807703D01*
X-1604803Y807937D01*
X-1605387Y808403D01*
X-1605637Y809220D01*
X-1605470Y810037D01*
X-1605053Y810620D01*
X-1604470Y810970D01*
X-1603887D01*
X-1603303Y810737D01*
X-1602803Y810153D01*
G01X-1598420Y810970D02*
X-1596420D01*
G01X-1597420D02*
Y803970D01*
G01X-1598420D02*
X-1596420D01*
G01X-1592203Y810970D02*
X-1589037D01*
X-1592203Y803970D01*
X-1589037D01*
G01X-1582153D02*
X-1585487D01*
Y810970D01*
X-1582153D01*
G01X-1583487Y807587D02*
X-1585487D01*
G01X-1590653Y846470D02*
Y853470D01*
X-1588987D01*
X-1588320Y853120D01*
X-1587820Y852653D01*
X-1587403Y851953D01*
X-1587070Y851137D01*
X-1586987Y849970D01*
X-1587070Y848803D01*
X-1587403Y847987D01*
X-1587820Y847286D01*
X-1588320Y846820D01*
X-1588987Y846470D01*
X-1590653D01*
G01X-1583687D02*
Y853470D01*
X-1581603D01*
X-1580937Y853120D01*
X-1580520Y852653D01*
X-1580353Y851720D01*
X-1580520Y850787D01*
X-1581020Y850203D01*
X-1581603Y849853D01*
X-1583687D01*
G01X-1581603D02*
X-1580353Y846470D01*
G01X-1576220Y853470D02*
X-1574220D01*
G01X-1575220D02*
Y846470D01*
G01X-1576220D02*
X-1574220D01*
G01X-1570087Y853470D02*
Y846470D01*
X-1566753D01*
G01X-1563287Y853470D02*
Y846470D01*
X-1559953D01*
G01X-1546187Y852887D02*
X-1546687Y853237D01*
X-1547270Y853470D01*
X-1547937D01*
X-1548687Y853120D01*
X-1549270Y852537D01*
X-1549687Y851837D01*
X-1550020Y850670D01*
X-1550103Y849620D01*
X-1549937Y848570D01*
X-1549687Y847870D01*
X-1549187Y847170D01*
X-1548603Y846703D01*
X-1548020Y846470D01*
X-1547437D01*
X-1546853Y846703D01*
X-1546353Y847053D01*
X-1545937Y847520D01*
G01X-1542970Y846470D02*
Y853470D01*
G01X-1539470D02*
Y846470D01*
G01Y849970D02*
X-1542970D01*
G01X-1536503Y846470D02*
X-1534420Y853470D01*
X-1532337Y846470D01*
G01X-1533087Y848920D02*
X-1535753D01*
G01X-1529287Y846470D02*
Y853470D01*
X-1527203D01*
X-1526537Y853120D01*
X-1526120Y852653D01*
X-1525953Y851720D01*
X-1526120Y850787D01*
X-1526620Y850203D01*
X-1527203Y849853D01*
X-1529287D01*
G01X-1527203D02*
X-1525953Y846470D01*
G01X-1520820Y853470D02*
Y846470D01*
G01X-1522737Y853470D02*
X-1518903D01*
G01X-1514020Y846237D02*
X-1514187Y846353D01*
Y846587D01*
X-1514020Y846703D01*
X-1513853Y846587D01*
Y846353D01*
X-1514020Y846237D01*
G01Y849386D02*
X-1514187Y849503D01*
Y849737D01*
X-1514020Y849853D01*
X-1513853Y849737D01*
Y849503D01*
X-1514020Y849386D01*
G01X-1500420Y853470D02*
Y846470D01*
G01X-1502337Y853470D02*
X-1498503D01*
G01X-1493620Y846470D02*
X-1494287Y846587D01*
X-1494870Y847053D01*
X-1495370Y847753D01*
X-1495703Y848570D01*
X-1495870Y849503D01*
Y850437D01*
X-1495703Y851370D01*
X-1495370Y852187D01*
X-1494870Y852887D01*
X-1494287Y853353D01*
X-1493620Y853470D01*
X-1492953Y853353D01*
X-1492370Y852887D01*
X-1491870Y852187D01*
X-1491537Y851370D01*
X-1491370Y850437D01*
Y849503D01*
X-1491537Y848570D01*
X-1491870Y847753D01*
X-1492370Y847053D01*
X-1492953Y846587D01*
X-1493620Y846470D01*
G01X-1488487D02*
Y853470D01*
X-1486487D01*
X-1485820Y853120D01*
X-1485320Y852303D01*
X-1485153Y851370D01*
X-1485320Y850437D01*
X-1485737Y849737D01*
X-1486487Y849386D01*
X-1488487D01*
G01X-1473220Y853470D02*
Y846470D01*
G01X-1474387Y851137D02*
X-1472053D01*
G01X-1466420Y846470D02*
X-1466920Y846587D01*
X-1467420Y847053D01*
X-1467753Y847870D01*
X-1467920Y848803D01*
X-1467753Y849737D01*
X-1467420Y850553D01*
X-1466920Y851020D01*
X-1466420Y851137D01*
X-1465920Y851020D01*
X-1465420Y850553D01*
X-1465087Y849737D01*
X-1465003Y848803D01*
X-1465087Y847870D01*
X-1465420Y847053D01*
X-1465920Y846587D01*
X-1466420Y846470D01*
G01X-1452153Y850203D02*
X-1451820Y850553D01*
X-1451570Y851137D01*
X-1451403Y851953D01*
X-1451570Y852653D01*
X-1451903Y853120D01*
X-1452487Y853470D01*
X-1454737D01*
Y846470D01*
X-1451987D01*
X-1451403Y846937D01*
X-1451070Y847637D01*
X-1450903Y848453D01*
X-1451070Y849270D01*
X-1451570Y849970D01*
X-1452153Y850203D01*
X-1454737D01*
G01X-1446020Y846470D02*
X-1446687Y846587D01*
X-1447270Y847053D01*
X-1447770Y847753D01*
X-1448103Y848570D01*
X-1448270Y849503D01*
Y850437D01*
X-1448103Y851370D01*
X-1447770Y852187D01*
X-1447270Y852887D01*
X-1446687Y853353D01*
X-1446020Y853470D01*
X-1445353Y853353D01*
X-1444770Y852887D01*
X-1444270Y852187D01*
X-1443937Y851370D01*
X-1443770Y850437D01*
Y849503D01*
X-1443937Y848570D01*
X-1444270Y847753D01*
X-1444770Y847053D01*
X-1445353Y846587D01*
X-1446020Y846470D01*
G01X-1439220Y853470D02*
Y846470D01*
G01X-1441137Y853470D02*
X-1437303D01*
G01X-1432420D02*
Y846470D01*
G01X-1434337Y853470D02*
X-1430503D01*
G01X-1425620Y846470D02*
X-1426287Y846587D01*
X-1426870Y847053D01*
X-1427370Y847753D01*
X-1427703Y848570D01*
X-1427870Y849503D01*
Y850437D01*
X-1427703Y851370D01*
X-1427370Y852187D01*
X-1426870Y852887D01*
X-1426287Y853353D01*
X-1425620Y853470D01*
X-1424953Y853353D01*
X-1424370Y852887D01*
X-1423870Y852187D01*
X-1423537Y851370D01*
X-1423370Y850437D01*
Y849503D01*
X-1423537Y848570D01*
X-1423870Y847753D01*
X-1424370Y847053D01*
X-1424953Y846587D01*
X-1425620Y846470D01*
G01X-1420987D02*
Y853470D01*
X-1418820Y847637D01*
X-1416653Y853470D01*
Y846470D01*
G01X-1573903Y821470D02*
X-1571820Y828470D01*
X-1569737Y821470D01*
G01X-1570487Y823920D02*
X-1573153D01*
G01X-1566687Y828470D02*
Y821470D01*
X-1563353D01*
G01X-1559887Y828470D02*
Y821470D01*
X-1556553D01*
G01X-1546453Y828470D02*
Y823453D01*
X-1546120Y822403D01*
X-1545453Y821703D01*
X-1544620Y821470D01*
X-1543787Y821703D01*
X-1543120Y822403D01*
X-1542787Y823453D01*
Y828470D01*
G01X-1539737Y821470D02*
Y828470D01*
X-1535903Y821470D01*
Y828470D01*
G01X-1532020D02*
X-1530020D01*
G01X-1531020D02*
Y821470D01*
G01X-1532020D02*
X-1530020D01*
G01X-1524220Y828470D02*
Y821470D01*
G01X-1526137Y828470D02*
X-1522303D01*
G01X-1519170Y822403D02*
X-1518503Y821820D01*
X-1517753Y821470D01*
X-1517087D01*
X-1516420Y821820D01*
X-1515920Y822403D01*
X-1515670Y823220D01*
X-1515837Y824037D01*
X-1516253Y824737D01*
X-1517003Y825203D01*
X-1518003Y825437D01*
X-1518587Y825903D01*
X-1518837Y826720D01*
X-1518670Y827537D01*
X-1518253Y828120D01*
X-1517670Y828470D01*
X-1517087D01*
X-1516503Y828237D01*
X-1516003Y827653D01*
G01X-1505903Y821470D02*
X-1503820Y828470D01*
X-1501737Y821470D01*
G01X-1502487Y823920D02*
X-1505153D01*
G01X-1498687Y821470D02*
Y828470D01*
X-1496603D01*
X-1495937Y828120D01*
X-1495520Y827653D01*
X-1495353Y826720D01*
X-1495520Y825787D01*
X-1496020Y825203D01*
X-1496603Y824853D01*
X-1498687D01*
G01X-1496603D02*
X-1495353Y821470D01*
G01X-1488553D02*
X-1491887D01*
Y828470D01*
X-1488553D01*
G01X-1489887Y825087D02*
X-1491887D01*
G01X-1477620Y828470D02*
X-1475620D01*
G01X-1476620D02*
Y821470D01*
G01X-1477620D02*
X-1475620D01*
G01X-1471737D02*
Y828470D01*
X-1467903Y821470D01*
Y828470D01*
G01X-1458387Y821470D02*
Y828470D01*
X-1456220Y822637D01*
X-1454053Y828470D01*
Y821470D01*
G01X-1450420Y828470D02*
X-1448420D01*
G01X-1449420D02*
Y821470D01*
G01X-1450420D02*
X-1448420D01*
G01X-1444287Y828470D02*
Y821470D01*
X-1440953D01*
G01X-1437570Y822403D02*
X-1436903Y821820D01*
X-1436153Y821470D01*
X-1435487D01*
X-1434820Y821820D01*
X-1434320Y822403D01*
X-1434070Y823220D01*
X-1434237Y824037D01*
X-1434653Y824737D01*
X-1435403Y825203D01*
X-1436403Y825437D01*
X-1436987Y825903D01*
X-1437237Y826720D01*
X-1437070Y827537D01*
X-1436653Y828120D01*
X-1436070Y828470D01*
X-1435487D01*
X-1434903Y828237D01*
X-1434403Y827653D01*
G01X-1551869Y2000D02*
X-1549746Y8988D01*
X-1547703Y1976D01*
G01X-1548439Y4430D02*
X-1551105Y4445D01*
G01X-1552981Y62765D02*
X-1550858Y69753D01*
X-1548815Y62741D01*
G01X-1549551Y65195D02*
X-1552217Y65210D01*
G01X-1531937Y339503D02*
X-1529937D01*
G01X-1531020Y341020D02*
Y337986D01*
G01X-1526053Y338220D02*
X-1525553Y337637D01*
X-1524970Y337287D01*
X-1524220Y337170D01*
X-1523470Y337403D01*
X-1522887Y337870D01*
X-1522470Y338687D01*
X-1522387Y339620D01*
X-1522553Y340553D01*
X-1522970Y341137D01*
X-1523553Y341603D01*
X-1524137Y341720D01*
X-1524720Y341603D01*
X-1525470Y341137D01*
X-1525220Y344170D01*
X-1522970D01*
G01X-1517420Y336937D02*
X-1517587Y337053D01*
Y337287D01*
X-1517420Y337403D01*
X-1517253Y337287D01*
Y337053D01*
X-1517420Y336937D01*
G01X-1510620Y344170D02*
X-1511287Y343937D01*
X-1511787Y343353D01*
X-1512120Y342653D01*
X-1512370Y341720D01*
X-1512453Y340670D01*
X-1512370Y339620D01*
X-1512120Y338687D01*
X-1511787Y337986D01*
X-1511287Y337403D01*
X-1510620Y337170D01*
X-1509953Y337403D01*
X-1509453Y337986D01*
X-1509120Y338687D01*
X-1508870Y339620D01*
X-1508787Y340670D01*
X-1508870Y341720D01*
X-1509120Y342653D01*
X-1509453Y343353D01*
X-1509953Y343937D01*
X-1510620Y344170D01*
G01X-1503820D02*
X-1504487Y343937D01*
X-1504987Y343353D01*
X-1505320Y342653D01*
X-1505570Y341720D01*
X-1505653Y340670D01*
X-1505570Y339620D01*
X-1505320Y338687D01*
X-1504987Y337986D01*
X-1504487Y337403D01*
X-1503820Y337170D01*
X-1503153Y337403D01*
X-1502653Y337986D01*
X-1502320Y338687D01*
X-1502070Y339620D01*
X-1501987Y340670D01*
X-1502070Y341720D01*
X-1502320Y342653D01*
X-1502653Y343353D01*
X-1503153Y343937D01*
X-1503820Y344170D01*
G01X-1497020D02*
X-1497687Y343937D01*
X-1498187Y343353D01*
X-1498520Y342653D01*
X-1498770Y341720D01*
X-1498853Y340670D01*
X-1498770Y339620D01*
X-1498520Y338687D01*
X-1498187Y337986D01*
X-1497687Y337403D01*
X-1497020Y337170D01*
X-1496353Y337403D01*
X-1495853Y337986D01*
X-1495520Y338687D01*
X-1495270Y339620D01*
X-1495187Y340670D01*
X-1495270Y341720D01*
X-1495520Y342653D01*
X-1495853Y343353D01*
X-1496353Y343937D01*
X-1497020Y344170D01*
G01X-1491720Y336937D02*
X-1488720Y344170D01*
G01X-1484503Y339503D02*
X-1482337D01*
G01X-1478453Y338220D02*
X-1477953Y337637D01*
X-1477370Y337287D01*
X-1476620Y337170D01*
X-1475870Y337403D01*
X-1475287Y337870D01*
X-1474870Y338687D01*
X-1474787Y339620D01*
X-1474953Y340553D01*
X-1475370Y341137D01*
X-1475953Y341603D01*
X-1476537Y341720D01*
X-1477120Y341603D01*
X-1477870Y341137D01*
X-1477620Y344170D01*
X-1475370D01*
G01X-1469820Y336937D02*
X-1469987Y337053D01*
Y337287D01*
X-1469820Y337403D01*
X-1469653Y337287D01*
Y337053D01*
X-1469820Y336937D01*
G01X-1463020Y344170D02*
X-1463687Y343937D01*
X-1464187Y343353D01*
X-1464520Y342653D01*
X-1464770Y341720D01*
X-1464853Y340670D01*
X-1464770Y339620D01*
X-1464520Y338687D01*
X-1464187Y337986D01*
X-1463687Y337403D01*
X-1463020Y337170D01*
X-1462353Y337403D01*
X-1461853Y337986D01*
X-1461520Y338687D01*
X-1461270Y339620D01*
X-1461187Y340670D01*
X-1461270Y341720D01*
X-1461520Y342653D01*
X-1461853Y343353D01*
X-1462353Y343937D01*
X-1463020Y344170D01*
G01X-1456220D02*
X-1456887Y343937D01*
X-1457387Y343353D01*
X-1457720Y342653D01*
X-1457970Y341720D01*
X-1458053Y340670D01*
X-1457970Y339620D01*
X-1457720Y338687D01*
X-1457387Y337986D01*
X-1456887Y337403D01*
X-1456220Y337170D01*
X-1455553Y337403D01*
X-1455053Y337986D01*
X-1454720Y338687D01*
X-1454470Y339620D01*
X-1454387Y340670D01*
X-1454470Y341720D01*
X-1454720Y342653D01*
X-1455053Y343353D01*
X-1455553Y343937D01*
X-1456220Y344170D01*
G01X-1449420D02*
X-1450087Y343937D01*
X-1450587Y343353D01*
X-1450920Y342653D01*
X-1451170Y341720D01*
X-1451253Y340670D01*
X-1451170Y339620D01*
X-1450920Y338687D01*
X-1450587Y337986D01*
X-1450087Y337403D01*
X-1449420Y337170D01*
X-1448753Y337403D01*
X-1448253Y337986D01*
X-1447920Y338687D01*
X-1447670Y339620D01*
X-1447587Y340670D01*
X-1447670Y341720D01*
X-1447920Y342653D01*
X-1448253Y343353D01*
X-1448753Y343937D01*
X-1449420Y344170D01*
G01X-1531937Y362903D02*
X-1529937D01*
G01X-1531020Y364420D02*
Y361386D01*
G01X-1525803Y366403D02*
X-1525303Y367103D01*
X-1524720Y367453D01*
X-1524053Y367570D01*
X-1523220Y367337D01*
X-1522637Y366753D01*
X-1522470Y366053D01*
X-1522553Y365353D01*
X-1522887Y364770D01*
X-1524553Y363603D01*
X-1525303Y362787D01*
X-1525803Y361620D01*
X-1525970Y360570D01*
X-1522470D01*
G01X-1517420Y360337D02*
X-1517587Y360453D01*
Y360687D01*
X-1517420Y360803D01*
X-1517253Y360687D01*
Y360453D01*
X-1517420Y360337D01*
G01X-1510620Y367570D02*
X-1511287Y367337D01*
X-1511787Y366753D01*
X-1512120Y366053D01*
X-1512370Y365120D01*
X-1512453Y364070D01*
X-1512370Y363020D01*
X-1512120Y362087D01*
X-1511787Y361386D01*
X-1511287Y360803D01*
X-1510620Y360570D01*
X-1509953Y360803D01*
X-1509453Y361386D01*
X-1509120Y362087D01*
X-1508870Y363020D01*
X-1508787Y364070D01*
X-1508870Y365120D01*
X-1509120Y366053D01*
X-1509453Y366753D01*
X-1509953Y367337D01*
X-1510620Y367570D01*
G01X-1503820D02*
X-1504487Y367337D01*
X-1504987Y366753D01*
X-1505320Y366053D01*
X-1505570Y365120D01*
X-1505653Y364070D01*
X-1505570Y363020D01*
X-1505320Y362087D01*
X-1504987Y361386D01*
X-1504487Y360803D01*
X-1503820Y360570D01*
X-1503153Y360803D01*
X-1502653Y361386D01*
X-1502320Y362087D01*
X-1502070Y363020D01*
X-1501987Y364070D01*
X-1502070Y365120D01*
X-1502320Y366053D01*
X-1502653Y366753D01*
X-1503153Y367337D01*
X-1503820Y367570D01*
G01X-1497020D02*
X-1497687Y367337D01*
X-1498187Y366753D01*
X-1498520Y366053D01*
X-1498770Y365120D01*
X-1498853Y364070D01*
X-1498770Y363020D01*
X-1498520Y362087D01*
X-1498187Y361386D01*
X-1497687Y360803D01*
X-1497020Y360570D01*
X-1496353Y360803D01*
X-1495853Y361386D01*
X-1495520Y362087D01*
X-1495270Y363020D01*
X-1495187Y364070D01*
X-1495270Y365120D01*
X-1495520Y366053D01*
X-1495853Y366753D01*
X-1496353Y367337D01*
X-1497020Y367570D01*
G01X-1491720Y360337D02*
X-1488720Y367570D01*
G01X-1484503Y362903D02*
X-1482337D01*
G01X-1476620Y360570D02*
Y367570D01*
X-1477620Y366170D01*
G01Y360570D02*
X-1475620D01*
G01X-1469820Y360337D02*
X-1469987Y360453D01*
Y360687D01*
X-1469820Y360803D01*
X-1469653Y360687D01*
Y360453D01*
X-1469820Y360337D01*
G01X-1463020Y367570D02*
X-1463687Y367337D01*
X-1464187Y366753D01*
X-1464520Y366053D01*
X-1464770Y365120D01*
X-1464853Y364070D01*
X-1464770Y363020D01*
X-1464520Y362087D01*
X-1464187Y361386D01*
X-1463687Y360803D01*
X-1463020Y360570D01*
X-1462353Y360803D01*
X-1461853Y361386D01*
X-1461520Y362087D01*
X-1461270Y363020D01*
X-1461187Y364070D01*
X-1461270Y365120D01*
X-1461520Y366053D01*
X-1461853Y366753D01*
X-1462353Y367337D01*
X-1463020Y367570D01*
G01X-1456220D02*
X-1456887Y367337D01*
X-1457387Y366753D01*
X-1457720Y366053D01*
X-1457970Y365120D01*
X-1458053Y364070D01*
X-1457970Y363020D01*
X-1457720Y362087D01*
X-1457387Y361386D01*
X-1456887Y360803D01*
X-1456220Y360570D01*
X-1455553Y360803D01*
X-1455053Y361386D01*
X-1454720Y362087D01*
X-1454470Y363020D01*
X-1454387Y364070D01*
X-1454470Y365120D01*
X-1454720Y366053D01*
X-1455053Y366753D01*
X-1455553Y367337D01*
X-1456220Y367570D01*
G01X-1449420D02*
X-1450087Y367337D01*
X-1450587Y366753D01*
X-1450920Y366053D01*
X-1451170Y365120D01*
X-1451253Y364070D01*
X-1451170Y363020D01*
X-1450920Y362087D01*
X-1450587Y361386D01*
X-1450087Y360803D01*
X-1449420Y360570D01*
X-1448753Y360803D01*
X-1448253Y361386D01*
X-1447920Y362087D01*
X-1447670Y363020D01*
X-1447587Y364070D01*
X-1447670Y365120D01*
X-1447920Y366053D01*
X-1448253Y366753D01*
X-1448753Y367337D01*
X-1449420Y367570D01*
G01X-1531937Y386303D02*
X-1529937D01*
G01X-1531020Y387820D02*
Y384786D01*
G01X-1526053Y385370D02*
X-1525553Y384553D01*
X-1524887Y384087D01*
X-1524137Y383970D01*
X-1523470Y384087D01*
X-1522803Y384670D01*
X-1522387Y385370D01*
X-1522303Y386070D01*
X-1522470Y386886D01*
X-1523053Y387470D01*
X-1523637Y387703D01*
X-1524387D01*
G01X-1523637D02*
X-1523137Y388053D01*
X-1522720Y388637D01*
X-1522553Y389337D01*
X-1522720Y390037D01*
X-1523137Y390620D01*
X-1523887Y390970D01*
X-1524637Y390853D01*
X-1525387Y390387D01*
G01X-1517420Y383737D02*
X-1517587Y383853D01*
Y384087D01*
X-1517420Y384203D01*
X-1517253Y384087D01*
Y383853D01*
X-1517420Y383737D01*
G01X-1510620Y390970D02*
X-1511287Y390737D01*
X-1511787Y390153D01*
X-1512120Y389453D01*
X-1512370Y388520D01*
X-1512453Y387470D01*
X-1512370Y386420D01*
X-1512120Y385487D01*
X-1511787Y384786D01*
X-1511287Y384203D01*
X-1510620Y383970D01*
X-1509953Y384203D01*
X-1509453Y384786D01*
X-1509120Y385487D01*
X-1508870Y386420D01*
X-1508787Y387470D01*
X-1508870Y388520D01*
X-1509120Y389453D01*
X-1509453Y390153D01*
X-1509953Y390737D01*
X-1510620Y390970D01*
G01X-1503820D02*
X-1504487Y390737D01*
X-1504987Y390153D01*
X-1505320Y389453D01*
X-1505570Y388520D01*
X-1505653Y387470D01*
X-1505570Y386420D01*
X-1505320Y385487D01*
X-1504987Y384786D01*
X-1504487Y384203D01*
X-1503820Y383970D01*
X-1503153Y384203D01*
X-1502653Y384786D01*
X-1502320Y385487D01*
X-1502070Y386420D01*
X-1501987Y387470D01*
X-1502070Y388520D01*
X-1502320Y389453D01*
X-1502653Y390153D01*
X-1503153Y390737D01*
X-1503820Y390970D01*
G01X-1497020D02*
X-1497687Y390737D01*
X-1498187Y390153D01*
X-1498520Y389453D01*
X-1498770Y388520D01*
X-1498853Y387470D01*
X-1498770Y386420D01*
X-1498520Y385487D01*
X-1498187Y384786D01*
X-1497687Y384203D01*
X-1497020Y383970D01*
X-1496353Y384203D01*
X-1495853Y384786D01*
X-1495520Y385487D01*
X-1495270Y386420D01*
X-1495187Y387470D01*
X-1495270Y388520D01*
X-1495520Y389453D01*
X-1495853Y390153D01*
X-1496353Y390737D01*
X-1497020Y390970D01*
G01X-1491720Y383737D02*
X-1488720Y390970D01*
G01X-1484503Y386303D02*
X-1482337D01*
G01X-1478453Y385370D02*
X-1477953Y384553D01*
X-1477287Y384087D01*
X-1476537Y383970D01*
X-1475870Y384087D01*
X-1475203Y384670D01*
X-1474787Y385370D01*
X-1474703Y386070D01*
X-1474870Y386886D01*
X-1475453Y387470D01*
X-1476037Y387703D01*
X-1476787D01*
G01X-1476037D02*
X-1475537Y388053D01*
X-1475120Y388637D01*
X-1474953Y389337D01*
X-1475120Y390037D01*
X-1475537Y390620D01*
X-1476287Y390970D01*
X-1477037Y390853D01*
X-1477787Y390387D01*
G01X-1469820Y383737D02*
X-1469987Y383853D01*
Y384087D01*
X-1469820Y384203D01*
X-1469653Y384087D01*
Y383853D01*
X-1469820Y383737D01*
G01X-1463020Y390970D02*
X-1463687Y390737D01*
X-1464187Y390153D01*
X-1464520Y389453D01*
X-1464770Y388520D01*
X-1464853Y387470D01*
X-1464770Y386420D01*
X-1464520Y385487D01*
X-1464187Y384786D01*
X-1463687Y384203D01*
X-1463020Y383970D01*
X-1462353Y384203D01*
X-1461853Y384786D01*
X-1461520Y385487D01*
X-1461270Y386420D01*
X-1461187Y387470D01*
X-1461270Y388520D01*
X-1461520Y389453D01*
X-1461853Y390153D01*
X-1462353Y390737D01*
X-1463020Y390970D01*
G01X-1456220D02*
X-1456887Y390737D01*
X-1457387Y390153D01*
X-1457720Y389453D01*
X-1457970Y388520D01*
X-1458053Y387470D01*
X-1457970Y386420D01*
X-1457720Y385487D01*
X-1457387Y384786D01*
X-1456887Y384203D01*
X-1456220Y383970D01*
X-1455553Y384203D01*
X-1455053Y384786D01*
X-1454720Y385487D01*
X-1454470Y386420D01*
X-1454387Y387470D01*
X-1454470Y388520D01*
X-1454720Y389453D01*
X-1455053Y390153D01*
X-1455553Y390737D01*
X-1456220Y390970D01*
G01X-1449420D02*
X-1450087Y390737D01*
X-1450587Y390153D01*
X-1450920Y389453D01*
X-1451170Y388520D01*
X-1451253Y387470D01*
X-1451170Y386420D01*
X-1450920Y385487D01*
X-1450587Y384786D01*
X-1450087Y384203D01*
X-1449420Y383970D01*
X-1448753Y384203D01*
X-1448253Y384786D01*
X-1447920Y385487D01*
X-1447670Y386420D01*
X-1447587Y387470D01*
X-1447670Y388520D01*
X-1447920Y389453D01*
X-1448253Y390153D01*
X-1448753Y390737D01*
X-1449420Y390970D01*
G01X-1531937Y409703D02*
X-1529937D01*
G01X-1531020Y411220D02*
Y408186D01*
G01X-1526053Y408770D02*
X-1525553Y407953D01*
X-1524887Y407487D01*
X-1524137Y407370D01*
X-1523470Y407487D01*
X-1522803Y408070D01*
X-1522387Y408770D01*
X-1522303Y409470D01*
X-1522470Y410286D01*
X-1523053Y410870D01*
X-1523637Y411103D01*
X-1524387D01*
G01X-1523637D02*
X-1523137Y411453D01*
X-1522720Y412037D01*
X-1522553Y412737D01*
X-1522720Y413437D01*
X-1523137Y414020D01*
X-1523887Y414370D01*
X-1524637Y414253D01*
X-1525387Y413787D01*
G01X-1517420Y407137D02*
X-1517587Y407253D01*
Y407487D01*
X-1517420Y407603D01*
X-1517253Y407487D01*
Y407253D01*
X-1517420Y407137D01*
G01X-1510620Y414370D02*
X-1511287Y414137D01*
X-1511787Y413553D01*
X-1512120Y412853D01*
X-1512370Y411920D01*
X-1512453Y410870D01*
X-1512370Y409820D01*
X-1512120Y408887D01*
X-1511787Y408186D01*
X-1511287Y407603D01*
X-1510620Y407370D01*
X-1509953Y407603D01*
X-1509453Y408186D01*
X-1509120Y408887D01*
X-1508870Y409820D01*
X-1508787Y410870D01*
X-1508870Y411920D01*
X-1509120Y412853D01*
X-1509453Y413553D01*
X-1509953Y414137D01*
X-1510620Y414370D01*
G01X-1503820D02*
X-1504487Y414137D01*
X-1504987Y413553D01*
X-1505320Y412853D01*
X-1505570Y411920D01*
X-1505653Y410870D01*
X-1505570Y409820D01*
X-1505320Y408887D01*
X-1504987Y408186D01*
X-1504487Y407603D01*
X-1503820Y407370D01*
X-1503153Y407603D01*
X-1502653Y408186D01*
X-1502320Y408887D01*
X-1502070Y409820D01*
X-1501987Y410870D01*
X-1502070Y411920D01*
X-1502320Y412853D01*
X-1502653Y413553D01*
X-1503153Y414137D01*
X-1503820Y414370D01*
G01X-1497020D02*
X-1497687Y414137D01*
X-1498187Y413553D01*
X-1498520Y412853D01*
X-1498770Y411920D01*
X-1498853Y410870D01*
X-1498770Y409820D01*
X-1498520Y408887D01*
X-1498187Y408186D01*
X-1497687Y407603D01*
X-1497020Y407370D01*
X-1496353Y407603D01*
X-1495853Y408186D01*
X-1495520Y408887D01*
X-1495270Y409820D01*
X-1495187Y410870D01*
X-1495270Y411920D01*
X-1495520Y412853D01*
X-1495853Y413553D01*
X-1496353Y414137D01*
X-1497020Y414370D01*
G01X-1491720Y407137D02*
X-1488720Y414370D01*
G01X-1484503Y409703D02*
X-1482337D01*
G01X-1478453Y408770D02*
X-1477953Y407953D01*
X-1477287Y407487D01*
X-1476537Y407370D01*
X-1475870Y407487D01*
X-1475203Y408070D01*
X-1474787Y408770D01*
X-1474703Y409470D01*
X-1474870Y410286D01*
X-1475453Y410870D01*
X-1476037Y411103D01*
X-1476787D01*
G01X-1476037D02*
X-1475537Y411453D01*
X-1475120Y412037D01*
X-1474953Y412737D01*
X-1475120Y413437D01*
X-1475537Y414020D01*
X-1476287Y414370D01*
X-1477037Y414253D01*
X-1477787Y413787D01*
G01X-1469820Y407137D02*
X-1469987Y407253D01*
Y407487D01*
X-1469820Y407603D01*
X-1469653Y407487D01*
Y407253D01*
X-1469820Y407137D01*
G01X-1463020Y414370D02*
X-1463687Y414137D01*
X-1464187Y413553D01*
X-1464520Y412853D01*
X-1464770Y411920D01*
X-1464853Y410870D01*
X-1464770Y409820D01*
X-1464520Y408887D01*
X-1464187Y408186D01*
X-1463687Y407603D01*
X-1463020Y407370D01*
X-1462353Y407603D01*
X-1461853Y408186D01*
X-1461520Y408887D01*
X-1461270Y409820D01*
X-1461187Y410870D01*
X-1461270Y411920D01*
X-1461520Y412853D01*
X-1461853Y413553D01*
X-1462353Y414137D01*
X-1463020Y414370D01*
G01X-1456220D02*
X-1456887Y414137D01*
X-1457387Y413553D01*
X-1457720Y412853D01*
X-1457970Y411920D01*
X-1458053Y410870D01*
X-1457970Y409820D01*
X-1457720Y408887D01*
X-1457387Y408186D01*
X-1456887Y407603D01*
X-1456220Y407370D01*
X-1455553Y407603D01*
X-1455053Y408186D01*
X-1454720Y408887D01*
X-1454470Y409820D01*
X-1454387Y410870D01*
X-1454470Y411920D01*
X-1454720Y412853D01*
X-1455053Y413553D01*
X-1455553Y414137D01*
X-1456220Y414370D01*
G01X-1449420D02*
X-1450087Y414137D01*
X-1450587Y413553D01*
X-1450920Y412853D01*
X-1451170Y411920D01*
X-1451253Y410870D01*
X-1451170Y409820D01*
X-1450920Y408887D01*
X-1450587Y408186D01*
X-1450087Y407603D01*
X-1449420Y407370D01*
X-1448753Y407603D01*
X-1448253Y408186D01*
X-1447920Y408887D01*
X-1447670Y409820D01*
X-1447587Y410870D01*
X-1447670Y411920D01*
X-1447920Y412853D01*
X-1448253Y413553D01*
X-1448753Y414137D01*
X-1449420Y414370D01*
G01X-1531937Y433103D02*
X-1529937D01*
G01X-1531020Y434620D02*
Y431586D01*
G01X-1526053Y432170D02*
X-1525553Y431353D01*
X-1524887Y430887D01*
X-1524137Y430770D01*
X-1523470Y430887D01*
X-1522803Y431470D01*
X-1522387Y432170D01*
X-1522303Y432870D01*
X-1522470Y433686D01*
X-1523053Y434270D01*
X-1523637Y434503D01*
X-1524387D01*
G01X-1523637D02*
X-1523137Y434853D01*
X-1522720Y435437D01*
X-1522553Y436137D01*
X-1522720Y436837D01*
X-1523137Y437420D01*
X-1523887Y437770D01*
X-1524637Y437653D01*
X-1525387Y437187D01*
G01X-1517420Y430537D02*
X-1517587Y430653D01*
Y430887D01*
X-1517420Y431003D01*
X-1517253Y430887D01*
Y430653D01*
X-1517420Y430537D01*
G01X-1510620Y437770D02*
X-1511287Y437537D01*
X-1511787Y436953D01*
X-1512120Y436253D01*
X-1512370Y435320D01*
X-1512453Y434270D01*
X-1512370Y433220D01*
X-1512120Y432287D01*
X-1511787Y431586D01*
X-1511287Y431003D01*
X-1510620Y430770D01*
X-1509953Y431003D01*
X-1509453Y431586D01*
X-1509120Y432287D01*
X-1508870Y433220D01*
X-1508787Y434270D01*
X-1508870Y435320D01*
X-1509120Y436253D01*
X-1509453Y436953D01*
X-1509953Y437537D01*
X-1510620Y437770D01*
G01X-1503820D02*
X-1504487Y437537D01*
X-1504987Y436953D01*
X-1505320Y436253D01*
X-1505570Y435320D01*
X-1505653Y434270D01*
X-1505570Y433220D01*
X-1505320Y432287D01*
X-1504987Y431586D01*
X-1504487Y431003D01*
X-1503820Y430770D01*
X-1503153Y431003D01*
X-1502653Y431586D01*
X-1502320Y432287D01*
X-1502070Y433220D01*
X-1501987Y434270D01*
X-1502070Y435320D01*
X-1502320Y436253D01*
X-1502653Y436953D01*
X-1503153Y437537D01*
X-1503820Y437770D01*
G01X-1497020D02*
X-1497687Y437537D01*
X-1498187Y436953D01*
X-1498520Y436253D01*
X-1498770Y435320D01*
X-1498853Y434270D01*
X-1498770Y433220D01*
X-1498520Y432287D01*
X-1498187Y431586D01*
X-1497687Y431003D01*
X-1497020Y430770D01*
X-1496353Y431003D01*
X-1495853Y431586D01*
X-1495520Y432287D01*
X-1495270Y433220D01*
X-1495187Y434270D01*
X-1495270Y435320D01*
X-1495520Y436253D01*
X-1495853Y436953D01*
X-1496353Y437537D01*
X-1497020Y437770D01*
G01X-1491720Y430537D02*
X-1488720Y437770D01*
G01X-1484503Y433103D02*
X-1482337D01*
G01X-1478453Y432170D02*
X-1477953Y431353D01*
X-1477287Y430887D01*
X-1476537Y430770D01*
X-1475870Y430887D01*
X-1475203Y431470D01*
X-1474787Y432170D01*
X-1474703Y432870D01*
X-1474870Y433686D01*
X-1475453Y434270D01*
X-1476037Y434503D01*
X-1476787D01*
G01X-1476037D02*
X-1475537Y434853D01*
X-1475120Y435437D01*
X-1474953Y436137D01*
X-1475120Y436837D01*
X-1475537Y437420D01*
X-1476287Y437770D01*
X-1477037Y437653D01*
X-1477787Y437187D01*
G01X-1469820Y430537D02*
X-1469987Y430653D01*
Y430887D01*
X-1469820Y431003D01*
X-1469653Y430887D01*
Y430653D01*
X-1469820Y430537D01*
G01X-1463020Y437770D02*
X-1463687Y437537D01*
X-1464187Y436953D01*
X-1464520Y436253D01*
X-1464770Y435320D01*
X-1464853Y434270D01*
X-1464770Y433220D01*
X-1464520Y432287D01*
X-1464187Y431586D01*
X-1463687Y431003D01*
X-1463020Y430770D01*
X-1462353Y431003D01*
X-1461853Y431586D01*
X-1461520Y432287D01*
X-1461270Y433220D01*
X-1461187Y434270D01*
X-1461270Y435320D01*
X-1461520Y436253D01*
X-1461853Y436953D01*
X-1462353Y437537D01*
X-1463020Y437770D01*
G01X-1456220D02*
X-1456887Y437537D01*
X-1457387Y436953D01*
X-1457720Y436253D01*
X-1457970Y435320D01*
X-1458053Y434270D01*
X-1457970Y433220D01*
X-1457720Y432287D01*
X-1457387Y431586D01*
X-1456887Y431003D01*
X-1456220Y430770D01*
X-1455553Y431003D01*
X-1455053Y431586D01*
X-1454720Y432287D01*
X-1454470Y433220D01*
X-1454387Y434270D01*
X-1454470Y435320D01*
X-1454720Y436253D01*
X-1455053Y436953D01*
X-1455553Y437537D01*
X-1456220Y437770D01*
G01X-1449420D02*
X-1450087Y437537D01*
X-1450587Y436953D01*
X-1450920Y436253D01*
X-1451170Y435320D01*
X-1451253Y434270D01*
X-1451170Y433220D01*
X-1450920Y432287D01*
X-1450587Y431586D01*
X-1450087Y431003D01*
X-1449420Y430770D01*
X-1448753Y431003D01*
X-1448253Y431586D01*
X-1447920Y432287D01*
X-1447670Y433220D01*
X-1447587Y434270D01*
X-1447670Y435320D01*
X-1447920Y436253D01*
X-1448253Y436953D01*
X-1448753Y437537D01*
X-1449420Y437770D01*
G01X-1531937Y456503D02*
X-1529937D01*
G01X-1531020Y458020D02*
Y454986D01*
G01X-1526053Y455570D02*
X-1525553Y454753D01*
X-1524887Y454287D01*
X-1524137Y454170D01*
X-1523470Y454287D01*
X-1522803Y454870D01*
X-1522387Y455570D01*
X-1522303Y456270D01*
X-1522470Y457086D01*
X-1523053Y457670D01*
X-1523637Y457903D01*
X-1524387D01*
G01X-1523637D02*
X-1523137Y458253D01*
X-1522720Y458837D01*
X-1522553Y459537D01*
X-1522720Y460237D01*
X-1523137Y460820D01*
X-1523887Y461170D01*
X-1524637Y461053D01*
X-1525387Y460587D01*
G01X-1517420Y453937D02*
X-1517587Y454053D01*
Y454287D01*
X-1517420Y454403D01*
X-1517253Y454287D01*
Y454053D01*
X-1517420Y453937D01*
G01X-1510620Y461170D02*
X-1511287Y460937D01*
X-1511787Y460353D01*
X-1512120Y459653D01*
X-1512370Y458720D01*
X-1512453Y457670D01*
X-1512370Y456620D01*
X-1512120Y455687D01*
X-1511787Y454986D01*
X-1511287Y454403D01*
X-1510620Y454170D01*
X-1509953Y454403D01*
X-1509453Y454986D01*
X-1509120Y455687D01*
X-1508870Y456620D01*
X-1508787Y457670D01*
X-1508870Y458720D01*
X-1509120Y459653D01*
X-1509453Y460353D01*
X-1509953Y460937D01*
X-1510620Y461170D01*
G01X-1503820D02*
X-1504487Y460937D01*
X-1504987Y460353D01*
X-1505320Y459653D01*
X-1505570Y458720D01*
X-1505653Y457670D01*
X-1505570Y456620D01*
X-1505320Y455687D01*
X-1504987Y454986D01*
X-1504487Y454403D01*
X-1503820Y454170D01*
X-1503153Y454403D01*
X-1502653Y454986D01*
X-1502320Y455687D01*
X-1502070Y456620D01*
X-1501987Y457670D01*
X-1502070Y458720D01*
X-1502320Y459653D01*
X-1502653Y460353D01*
X-1503153Y460937D01*
X-1503820Y461170D01*
G01X-1497020D02*
X-1497687Y460937D01*
X-1498187Y460353D01*
X-1498520Y459653D01*
X-1498770Y458720D01*
X-1498853Y457670D01*
X-1498770Y456620D01*
X-1498520Y455687D01*
X-1498187Y454986D01*
X-1497687Y454403D01*
X-1497020Y454170D01*
X-1496353Y454403D01*
X-1495853Y454986D01*
X-1495520Y455687D01*
X-1495270Y456620D01*
X-1495187Y457670D01*
X-1495270Y458720D01*
X-1495520Y459653D01*
X-1495853Y460353D01*
X-1496353Y460937D01*
X-1497020Y461170D01*
G01X-1491720Y453937D02*
X-1488720Y461170D01*
G01X-1484503Y456503D02*
X-1482337D01*
G01X-1478453Y455570D02*
X-1477953Y454753D01*
X-1477287Y454287D01*
X-1476537Y454170D01*
X-1475870Y454287D01*
X-1475203Y454870D01*
X-1474787Y455570D01*
X-1474703Y456270D01*
X-1474870Y457086D01*
X-1475453Y457670D01*
X-1476037Y457903D01*
X-1476787D01*
G01X-1476037D02*
X-1475537Y458253D01*
X-1475120Y458837D01*
X-1474953Y459537D01*
X-1475120Y460237D01*
X-1475537Y460820D01*
X-1476287Y461170D01*
X-1477037Y461053D01*
X-1477787Y460587D01*
G01X-1469820Y453937D02*
X-1469987Y454053D01*
Y454287D01*
X-1469820Y454403D01*
X-1469653Y454287D01*
Y454053D01*
X-1469820Y453937D01*
G01X-1463020Y461170D02*
X-1463687Y460937D01*
X-1464187Y460353D01*
X-1464520Y459653D01*
X-1464770Y458720D01*
X-1464853Y457670D01*
X-1464770Y456620D01*
X-1464520Y455687D01*
X-1464187Y454986D01*
X-1463687Y454403D01*
X-1463020Y454170D01*
X-1462353Y454403D01*
X-1461853Y454986D01*
X-1461520Y455687D01*
X-1461270Y456620D01*
X-1461187Y457670D01*
X-1461270Y458720D01*
X-1461520Y459653D01*
X-1461853Y460353D01*
X-1462353Y460937D01*
X-1463020Y461170D01*
G01X-1456220D02*
X-1456887Y460937D01*
X-1457387Y460353D01*
X-1457720Y459653D01*
X-1457970Y458720D01*
X-1458053Y457670D01*
X-1457970Y456620D01*
X-1457720Y455687D01*
X-1457387Y454986D01*
X-1456887Y454403D01*
X-1456220Y454170D01*
X-1455553Y454403D01*
X-1455053Y454986D01*
X-1454720Y455687D01*
X-1454470Y456620D01*
X-1454387Y457670D01*
X-1454470Y458720D01*
X-1454720Y459653D01*
X-1455053Y460353D01*
X-1455553Y460937D01*
X-1456220Y461170D01*
G01X-1449420D02*
X-1450087Y460937D01*
X-1450587Y460353D01*
X-1450920Y459653D01*
X-1451170Y458720D01*
X-1451253Y457670D01*
X-1451170Y456620D01*
X-1450920Y455687D01*
X-1450587Y454986D01*
X-1450087Y454403D01*
X-1449420Y454170D01*
X-1448753Y454403D01*
X-1448253Y454986D01*
X-1447920Y455687D01*
X-1447670Y456620D01*
X-1447587Y457670D01*
X-1447670Y458720D01*
X-1447920Y459653D01*
X-1448253Y460353D01*
X-1448753Y460937D01*
X-1449420Y461170D01*
G01X-1531937Y479903D02*
X-1529937D01*
G01X-1531020Y481420D02*
Y478386D01*
G01X-1526053Y478620D02*
X-1525553Y478037D01*
X-1524970Y477687D01*
X-1524220Y477570D01*
X-1523470Y477803D01*
X-1522887Y478270D01*
X-1522470Y479087D01*
X-1522387Y480020D01*
X-1522553Y480953D01*
X-1522970Y481537D01*
X-1523553Y482003D01*
X-1524137Y482120D01*
X-1524720Y482003D01*
X-1525470Y481537D01*
X-1525220Y484570D01*
X-1522970D01*
G01X-1517420Y477337D02*
X-1517587Y477453D01*
Y477687D01*
X-1517420Y477803D01*
X-1517253Y477687D01*
Y477453D01*
X-1517420Y477337D01*
G01X-1510620Y484570D02*
X-1511287Y484337D01*
X-1511787Y483753D01*
X-1512120Y483053D01*
X-1512370Y482120D01*
X-1512453Y481070D01*
X-1512370Y480020D01*
X-1512120Y479087D01*
X-1511787Y478386D01*
X-1511287Y477803D01*
X-1510620Y477570D01*
X-1509953Y477803D01*
X-1509453Y478386D01*
X-1509120Y479087D01*
X-1508870Y480020D01*
X-1508787Y481070D01*
X-1508870Y482120D01*
X-1509120Y483053D01*
X-1509453Y483753D01*
X-1509953Y484337D01*
X-1510620Y484570D01*
G01X-1503820D02*
X-1504487Y484337D01*
X-1504987Y483753D01*
X-1505320Y483053D01*
X-1505570Y482120D01*
X-1505653Y481070D01*
X-1505570Y480020D01*
X-1505320Y479087D01*
X-1504987Y478386D01*
X-1504487Y477803D01*
X-1503820Y477570D01*
X-1503153Y477803D01*
X-1502653Y478386D01*
X-1502320Y479087D01*
X-1502070Y480020D01*
X-1501987Y481070D01*
X-1502070Y482120D01*
X-1502320Y483053D01*
X-1502653Y483753D01*
X-1503153Y484337D01*
X-1503820Y484570D01*
G01X-1497020D02*
X-1497687Y484337D01*
X-1498187Y483753D01*
X-1498520Y483053D01*
X-1498770Y482120D01*
X-1498853Y481070D01*
X-1498770Y480020D01*
X-1498520Y479087D01*
X-1498187Y478386D01*
X-1497687Y477803D01*
X-1497020Y477570D01*
X-1496353Y477803D01*
X-1495853Y478386D01*
X-1495520Y479087D01*
X-1495270Y480020D01*
X-1495187Y481070D01*
X-1495270Y482120D01*
X-1495520Y483053D01*
X-1495853Y483753D01*
X-1496353Y484337D01*
X-1497020Y484570D01*
G01X-1491720Y477337D02*
X-1488720Y484570D01*
G01X-1484503Y479903D02*
X-1482337D01*
G01X-1478453Y478620D02*
X-1477953Y478037D01*
X-1477370Y477687D01*
X-1476620Y477570D01*
X-1475870Y477803D01*
X-1475287Y478270D01*
X-1474870Y479087D01*
X-1474787Y480020D01*
X-1474953Y480953D01*
X-1475370Y481537D01*
X-1475953Y482003D01*
X-1476537Y482120D01*
X-1477120Y482003D01*
X-1477870Y481537D01*
X-1477620Y484570D01*
X-1475370D01*
G01X-1469820Y477337D02*
X-1469987Y477453D01*
Y477687D01*
X-1469820Y477803D01*
X-1469653Y477687D01*
Y477453D01*
X-1469820Y477337D01*
G01X-1463020Y484570D02*
X-1463687Y484337D01*
X-1464187Y483753D01*
X-1464520Y483053D01*
X-1464770Y482120D01*
X-1464853Y481070D01*
X-1464770Y480020D01*
X-1464520Y479087D01*
X-1464187Y478386D01*
X-1463687Y477803D01*
X-1463020Y477570D01*
X-1462353Y477803D01*
X-1461853Y478386D01*
X-1461520Y479087D01*
X-1461270Y480020D01*
X-1461187Y481070D01*
X-1461270Y482120D01*
X-1461520Y483053D01*
X-1461853Y483753D01*
X-1462353Y484337D01*
X-1463020Y484570D01*
G01X-1456220D02*
X-1456887Y484337D01*
X-1457387Y483753D01*
X-1457720Y483053D01*
X-1457970Y482120D01*
X-1458053Y481070D01*
X-1457970Y480020D01*
X-1457720Y479087D01*
X-1457387Y478386D01*
X-1456887Y477803D01*
X-1456220Y477570D01*
X-1455553Y477803D01*
X-1455053Y478386D01*
X-1454720Y479087D01*
X-1454470Y480020D01*
X-1454387Y481070D01*
X-1454470Y482120D01*
X-1454720Y483053D01*
X-1455053Y483753D01*
X-1455553Y484337D01*
X-1456220Y484570D01*
G01X-1449420D02*
X-1450087Y484337D01*
X-1450587Y483753D01*
X-1450920Y483053D01*
X-1451170Y482120D01*
X-1451253Y481070D01*
X-1451170Y480020D01*
X-1450920Y479087D01*
X-1450587Y478386D01*
X-1450087Y477803D01*
X-1449420Y477570D01*
X-1448753Y477803D01*
X-1448253Y478386D01*
X-1447920Y479087D01*
X-1447670Y480020D01*
X-1447587Y481070D01*
X-1447670Y482120D01*
X-1447920Y483053D01*
X-1448253Y483753D01*
X-1448753Y484337D01*
X-1449420Y484570D01*
G01X-1531937Y503303D02*
X-1529937D01*
G01X-1531020Y504820D02*
Y501786D01*
G01X-1526053Y502020D02*
X-1525553Y501437D01*
X-1524970Y501087D01*
X-1524220Y500970D01*
X-1523470Y501203D01*
X-1522887Y501670D01*
X-1522470Y502487D01*
X-1522387Y503420D01*
X-1522553Y504353D01*
X-1522970Y504937D01*
X-1523553Y505403D01*
X-1524137Y505520D01*
X-1524720Y505403D01*
X-1525470Y504937D01*
X-1525220Y507970D01*
X-1522970D01*
G01X-1517420Y500737D02*
X-1517587Y500853D01*
Y501087D01*
X-1517420Y501203D01*
X-1517253Y501087D01*
Y500853D01*
X-1517420Y500737D01*
G01X-1510620Y507970D02*
X-1511287Y507737D01*
X-1511787Y507153D01*
X-1512120Y506453D01*
X-1512370Y505520D01*
X-1512453Y504470D01*
X-1512370Y503420D01*
X-1512120Y502487D01*
X-1511787Y501786D01*
X-1511287Y501203D01*
X-1510620Y500970D01*
X-1509953Y501203D01*
X-1509453Y501786D01*
X-1509120Y502487D01*
X-1508870Y503420D01*
X-1508787Y504470D01*
X-1508870Y505520D01*
X-1509120Y506453D01*
X-1509453Y507153D01*
X-1509953Y507737D01*
X-1510620Y507970D01*
G01X-1503820D02*
X-1504487Y507737D01*
X-1504987Y507153D01*
X-1505320Y506453D01*
X-1505570Y505520D01*
X-1505653Y504470D01*
X-1505570Y503420D01*
X-1505320Y502487D01*
X-1504987Y501786D01*
X-1504487Y501203D01*
X-1503820Y500970D01*
X-1503153Y501203D01*
X-1502653Y501786D01*
X-1502320Y502487D01*
X-1502070Y503420D01*
X-1501987Y504470D01*
X-1502070Y505520D01*
X-1502320Y506453D01*
X-1502653Y507153D01*
X-1503153Y507737D01*
X-1503820Y507970D01*
G01X-1497020D02*
X-1497687Y507737D01*
X-1498187Y507153D01*
X-1498520Y506453D01*
X-1498770Y505520D01*
X-1498853Y504470D01*
X-1498770Y503420D01*
X-1498520Y502487D01*
X-1498187Y501786D01*
X-1497687Y501203D01*
X-1497020Y500970D01*
X-1496353Y501203D01*
X-1495853Y501786D01*
X-1495520Y502487D01*
X-1495270Y503420D01*
X-1495187Y504470D01*
X-1495270Y505520D01*
X-1495520Y506453D01*
X-1495853Y507153D01*
X-1496353Y507737D01*
X-1497020Y507970D01*
G01X-1491720Y500737D02*
X-1488720Y507970D01*
G01X-1484503Y503303D02*
X-1482337D01*
G01X-1478453Y502020D02*
X-1477953Y501437D01*
X-1477370Y501087D01*
X-1476620Y500970D01*
X-1475870Y501203D01*
X-1475287Y501670D01*
X-1474870Y502487D01*
X-1474787Y503420D01*
X-1474953Y504353D01*
X-1475370Y504937D01*
X-1475953Y505403D01*
X-1476537Y505520D01*
X-1477120Y505403D01*
X-1477870Y504937D01*
X-1477620Y507970D01*
X-1475370D01*
G01X-1469820Y500737D02*
X-1469987Y500853D01*
Y501087D01*
X-1469820Y501203D01*
X-1469653Y501087D01*
Y500853D01*
X-1469820Y500737D01*
G01X-1463020Y507970D02*
X-1463687Y507737D01*
X-1464187Y507153D01*
X-1464520Y506453D01*
X-1464770Y505520D01*
X-1464853Y504470D01*
X-1464770Y503420D01*
X-1464520Y502487D01*
X-1464187Y501786D01*
X-1463687Y501203D01*
X-1463020Y500970D01*
X-1462353Y501203D01*
X-1461853Y501786D01*
X-1461520Y502487D01*
X-1461270Y503420D01*
X-1461187Y504470D01*
X-1461270Y505520D01*
X-1461520Y506453D01*
X-1461853Y507153D01*
X-1462353Y507737D01*
X-1463020Y507970D01*
G01X-1456220D02*
X-1456887Y507737D01*
X-1457387Y507153D01*
X-1457720Y506453D01*
X-1457970Y505520D01*
X-1458053Y504470D01*
X-1457970Y503420D01*
X-1457720Y502487D01*
X-1457387Y501786D01*
X-1456887Y501203D01*
X-1456220Y500970D01*
X-1455553Y501203D01*
X-1455053Y501786D01*
X-1454720Y502487D01*
X-1454470Y503420D01*
X-1454387Y504470D01*
X-1454470Y505520D01*
X-1454720Y506453D01*
X-1455053Y507153D01*
X-1455553Y507737D01*
X-1456220Y507970D01*
G01X-1449420D02*
X-1450087Y507737D01*
X-1450587Y507153D01*
X-1450920Y506453D01*
X-1451170Y505520D01*
X-1451253Y504470D01*
X-1451170Y503420D01*
X-1450920Y502487D01*
X-1450587Y501786D01*
X-1450087Y501203D01*
X-1449420Y500970D01*
X-1448753Y501203D01*
X-1448253Y501786D01*
X-1447920Y502487D01*
X-1447670Y503420D01*
X-1447587Y504470D01*
X-1447670Y505520D01*
X-1447920Y506453D01*
X-1448253Y507153D01*
X-1448753Y507737D01*
X-1449420Y507970D01*
G01X-1531937Y526703D02*
X-1529937D01*
G01X-1531020Y528220D02*
Y525186D01*
G01X-1526053Y525770D02*
X-1525553Y524953D01*
X-1524887Y524487D01*
X-1524137Y524370D01*
X-1523470Y524487D01*
X-1522803Y525070D01*
X-1522387Y525770D01*
X-1522303Y526470D01*
X-1522470Y527286D01*
X-1523053Y527870D01*
X-1523637Y528103D01*
X-1524387D01*
G01X-1523637D02*
X-1523137Y528453D01*
X-1522720Y529037D01*
X-1522553Y529737D01*
X-1522720Y530437D01*
X-1523137Y531020D01*
X-1523887Y531370D01*
X-1524637Y531253D01*
X-1525387Y530787D01*
G01X-1517420Y524137D02*
X-1517587Y524253D01*
Y524487D01*
X-1517420Y524603D01*
X-1517253Y524487D01*
Y524253D01*
X-1517420Y524137D01*
G01X-1510620Y531370D02*
X-1511287Y531137D01*
X-1511787Y530553D01*
X-1512120Y529853D01*
X-1512370Y528920D01*
X-1512453Y527870D01*
X-1512370Y526820D01*
X-1512120Y525887D01*
X-1511787Y525186D01*
X-1511287Y524603D01*
X-1510620Y524370D01*
X-1509953Y524603D01*
X-1509453Y525186D01*
X-1509120Y525887D01*
X-1508870Y526820D01*
X-1508787Y527870D01*
X-1508870Y528920D01*
X-1509120Y529853D01*
X-1509453Y530553D01*
X-1509953Y531137D01*
X-1510620Y531370D01*
G01X-1503820D02*
X-1504487Y531137D01*
X-1504987Y530553D01*
X-1505320Y529853D01*
X-1505570Y528920D01*
X-1505653Y527870D01*
X-1505570Y526820D01*
X-1505320Y525887D01*
X-1504987Y525186D01*
X-1504487Y524603D01*
X-1503820Y524370D01*
X-1503153Y524603D01*
X-1502653Y525186D01*
X-1502320Y525887D01*
X-1502070Y526820D01*
X-1501987Y527870D01*
X-1502070Y528920D01*
X-1502320Y529853D01*
X-1502653Y530553D01*
X-1503153Y531137D01*
X-1503820Y531370D01*
G01X-1497020D02*
X-1497687Y531137D01*
X-1498187Y530553D01*
X-1498520Y529853D01*
X-1498770Y528920D01*
X-1498853Y527870D01*
X-1498770Y526820D01*
X-1498520Y525887D01*
X-1498187Y525186D01*
X-1497687Y524603D01*
X-1497020Y524370D01*
X-1496353Y524603D01*
X-1495853Y525186D01*
X-1495520Y525887D01*
X-1495270Y526820D01*
X-1495187Y527870D01*
X-1495270Y528920D01*
X-1495520Y529853D01*
X-1495853Y530553D01*
X-1496353Y531137D01*
X-1497020Y531370D01*
G01X-1491720Y524137D02*
X-1488720Y531370D01*
G01X-1484503Y526703D02*
X-1482337D01*
G01X-1478453Y525770D02*
X-1477953Y524953D01*
X-1477287Y524487D01*
X-1476537Y524370D01*
X-1475870Y524487D01*
X-1475203Y525070D01*
X-1474787Y525770D01*
X-1474703Y526470D01*
X-1474870Y527286D01*
X-1475453Y527870D01*
X-1476037Y528103D01*
X-1476787D01*
G01X-1476037D02*
X-1475537Y528453D01*
X-1475120Y529037D01*
X-1474953Y529737D01*
X-1475120Y530437D01*
X-1475537Y531020D01*
X-1476287Y531370D01*
X-1477037Y531253D01*
X-1477787Y530787D01*
G01X-1469820Y524137D02*
X-1469987Y524253D01*
Y524487D01*
X-1469820Y524603D01*
X-1469653Y524487D01*
Y524253D01*
X-1469820Y524137D01*
G01X-1463020Y531370D02*
X-1463687Y531137D01*
X-1464187Y530553D01*
X-1464520Y529853D01*
X-1464770Y528920D01*
X-1464853Y527870D01*
X-1464770Y526820D01*
X-1464520Y525887D01*
X-1464187Y525186D01*
X-1463687Y524603D01*
X-1463020Y524370D01*
X-1462353Y524603D01*
X-1461853Y525186D01*
X-1461520Y525887D01*
X-1461270Y526820D01*
X-1461187Y527870D01*
X-1461270Y528920D01*
X-1461520Y529853D01*
X-1461853Y530553D01*
X-1462353Y531137D01*
X-1463020Y531370D01*
G01X-1456220D02*
X-1456887Y531137D01*
X-1457387Y530553D01*
X-1457720Y529853D01*
X-1457970Y528920D01*
X-1458053Y527870D01*
X-1457970Y526820D01*
X-1457720Y525887D01*
X-1457387Y525186D01*
X-1456887Y524603D01*
X-1456220Y524370D01*
X-1455553Y524603D01*
X-1455053Y525186D01*
X-1454720Y525887D01*
X-1454470Y526820D01*
X-1454387Y527870D01*
X-1454470Y528920D01*
X-1454720Y529853D01*
X-1455053Y530553D01*
X-1455553Y531137D01*
X-1456220Y531370D01*
G01X-1449420D02*
X-1450087Y531137D01*
X-1450587Y530553D01*
X-1450920Y529853D01*
X-1451170Y528920D01*
X-1451253Y527870D01*
X-1451170Y526820D01*
X-1450920Y525887D01*
X-1450587Y525186D01*
X-1450087Y524603D01*
X-1449420Y524370D01*
X-1448753Y524603D01*
X-1448253Y525186D01*
X-1447920Y525887D01*
X-1447670Y526820D01*
X-1447587Y527870D01*
X-1447670Y528920D01*
X-1447920Y529853D01*
X-1448253Y530553D01*
X-1448753Y531137D01*
X-1449420Y531370D01*
G01X-1531937Y550103D02*
X-1529937D01*
G01X-1531020Y551620D02*
Y548586D01*
G01X-1526053Y549170D02*
X-1525553Y548353D01*
X-1524887Y547887D01*
X-1524137Y547770D01*
X-1523470Y547887D01*
X-1522803Y548470D01*
X-1522387Y549170D01*
X-1522303Y549870D01*
X-1522470Y550686D01*
X-1523053Y551270D01*
X-1523637Y551503D01*
X-1524387D01*
G01X-1523637D02*
X-1523137Y551853D01*
X-1522720Y552437D01*
X-1522553Y553137D01*
X-1522720Y553837D01*
X-1523137Y554420D01*
X-1523887Y554770D01*
X-1524637Y554653D01*
X-1525387Y554187D01*
G01X-1517420Y547537D02*
X-1517587Y547653D01*
Y547887D01*
X-1517420Y548003D01*
X-1517253Y547887D01*
Y547653D01*
X-1517420Y547537D01*
G01X-1510620Y554770D02*
X-1511287Y554537D01*
X-1511787Y553953D01*
X-1512120Y553253D01*
X-1512370Y552320D01*
X-1512453Y551270D01*
X-1512370Y550220D01*
X-1512120Y549287D01*
X-1511787Y548586D01*
X-1511287Y548003D01*
X-1510620Y547770D01*
X-1509953Y548003D01*
X-1509453Y548586D01*
X-1509120Y549287D01*
X-1508870Y550220D01*
X-1508787Y551270D01*
X-1508870Y552320D01*
X-1509120Y553253D01*
X-1509453Y553953D01*
X-1509953Y554537D01*
X-1510620Y554770D01*
G01X-1503820D02*
X-1504487Y554537D01*
X-1504987Y553953D01*
X-1505320Y553253D01*
X-1505570Y552320D01*
X-1505653Y551270D01*
X-1505570Y550220D01*
X-1505320Y549287D01*
X-1504987Y548586D01*
X-1504487Y548003D01*
X-1503820Y547770D01*
X-1503153Y548003D01*
X-1502653Y548586D01*
X-1502320Y549287D01*
X-1502070Y550220D01*
X-1501987Y551270D01*
X-1502070Y552320D01*
X-1502320Y553253D01*
X-1502653Y553953D01*
X-1503153Y554537D01*
X-1503820Y554770D01*
G01X-1497020D02*
X-1497687Y554537D01*
X-1498187Y553953D01*
X-1498520Y553253D01*
X-1498770Y552320D01*
X-1498853Y551270D01*
X-1498770Y550220D01*
X-1498520Y549287D01*
X-1498187Y548586D01*
X-1497687Y548003D01*
X-1497020Y547770D01*
X-1496353Y548003D01*
X-1495853Y548586D01*
X-1495520Y549287D01*
X-1495270Y550220D01*
X-1495187Y551270D01*
X-1495270Y552320D01*
X-1495520Y553253D01*
X-1495853Y553953D01*
X-1496353Y554537D01*
X-1497020Y554770D01*
G01X-1491720Y547537D02*
X-1488720Y554770D01*
G01X-1484503Y550103D02*
X-1482337D01*
G01X-1478453Y549170D02*
X-1477953Y548353D01*
X-1477287Y547887D01*
X-1476537Y547770D01*
X-1475870Y547887D01*
X-1475203Y548470D01*
X-1474787Y549170D01*
X-1474703Y549870D01*
X-1474870Y550686D01*
X-1475453Y551270D01*
X-1476037Y551503D01*
X-1476787D01*
G01X-1476037D02*
X-1475537Y551853D01*
X-1475120Y552437D01*
X-1474953Y553137D01*
X-1475120Y553837D01*
X-1475537Y554420D01*
X-1476287Y554770D01*
X-1477037Y554653D01*
X-1477787Y554187D01*
G01X-1469820Y547537D02*
X-1469987Y547653D01*
Y547887D01*
X-1469820Y548003D01*
X-1469653Y547887D01*
Y547653D01*
X-1469820Y547537D01*
G01X-1463020Y554770D02*
X-1463687Y554537D01*
X-1464187Y553953D01*
X-1464520Y553253D01*
X-1464770Y552320D01*
X-1464853Y551270D01*
X-1464770Y550220D01*
X-1464520Y549287D01*
X-1464187Y548586D01*
X-1463687Y548003D01*
X-1463020Y547770D01*
X-1462353Y548003D01*
X-1461853Y548586D01*
X-1461520Y549287D01*
X-1461270Y550220D01*
X-1461187Y551270D01*
X-1461270Y552320D01*
X-1461520Y553253D01*
X-1461853Y553953D01*
X-1462353Y554537D01*
X-1463020Y554770D01*
G01X-1456220D02*
X-1456887Y554537D01*
X-1457387Y553953D01*
X-1457720Y553253D01*
X-1457970Y552320D01*
X-1458053Y551270D01*
X-1457970Y550220D01*
X-1457720Y549287D01*
X-1457387Y548586D01*
X-1456887Y548003D01*
X-1456220Y547770D01*
X-1455553Y548003D01*
X-1455053Y548586D01*
X-1454720Y549287D01*
X-1454470Y550220D01*
X-1454387Y551270D01*
X-1454470Y552320D01*
X-1454720Y553253D01*
X-1455053Y553953D01*
X-1455553Y554537D01*
X-1456220Y554770D01*
G01X-1449420D02*
X-1450087Y554537D01*
X-1450587Y553953D01*
X-1450920Y553253D01*
X-1451170Y552320D01*
X-1451253Y551270D01*
X-1451170Y550220D01*
X-1450920Y549287D01*
X-1450587Y548586D01*
X-1450087Y548003D01*
X-1449420Y547770D01*
X-1448753Y548003D01*
X-1448253Y548586D01*
X-1447920Y549287D01*
X-1447670Y550220D01*
X-1447587Y551270D01*
X-1447670Y552320D01*
X-1447920Y553253D01*
X-1448253Y553953D01*
X-1448753Y554537D01*
X-1449420Y554770D01*
G01X-1531937Y573503D02*
X-1529937D01*
G01X-1531020Y575020D02*
Y571986D01*
G01X-1525803Y577003D02*
X-1525303Y577703D01*
X-1524720Y578053D01*
X-1524053Y578170D01*
X-1523220Y577937D01*
X-1522637Y577353D01*
X-1522470Y576653D01*
X-1522553Y575953D01*
X-1522887Y575370D01*
X-1524553Y574203D01*
X-1525303Y573387D01*
X-1525803Y572220D01*
X-1525970Y571170D01*
X-1522470D01*
G01X-1517420Y570937D02*
X-1517587Y571053D01*
Y571287D01*
X-1517420Y571403D01*
X-1517253Y571287D01*
Y571053D01*
X-1517420Y570937D01*
G01X-1510620Y578170D02*
X-1511287Y577937D01*
X-1511787Y577353D01*
X-1512120Y576653D01*
X-1512370Y575720D01*
X-1512453Y574670D01*
X-1512370Y573620D01*
X-1512120Y572687D01*
X-1511787Y571986D01*
X-1511287Y571403D01*
X-1510620Y571170D01*
X-1509953Y571403D01*
X-1509453Y571986D01*
X-1509120Y572687D01*
X-1508870Y573620D01*
X-1508787Y574670D01*
X-1508870Y575720D01*
X-1509120Y576653D01*
X-1509453Y577353D01*
X-1509953Y577937D01*
X-1510620Y578170D01*
G01X-1503820D02*
X-1504487Y577937D01*
X-1504987Y577353D01*
X-1505320Y576653D01*
X-1505570Y575720D01*
X-1505653Y574670D01*
X-1505570Y573620D01*
X-1505320Y572687D01*
X-1504987Y571986D01*
X-1504487Y571403D01*
X-1503820Y571170D01*
X-1503153Y571403D01*
X-1502653Y571986D01*
X-1502320Y572687D01*
X-1502070Y573620D01*
X-1501987Y574670D01*
X-1502070Y575720D01*
X-1502320Y576653D01*
X-1502653Y577353D01*
X-1503153Y577937D01*
X-1503820Y578170D01*
G01X-1497020D02*
X-1497687Y577937D01*
X-1498187Y577353D01*
X-1498520Y576653D01*
X-1498770Y575720D01*
X-1498853Y574670D01*
X-1498770Y573620D01*
X-1498520Y572687D01*
X-1498187Y571986D01*
X-1497687Y571403D01*
X-1497020Y571170D01*
X-1496353Y571403D01*
X-1495853Y571986D01*
X-1495520Y572687D01*
X-1495270Y573620D01*
X-1495187Y574670D01*
X-1495270Y575720D01*
X-1495520Y576653D01*
X-1495853Y577353D01*
X-1496353Y577937D01*
X-1497020Y578170D01*
G01X-1491720Y570937D02*
X-1488720Y578170D01*
G01X-1484503Y573503D02*
X-1482337D01*
G01X-1478203Y577003D02*
X-1477703Y577703D01*
X-1477120Y578053D01*
X-1476453Y578170D01*
X-1475620Y577937D01*
X-1475037Y577353D01*
X-1474870Y576653D01*
X-1474953Y575953D01*
X-1475287Y575370D01*
X-1476953Y574203D01*
X-1477703Y573387D01*
X-1478203Y572220D01*
X-1478370Y571170D01*
X-1474870D01*
G01X-1469820Y570937D02*
X-1469987Y571053D01*
Y571287D01*
X-1469820Y571403D01*
X-1469653Y571287D01*
Y571053D01*
X-1469820Y570937D01*
G01X-1463020Y578170D02*
X-1463687Y577937D01*
X-1464187Y577353D01*
X-1464520Y576653D01*
X-1464770Y575720D01*
X-1464853Y574670D01*
X-1464770Y573620D01*
X-1464520Y572687D01*
X-1464187Y571986D01*
X-1463687Y571403D01*
X-1463020Y571170D01*
X-1462353Y571403D01*
X-1461853Y571986D01*
X-1461520Y572687D01*
X-1461270Y573620D01*
X-1461187Y574670D01*
X-1461270Y575720D01*
X-1461520Y576653D01*
X-1461853Y577353D01*
X-1462353Y577937D01*
X-1463020Y578170D01*
G01X-1456220D02*
X-1456887Y577937D01*
X-1457387Y577353D01*
X-1457720Y576653D01*
X-1457970Y575720D01*
X-1458053Y574670D01*
X-1457970Y573620D01*
X-1457720Y572687D01*
X-1457387Y571986D01*
X-1456887Y571403D01*
X-1456220Y571170D01*
X-1455553Y571403D01*
X-1455053Y571986D01*
X-1454720Y572687D01*
X-1454470Y573620D01*
X-1454387Y574670D01*
X-1454470Y575720D01*
X-1454720Y576653D01*
X-1455053Y577353D01*
X-1455553Y577937D01*
X-1456220Y578170D01*
G01X-1449420D02*
X-1450087Y577937D01*
X-1450587Y577353D01*
X-1450920Y576653D01*
X-1451170Y575720D01*
X-1451253Y574670D01*
X-1451170Y573620D01*
X-1450920Y572687D01*
X-1450587Y571986D01*
X-1450087Y571403D01*
X-1449420Y571170D01*
X-1448753Y571403D01*
X-1448253Y571986D01*
X-1447920Y572687D01*
X-1447670Y573620D01*
X-1447587Y574670D01*
X-1447670Y575720D01*
X-1447920Y576653D01*
X-1448253Y577353D01*
X-1448753Y577937D01*
X-1449420Y578170D01*
G01X-1531937Y596903D02*
X-1529937D01*
G01X-1531020Y598420D02*
Y595386D01*
G01X-1526053Y595970D02*
X-1525553Y595153D01*
X-1524887Y594687D01*
X-1524137Y594570D01*
X-1523470Y594687D01*
X-1522803Y595270D01*
X-1522387Y595970D01*
X-1522303Y596670D01*
X-1522470Y597486D01*
X-1523053Y598070D01*
X-1523637Y598303D01*
X-1524387D01*
G01X-1523637D02*
X-1523137Y598653D01*
X-1522720Y599237D01*
X-1522553Y599937D01*
X-1522720Y600637D01*
X-1523137Y601220D01*
X-1523887Y601570D01*
X-1524637Y601453D01*
X-1525387Y600987D01*
G01X-1517420Y594337D02*
X-1517587Y594453D01*
Y594687D01*
X-1517420Y594803D01*
X-1517253Y594687D01*
Y594453D01*
X-1517420Y594337D01*
G01X-1510620Y601570D02*
X-1511287Y601337D01*
X-1511787Y600753D01*
X-1512120Y600053D01*
X-1512370Y599120D01*
X-1512453Y598070D01*
X-1512370Y597020D01*
X-1512120Y596087D01*
X-1511787Y595386D01*
X-1511287Y594803D01*
X-1510620Y594570D01*
X-1509953Y594803D01*
X-1509453Y595386D01*
X-1509120Y596087D01*
X-1508870Y597020D01*
X-1508787Y598070D01*
X-1508870Y599120D01*
X-1509120Y600053D01*
X-1509453Y600753D01*
X-1509953Y601337D01*
X-1510620Y601570D01*
G01X-1503820D02*
X-1504487Y601337D01*
X-1504987Y600753D01*
X-1505320Y600053D01*
X-1505570Y599120D01*
X-1505653Y598070D01*
X-1505570Y597020D01*
X-1505320Y596087D01*
X-1504987Y595386D01*
X-1504487Y594803D01*
X-1503820Y594570D01*
X-1503153Y594803D01*
X-1502653Y595386D01*
X-1502320Y596087D01*
X-1502070Y597020D01*
X-1501987Y598070D01*
X-1502070Y599120D01*
X-1502320Y600053D01*
X-1502653Y600753D01*
X-1503153Y601337D01*
X-1503820Y601570D01*
G01X-1497020D02*
X-1497687Y601337D01*
X-1498187Y600753D01*
X-1498520Y600053D01*
X-1498770Y599120D01*
X-1498853Y598070D01*
X-1498770Y597020D01*
X-1498520Y596087D01*
X-1498187Y595386D01*
X-1497687Y594803D01*
X-1497020Y594570D01*
X-1496353Y594803D01*
X-1495853Y595386D01*
X-1495520Y596087D01*
X-1495270Y597020D01*
X-1495187Y598070D01*
X-1495270Y599120D01*
X-1495520Y600053D01*
X-1495853Y600753D01*
X-1496353Y601337D01*
X-1497020Y601570D01*
G01X-1491720Y594337D02*
X-1488720Y601570D01*
G01X-1484503Y596903D02*
X-1482337D01*
G01X-1478453Y595970D02*
X-1477953Y595153D01*
X-1477287Y594687D01*
X-1476537Y594570D01*
X-1475870Y594687D01*
X-1475203Y595270D01*
X-1474787Y595970D01*
X-1474703Y596670D01*
X-1474870Y597486D01*
X-1475453Y598070D01*
X-1476037Y598303D01*
X-1476787D01*
G01X-1476037D02*
X-1475537Y598653D01*
X-1475120Y599237D01*
X-1474953Y599937D01*
X-1475120Y600637D01*
X-1475537Y601220D01*
X-1476287Y601570D01*
X-1477037Y601453D01*
X-1477787Y600987D01*
G01X-1469820Y594337D02*
X-1469987Y594453D01*
Y594687D01*
X-1469820Y594803D01*
X-1469653Y594687D01*
Y594453D01*
X-1469820Y594337D01*
G01X-1463020Y601570D02*
X-1463687Y601337D01*
X-1464187Y600753D01*
X-1464520Y600053D01*
X-1464770Y599120D01*
X-1464853Y598070D01*
X-1464770Y597020D01*
X-1464520Y596087D01*
X-1464187Y595386D01*
X-1463687Y594803D01*
X-1463020Y594570D01*
X-1462353Y594803D01*
X-1461853Y595386D01*
X-1461520Y596087D01*
X-1461270Y597020D01*
X-1461187Y598070D01*
X-1461270Y599120D01*
X-1461520Y600053D01*
X-1461853Y600753D01*
X-1462353Y601337D01*
X-1463020Y601570D01*
G01X-1456220D02*
X-1456887Y601337D01*
X-1457387Y600753D01*
X-1457720Y600053D01*
X-1457970Y599120D01*
X-1458053Y598070D01*
X-1457970Y597020D01*
X-1457720Y596087D01*
X-1457387Y595386D01*
X-1456887Y594803D01*
X-1456220Y594570D01*
X-1455553Y594803D01*
X-1455053Y595386D01*
X-1454720Y596087D01*
X-1454470Y597020D01*
X-1454387Y598070D01*
X-1454470Y599120D01*
X-1454720Y600053D01*
X-1455053Y600753D01*
X-1455553Y601337D01*
X-1456220Y601570D01*
G01X-1449420D02*
X-1450087Y601337D01*
X-1450587Y600753D01*
X-1450920Y600053D01*
X-1451170Y599120D01*
X-1451253Y598070D01*
X-1451170Y597020D01*
X-1450920Y596087D01*
X-1450587Y595386D01*
X-1450087Y594803D01*
X-1449420Y594570D01*
X-1448753Y594803D01*
X-1448253Y595386D01*
X-1447920Y596087D01*
X-1447670Y597020D01*
X-1447587Y598070D01*
X-1447670Y599120D01*
X-1447920Y600053D01*
X-1448253Y600753D01*
X-1448753Y601337D01*
X-1449420Y601570D01*
G01X-1531937Y620303D02*
X-1529937D01*
G01X-1531020Y621820D02*
Y618786D01*
G01X-1526053Y619370D02*
X-1525553Y618553D01*
X-1524887Y618087D01*
X-1524137Y617970D01*
X-1523470Y618087D01*
X-1522803Y618670D01*
X-1522387Y619370D01*
X-1522303Y620070D01*
X-1522470Y620886D01*
X-1523053Y621470D01*
X-1523637Y621703D01*
X-1524387D01*
G01X-1523637D02*
X-1523137Y622053D01*
X-1522720Y622637D01*
X-1522553Y623337D01*
X-1522720Y624037D01*
X-1523137Y624620D01*
X-1523887Y624970D01*
X-1524637Y624853D01*
X-1525387Y624387D01*
G01X-1517420Y617737D02*
X-1517587Y617853D01*
Y618087D01*
X-1517420Y618203D01*
X-1517253Y618087D01*
Y617853D01*
X-1517420Y617737D01*
G01X-1510620Y624970D02*
X-1511287Y624737D01*
X-1511787Y624153D01*
X-1512120Y623453D01*
X-1512370Y622520D01*
X-1512453Y621470D01*
X-1512370Y620420D01*
X-1512120Y619487D01*
X-1511787Y618786D01*
X-1511287Y618203D01*
X-1510620Y617970D01*
X-1509953Y618203D01*
X-1509453Y618786D01*
X-1509120Y619487D01*
X-1508870Y620420D01*
X-1508787Y621470D01*
X-1508870Y622520D01*
X-1509120Y623453D01*
X-1509453Y624153D01*
X-1509953Y624737D01*
X-1510620Y624970D01*
G01X-1503820D02*
X-1504487Y624737D01*
X-1504987Y624153D01*
X-1505320Y623453D01*
X-1505570Y622520D01*
X-1505653Y621470D01*
X-1505570Y620420D01*
X-1505320Y619487D01*
X-1504987Y618786D01*
X-1504487Y618203D01*
X-1503820Y617970D01*
X-1503153Y618203D01*
X-1502653Y618786D01*
X-1502320Y619487D01*
X-1502070Y620420D01*
X-1501987Y621470D01*
X-1502070Y622520D01*
X-1502320Y623453D01*
X-1502653Y624153D01*
X-1503153Y624737D01*
X-1503820Y624970D01*
G01X-1497020D02*
X-1497687Y624737D01*
X-1498187Y624153D01*
X-1498520Y623453D01*
X-1498770Y622520D01*
X-1498853Y621470D01*
X-1498770Y620420D01*
X-1498520Y619487D01*
X-1498187Y618786D01*
X-1497687Y618203D01*
X-1497020Y617970D01*
X-1496353Y618203D01*
X-1495853Y618786D01*
X-1495520Y619487D01*
X-1495270Y620420D01*
X-1495187Y621470D01*
X-1495270Y622520D01*
X-1495520Y623453D01*
X-1495853Y624153D01*
X-1496353Y624737D01*
X-1497020Y624970D01*
G01X-1491720Y617737D02*
X-1488720Y624970D01*
G01X-1484503Y620303D02*
X-1482337D01*
G01X-1478453Y619370D02*
X-1477953Y618553D01*
X-1477287Y618087D01*
X-1476537Y617970D01*
X-1475870Y618087D01*
X-1475203Y618670D01*
X-1474787Y619370D01*
X-1474703Y620070D01*
X-1474870Y620886D01*
X-1475453Y621470D01*
X-1476037Y621703D01*
X-1476787D01*
G01X-1476037D02*
X-1475537Y622053D01*
X-1475120Y622637D01*
X-1474953Y623337D01*
X-1475120Y624037D01*
X-1475537Y624620D01*
X-1476287Y624970D01*
X-1477037Y624853D01*
X-1477787Y624387D01*
G01X-1469820Y617737D02*
X-1469987Y617853D01*
Y618087D01*
X-1469820Y618203D01*
X-1469653Y618087D01*
Y617853D01*
X-1469820Y617737D01*
G01X-1463020Y624970D02*
X-1463687Y624737D01*
X-1464187Y624153D01*
X-1464520Y623453D01*
X-1464770Y622520D01*
X-1464853Y621470D01*
X-1464770Y620420D01*
X-1464520Y619487D01*
X-1464187Y618786D01*
X-1463687Y618203D01*
X-1463020Y617970D01*
X-1462353Y618203D01*
X-1461853Y618786D01*
X-1461520Y619487D01*
X-1461270Y620420D01*
X-1461187Y621470D01*
X-1461270Y622520D01*
X-1461520Y623453D01*
X-1461853Y624153D01*
X-1462353Y624737D01*
X-1463020Y624970D01*
G01X-1456220D02*
X-1456887Y624737D01*
X-1457387Y624153D01*
X-1457720Y623453D01*
X-1457970Y622520D01*
X-1458053Y621470D01*
X-1457970Y620420D01*
X-1457720Y619487D01*
X-1457387Y618786D01*
X-1456887Y618203D01*
X-1456220Y617970D01*
X-1455553Y618203D01*
X-1455053Y618786D01*
X-1454720Y619487D01*
X-1454470Y620420D01*
X-1454387Y621470D01*
X-1454470Y622520D01*
X-1454720Y623453D01*
X-1455053Y624153D01*
X-1455553Y624737D01*
X-1456220Y624970D01*
G01X-1449420D02*
X-1450087Y624737D01*
X-1450587Y624153D01*
X-1450920Y623453D01*
X-1451170Y622520D01*
X-1451253Y621470D01*
X-1451170Y620420D01*
X-1450920Y619487D01*
X-1450587Y618786D01*
X-1450087Y618203D01*
X-1449420Y617970D01*
X-1448753Y618203D01*
X-1448253Y618786D01*
X-1447920Y619487D01*
X-1447670Y620420D01*
X-1447587Y621470D01*
X-1447670Y622520D01*
X-1447920Y623453D01*
X-1448253Y624153D01*
X-1448753Y624737D01*
X-1449420Y624970D01*
G01X-1531937Y643703D02*
X-1529937D01*
G01X-1531020Y645220D02*
Y642186D01*
G01X-1525803Y647203D02*
X-1525303Y647903D01*
X-1524720Y648253D01*
X-1524053Y648370D01*
X-1523220Y648137D01*
X-1522637Y647553D01*
X-1522470Y646853D01*
X-1522553Y646153D01*
X-1522887Y645570D01*
X-1524553Y644403D01*
X-1525303Y643587D01*
X-1525803Y642420D01*
X-1525970Y641370D01*
X-1522470D01*
G01X-1517420Y641137D02*
X-1517587Y641253D01*
Y641487D01*
X-1517420Y641603D01*
X-1517253Y641487D01*
Y641253D01*
X-1517420Y641137D01*
G01X-1510620Y648370D02*
X-1511287Y648137D01*
X-1511787Y647553D01*
X-1512120Y646853D01*
X-1512370Y645920D01*
X-1512453Y644870D01*
X-1512370Y643820D01*
X-1512120Y642887D01*
X-1511787Y642186D01*
X-1511287Y641603D01*
X-1510620Y641370D01*
X-1509953Y641603D01*
X-1509453Y642186D01*
X-1509120Y642887D01*
X-1508870Y643820D01*
X-1508787Y644870D01*
X-1508870Y645920D01*
X-1509120Y646853D01*
X-1509453Y647553D01*
X-1509953Y648137D01*
X-1510620Y648370D01*
G01X-1503820D02*
X-1504487Y648137D01*
X-1504987Y647553D01*
X-1505320Y646853D01*
X-1505570Y645920D01*
X-1505653Y644870D01*
X-1505570Y643820D01*
X-1505320Y642887D01*
X-1504987Y642186D01*
X-1504487Y641603D01*
X-1503820Y641370D01*
X-1503153Y641603D01*
X-1502653Y642186D01*
X-1502320Y642887D01*
X-1502070Y643820D01*
X-1501987Y644870D01*
X-1502070Y645920D01*
X-1502320Y646853D01*
X-1502653Y647553D01*
X-1503153Y648137D01*
X-1503820Y648370D01*
G01X-1497020D02*
X-1497687Y648137D01*
X-1498187Y647553D01*
X-1498520Y646853D01*
X-1498770Y645920D01*
X-1498853Y644870D01*
X-1498770Y643820D01*
X-1498520Y642887D01*
X-1498187Y642186D01*
X-1497687Y641603D01*
X-1497020Y641370D01*
X-1496353Y641603D01*
X-1495853Y642186D01*
X-1495520Y642887D01*
X-1495270Y643820D01*
X-1495187Y644870D01*
X-1495270Y645920D01*
X-1495520Y646853D01*
X-1495853Y647553D01*
X-1496353Y648137D01*
X-1497020Y648370D01*
G01X-1491720Y641137D02*
X-1488720Y648370D01*
G01X-1484503Y643703D02*
X-1482337D01*
G01X-1478203Y647203D02*
X-1477703Y647903D01*
X-1477120Y648253D01*
X-1476453Y648370D01*
X-1475620Y648137D01*
X-1475037Y647553D01*
X-1474870Y646853D01*
X-1474953Y646153D01*
X-1475287Y645570D01*
X-1476953Y644403D01*
X-1477703Y643587D01*
X-1478203Y642420D01*
X-1478370Y641370D01*
X-1474870D01*
G01X-1469820Y641137D02*
X-1469987Y641253D01*
Y641487D01*
X-1469820Y641603D01*
X-1469653Y641487D01*
Y641253D01*
X-1469820Y641137D01*
G01X-1463020Y648370D02*
X-1463687Y648137D01*
X-1464187Y647553D01*
X-1464520Y646853D01*
X-1464770Y645920D01*
X-1464853Y644870D01*
X-1464770Y643820D01*
X-1464520Y642887D01*
X-1464187Y642186D01*
X-1463687Y641603D01*
X-1463020Y641370D01*
X-1462353Y641603D01*
X-1461853Y642186D01*
X-1461520Y642887D01*
X-1461270Y643820D01*
X-1461187Y644870D01*
X-1461270Y645920D01*
X-1461520Y646853D01*
X-1461853Y647553D01*
X-1462353Y648137D01*
X-1463020Y648370D01*
G01X-1456220D02*
X-1456887Y648137D01*
X-1457387Y647553D01*
X-1457720Y646853D01*
X-1457970Y645920D01*
X-1458053Y644870D01*
X-1457970Y643820D01*
X-1457720Y642887D01*
X-1457387Y642186D01*
X-1456887Y641603D01*
X-1456220Y641370D01*
X-1455553Y641603D01*
X-1455053Y642186D01*
X-1454720Y642887D01*
X-1454470Y643820D01*
X-1454387Y644870D01*
X-1454470Y645920D01*
X-1454720Y646853D01*
X-1455053Y647553D01*
X-1455553Y648137D01*
X-1456220Y648370D01*
G01X-1449420D02*
X-1450087Y648137D01*
X-1450587Y647553D01*
X-1450920Y646853D01*
X-1451170Y645920D01*
X-1451253Y644870D01*
X-1451170Y643820D01*
X-1450920Y642887D01*
X-1450587Y642186D01*
X-1450087Y641603D01*
X-1449420Y641370D01*
X-1448753Y641603D01*
X-1448253Y642186D01*
X-1447920Y642887D01*
X-1447670Y643820D01*
X-1447587Y644870D01*
X-1447670Y645920D01*
X-1447920Y646853D01*
X-1448253Y647553D01*
X-1448753Y648137D01*
X-1449420Y648370D01*
G01X-1531937Y667103D02*
X-1529937D01*
G01X-1531020Y668620D02*
Y665586D01*
G01X-1526053Y666170D02*
X-1525553Y665353D01*
X-1524887Y664887D01*
X-1524137Y664770D01*
X-1523470Y664887D01*
X-1522803Y665470D01*
X-1522387Y666170D01*
X-1522303Y666870D01*
X-1522470Y667686D01*
X-1523053Y668270D01*
X-1523637Y668503D01*
X-1524387D01*
G01X-1523637D02*
X-1523137Y668853D01*
X-1522720Y669437D01*
X-1522553Y670137D01*
X-1522720Y670837D01*
X-1523137Y671420D01*
X-1523887Y671770D01*
X-1524637Y671653D01*
X-1525387Y671187D01*
G01X-1517420Y664537D02*
X-1517587Y664653D01*
Y664887D01*
X-1517420Y665003D01*
X-1517253Y664887D01*
Y664653D01*
X-1517420Y664537D01*
G01X-1510620Y671770D02*
X-1511287Y671537D01*
X-1511787Y670953D01*
X-1512120Y670253D01*
X-1512370Y669320D01*
X-1512453Y668270D01*
X-1512370Y667220D01*
X-1512120Y666287D01*
X-1511787Y665586D01*
X-1511287Y665003D01*
X-1510620Y664770D01*
X-1509953Y665003D01*
X-1509453Y665586D01*
X-1509120Y666287D01*
X-1508870Y667220D01*
X-1508787Y668270D01*
X-1508870Y669320D01*
X-1509120Y670253D01*
X-1509453Y670953D01*
X-1509953Y671537D01*
X-1510620Y671770D01*
G01X-1503820D02*
X-1504487Y671537D01*
X-1504987Y670953D01*
X-1505320Y670253D01*
X-1505570Y669320D01*
X-1505653Y668270D01*
X-1505570Y667220D01*
X-1505320Y666287D01*
X-1504987Y665586D01*
X-1504487Y665003D01*
X-1503820Y664770D01*
X-1503153Y665003D01*
X-1502653Y665586D01*
X-1502320Y666287D01*
X-1502070Y667220D01*
X-1501987Y668270D01*
X-1502070Y669320D01*
X-1502320Y670253D01*
X-1502653Y670953D01*
X-1503153Y671537D01*
X-1503820Y671770D01*
G01X-1497020D02*
X-1497687Y671537D01*
X-1498187Y670953D01*
X-1498520Y670253D01*
X-1498770Y669320D01*
X-1498853Y668270D01*
X-1498770Y667220D01*
X-1498520Y666287D01*
X-1498187Y665586D01*
X-1497687Y665003D01*
X-1497020Y664770D01*
X-1496353Y665003D01*
X-1495853Y665586D01*
X-1495520Y666287D01*
X-1495270Y667220D01*
X-1495187Y668270D01*
X-1495270Y669320D01*
X-1495520Y670253D01*
X-1495853Y670953D01*
X-1496353Y671537D01*
X-1497020Y671770D01*
G01X-1491720Y664537D02*
X-1488720Y671770D01*
G01X-1484503Y667103D02*
X-1482337D01*
G01X-1478453Y666170D02*
X-1477953Y665353D01*
X-1477287Y664887D01*
X-1476537Y664770D01*
X-1475870Y664887D01*
X-1475203Y665470D01*
X-1474787Y666170D01*
X-1474703Y666870D01*
X-1474870Y667686D01*
X-1475453Y668270D01*
X-1476037Y668503D01*
X-1476787D01*
G01X-1476037D02*
X-1475537Y668853D01*
X-1475120Y669437D01*
X-1474953Y670137D01*
X-1475120Y670837D01*
X-1475537Y671420D01*
X-1476287Y671770D01*
X-1477037Y671653D01*
X-1477787Y671187D01*
G01X-1469820Y664537D02*
X-1469987Y664653D01*
Y664887D01*
X-1469820Y665003D01*
X-1469653Y664887D01*
Y664653D01*
X-1469820Y664537D01*
G01X-1463020Y671770D02*
X-1463687Y671537D01*
X-1464187Y670953D01*
X-1464520Y670253D01*
X-1464770Y669320D01*
X-1464853Y668270D01*
X-1464770Y667220D01*
X-1464520Y666287D01*
X-1464187Y665586D01*
X-1463687Y665003D01*
X-1463020Y664770D01*
X-1462353Y665003D01*
X-1461853Y665586D01*
X-1461520Y666287D01*
X-1461270Y667220D01*
X-1461187Y668270D01*
X-1461270Y669320D01*
X-1461520Y670253D01*
X-1461853Y670953D01*
X-1462353Y671537D01*
X-1463020Y671770D01*
G01X-1456220D02*
X-1456887Y671537D01*
X-1457387Y670953D01*
X-1457720Y670253D01*
X-1457970Y669320D01*
X-1458053Y668270D01*
X-1457970Y667220D01*
X-1457720Y666287D01*
X-1457387Y665586D01*
X-1456887Y665003D01*
X-1456220Y664770D01*
X-1455553Y665003D01*
X-1455053Y665586D01*
X-1454720Y666287D01*
X-1454470Y667220D01*
X-1454387Y668270D01*
X-1454470Y669320D01*
X-1454720Y670253D01*
X-1455053Y670953D01*
X-1455553Y671537D01*
X-1456220Y671770D01*
G01X-1449420D02*
X-1450087Y671537D01*
X-1450587Y670953D01*
X-1450920Y670253D01*
X-1451170Y669320D01*
X-1451253Y668270D01*
X-1451170Y667220D01*
X-1450920Y666287D01*
X-1450587Y665586D01*
X-1450087Y665003D01*
X-1449420Y664770D01*
X-1448753Y665003D01*
X-1448253Y665586D01*
X-1447920Y666287D01*
X-1447670Y667220D01*
X-1447587Y668270D01*
X-1447670Y669320D01*
X-1447920Y670253D01*
X-1448253Y670953D01*
X-1448753Y671537D01*
X-1449420Y671770D01*
G01X-1531937Y690503D02*
X-1529937D01*
G01X-1531020Y692020D02*
Y688986D01*
G01X-1526053Y689570D02*
X-1525553Y688753D01*
X-1524887Y688287D01*
X-1524137Y688170D01*
X-1523470Y688287D01*
X-1522803Y688870D01*
X-1522387Y689570D01*
X-1522303Y690270D01*
X-1522470Y691086D01*
X-1523053Y691670D01*
X-1523637Y691903D01*
X-1524387D01*
G01X-1523637D02*
X-1523137Y692253D01*
X-1522720Y692837D01*
X-1522553Y693537D01*
X-1522720Y694237D01*
X-1523137Y694820D01*
X-1523887Y695170D01*
X-1524637Y695053D01*
X-1525387Y694587D01*
G01X-1517420Y687937D02*
X-1517587Y688053D01*
Y688287D01*
X-1517420Y688403D01*
X-1517253Y688287D01*
Y688053D01*
X-1517420Y687937D01*
G01X-1510620Y695170D02*
X-1511287Y694937D01*
X-1511787Y694353D01*
X-1512120Y693653D01*
X-1512370Y692720D01*
X-1512453Y691670D01*
X-1512370Y690620D01*
X-1512120Y689687D01*
X-1511787Y688986D01*
X-1511287Y688403D01*
X-1510620Y688170D01*
X-1509953Y688403D01*
X-1509453Y688986D01*
X-1509120Y689687D01*
X-1508870Y690620D01*
X-1508787Y691670D01*
X-1508870Y692720D01*
X-1509120Y693653D01*
X-1509453Y694353D01*
X-1509953Y694937D01*
X-1510620Y695170D01*
G01X-1503820D02*
X-1504487Y694937D01*
X-1504987Y694353D01*
X-1505320Y693653D01*
X-1505570Y692720D01*
X-1505653Y691670D01*
X-1505570Y690620D01*
X-1505320Y689687D01*
X-1504987Y688986D01*
X-1504487Y688403D01*
X-1503820Y688170D01*
X-1503153Y688403D01*
X-1502653Y688986D01*
X-1502320Y689687D01*
X-1502070Y690620D01*
X-1501987Y691670D01*
X-1502070Y692720D01*
X-1502320Y693653D01*
X-1502653Y694353D01*
X-1503153Y694937D01*
X-1503820Y695170D01*
G01X-1497020D02*
X-1497687Y694937D01*
X-1498187Y694353D01*
X-1498520Y693653D01*
X-1498770Y692720D01*
X-1498853Y691670D01*
X-1498770Y690620D01*
X-1498520Y689687D01*
X-1498187Y688986D01*
X-1497687Y688403D01*
X-1497020Y688170D01*
X-1496353Y688403D01*
X-1495853Y688986D01*
X-1495520Y689687D01*
X-1495270Y690620D01*
X-1495187Y691670D01*
X-1495270Y692720D01*
X-1495520Y693653D01*
X-1495853Y694353D01*
X-1496353Y694937D01*
X-1497020Y695170D01*
G01X-1491720Y687937D02*
X-1488720Y695170D01*
G01X-1484503Y690503D02*
X-1482337D01*
G01X-1478453Y689570D02*
X-1477953Y688753D01*
X-1477287Y688287D01*
X-1476537Y688170D01*
X-1475870Y688287D01*
X-1475203Y688870D01*
X-1474787Y689570D01*
X-1474703Y690270D01*
X-1474870Y691086D01*
X-1475453Y691670D01*
X-1476037Y691903D01*
X-1476787D01*
G01X-1476037D02*
X-1475537Y692253D01*
X-1475120Y692837D01*
X-1474953Y693537D01*
X-1475120Y694237D01*
X-1475537Y694820D01*
X-1476287Y695170D01*
X-1477037Y695053D01*
X-1477787Y694587D01*
G01X-1469820Y687937D02*
X-1469987Y688053D01*
Y688287D01*
X-1469820Y688403D01*
X-1469653Y688287D01*
Y688053D01*
X-1469820Y687937D01*
G01X-1463020Y695170D02*
X-1463687Y694937D01*
X-1464187Y694353D01*
X-1464520Y693653D01*
X-1464770Y692720D01*
X-1464853Y691670D01*
X-1464770Y690620D01*
X-1464520Y689687D01*
X-1464187Y688986D01*
X-1463687Y688403D01*
X-1463020Y688170D01*
X-1462353Y688403D01*
X-1461853Y688986D01*
X-1461520Y689687D01*
X-1461270Y690620D01*
X-1461187Y691670D01*
X-1461270Y692720D01*
X-1461520Y693653D01*
X-1461853Y694353D01*
X-1462353Y694937D01*
X-1463020Y695170D01*
G01X-1456220D02*
X-1456887Y694937D01*
X-1457387Y694353D01*
X-1457720Y693653D01*
X-1457970Y692720D01*
X-1458053Y691670D01*
X-1457970Y690620D01*
X-1457720Y689687D01*
X-1457387Y688986D01*
X-1456887Y688403D01*
X-1456220Y688170D01*
X-1455553Y688403D01*
X-1455053Y688986D01*
X-1454720Y689687D01*
X-1454470Y690620D01*
X-1454387Y691670D01*
X-1454470Y692720D01*
X-1454720Y693653D01*
X-1455053Y694353D01*
X-1455553Y694937D01*
X-1456220Y695170D01*
G01X-1449420D02*
X-1450087Y694937D01*
X-1450587Y694353D01*
X-1450920Y693653D01*
X-1451170Y692720D01*
X-1451253Y691670D01*
X-1451170Y690620D01*
X-1450920Y689687D01*
X-1450587Y688986D01*
X-1450087Y688403D01*
X-1449420Y688170D01*
X-1448753Y688403D01*
X-1448253Y688986D01*
X-1447920Y689687D01*
X-1447670Y690620D01*
X-1447587Y691670D01*
X-1447670Y692720D01*
X-1447920Y693653D01*
X-1448253Y694353D01*
X-1448753Y694937D01*
X-1449420Y695170D01*
G01X-1531937Y713903D02*
X-1529937D01*
G01X-1531020Y715420D02*
Y712386D01*
G01X-1525803Y717403D02*
X-1525303Y718103D01*
X-1524720Y718453D01*
X-1524053Y718570D01*
X-1523220Y718337D01*
X-1522637Y717753D01*
X-1522470Y717053D01*
X-1522553Y716353D01*
X-1522887Y715770D01*
X-1524553Y714603D01*
X-1525303Y713787D01*
X-1525803Y712620D01*
X-1525970Y711570D01*
X-1522470D01*
G01X-1517420Y711337D02*
X-1517587Y711453D01*
Y711687D01*
X-1517420Y711803D01*
X-1517253Y711687D01*
Y711453D01*
X-1517420Y711337D01*
G01X-1510620Y718570D02*
X-1511287Y718337D01*
X-1511787Y717753D01*
X-1512120Y717053D01*
X-1512370Y716120D01*
X-1512453Y715070D01*
X-1512370Y714020D01*
X-1512120Y713087D01*
X-1511787Y712386D01*
X-1511287Y711803D01*
X-1510620Y711570D01*
X-1509953Y711803D01*
X-1509453Y712386D01*
X-1509120Y713087D01*
X-1508870Y714020D01*
X-1508787Y715070D01*
X-1508870Y716120D01*
X-1509120Y717053D01*
X-1509453Y717753D01*
X-1509953Y718337D01*
X-1510620Y718570D01*
G01X-1503820D02*
X-1504487Y718337D01*
X-1504987Y717753D01*
X-1505320Y717053D01*
X-1505570Y716120D01*
X-1505653Y715070D01*
X-1505570Y714020D01*
X-1505320Y713087D01*
X-1504987Y712386D01*
X-1504487Y711803D01*
X-1503820Y711570D01*
X-1503153Y711803D01*
X-1502653Y712386D01*
X-1502320Y713087D01*
X-1502070Y714020D01*
X-1501987Y715070D01*
X-1502070Y716120D01*
X-1502320Y717053D01*
X-1502653Y717753D01*
X-1503153Y718337D01*
X-1503820Y718570D01*
G01X-1497020D02*
X-1497687Y718337D01*
X-1498187Y717753D01*
X-1498520Y717053D01*
X-1498770Y716120D01*
X-1498853Y715070D01*
X-1498770Y714020D01*
X-1498520Y713087D01*
X-1498187Y712386D01*
X-1497687Y711803D01*
X-1497020Y711570D01*
X-1496353Y711803D01*
X-1495853Y712386D01*
X-1495520Y713087D01*
X-1495270Y714020D01*
X-1495187Y715070D01*
X-1495270Y716120D01*
X-1495520Y717053D01*
X-1495853Y717753D01*
X-1496353Y718337D01*
X-1497020Y718570D01*
G01X-1491720Y711337D02*
X-1488720Y718570D01*
G01X-1484503Y713903D02*
X-1482337D01*
G01X-1478203Y717403D02*
X-1477703Y718103D01*
X-1477120Y718453D01*
X-1476453Y718570D01*
X-1475620Y718337D01*
X-1475037Y717753D01*
X-1474870Y717053D01*
X-1474953Y716353D01*
X-1475287Y715770D01*
X-1476953Y714603D01*
X-1477703Y713787D01*
X-1478203Y712620D01*
X-1478370Y711570D01*
X-1474870D01*
G01X-1469820Y711337D02*
X-1469987Y711453D01*
Y711687D01*
X-1469820Y711803D01*
X-1469653Y711687D01*
Y711453D01*
X-1469820Y711337D01*
G01X-1463020Y718570D02*
X-1463687Y718337D01*
X-1464187Y717753D01*
X-1464520Y717053D01*
X-1464770Y716120D01*
X-1464853Y715070D01*
X-1464770Y714020D01*
X-1464520Y713087D01*
X-1464187Y712386D01*
X-1463687Y711803D01*
X-1463020Y711570D01*
X-1462353Y711803D01*
X-1461853Y712386D01*
X-1461520Y713087D01*
X-1461270Y714020D01*
X-1461187Y715070D01*
X-1461270Y716120D01*
X-1461520Y717053D01*
X-1461853Y717753D01*
X-1462353Y718337D01*
X-1463020Y718570D01*
G01X-1456220D02*
X-1456887Y718337D01*
X-1457387Y717753D01*
X-1457720Y717053D01*
X-1457970Y716120D01*
X-1458053Y715070D01*
X-1457970Y714020D01*
X-1457720Y713087D01*
X-1457387Y712386D01*
X-1456887Y711803D01*
X-1456220Y711570D01*
X-1455553Y711803D01*
X-1455053Y712386D01*
X-1454720Y713087D01*
X-1454470Y714020D01*
X-1454387Y715070D01*
X-1454470Y716120D01*
X-1454720Y717053D01*
X-1455053Y717753D01*
X-1455553Y718337D01*
X-1456220Y718570D01*
G01X-1449420D02*
X-1450087Y718337D01*
X-1450587Y717753D01*
X-1450920Y717053D01*
X-1451170Y716120D01*
X-1451253Y715070D01*
X-1451170Y714020D01*
X-1450920Y713087D01*
X-1450587Y712386D01*
X-1450087Y711803D01*
X-1449420Y711570D01*
X-1448753Y711803D01*
X-1448253Y712386D01*
X-1447920Y713087D01*
X-1447670Y714020D01*
X-1447587Y715070D01*
X-1447670Y716120D01*
X-1447920Y717053D01*
X-1448253Y717753D01*
X-1448753Y718337D01*
X-1449420Y718570D01*
G01X-1531937Y737303D02*
X-1529937D01*
G01X-1531020Y738820D02*
Y735786D01*
G01X-1525803Y740803D02*
X-1525303Y741503D01*
X-1524720Y741853D01*
X-1524053Y741970D01*
X-1523220Y741737D01*
X-1522637Y741153D01*
X-1522470Y740453D01*
X-1522553Y739753D01*
X-1522887Y739170D01*
X-1524553Y738003D01*
X-1525303Y737187D01*
X-1525803Y736020D01*
X-1525970Y734970D01*
X-1522470D01*
G01X-1517420Y734737D02*
X-1517587Y734853D01*
Y735087D01*
X-1517420Y735203D01*
X-1517253Y735087D01*
Y734853D01*
X-1517420Y734737D01*
G01X-1510620Y741970D02*
X-1511287Y741737D01*
X-1511787Y741153D01*
X-1512120Y740453D01*
X-1512370Y739520D01*
X-1512453Y738470D01*
X-1512370Y737420D01*
X-1512120Y736487D01*
X-1511787Y735786D01*
X-1511287Y735203D01*
X-1510620Y734970D01*
X-1509953Y735203D01*
X-1509453Y735786D01*
X-1509120Y736487D01*
X-1508870Y737420D01*
X-1508787Y738470D01*
X-1508870Y739520D01*
X-1509120Y740453D01*
X-1509453Y741153D01*
X-1509953Y741737D01*
X-1510620Y741970D01*
G01X-1503820D02*
X-1504487Y741737D01*
X-1504987Y741153D01*
X-1505320Y740453D01*
X-1505570Y739520D01*
X-1505653Y738470D01*
X-1505570Y737420D01*
X-1505320Y736487D01*
X-1504987Y735786D01*
X-1504487Y735203D01*
X-1503820Y734970D01*
X-1503153Y735203D01*
X-1502653Y735786D01*
X-1502320Y736487D01*
X-1502070Y737420D01*
X-1501987Y738470D01*
X-1502070Y739520D01*
X-1502320Y740453D01*
X-1502653Y741153D01*
X-1503153Y741737D01*
X-1503820Y741970D01*
G01X-1497020D02*
X-1497687Y741737D01*
X-1498187Y741153D01*
X-1498520Y740453D01*
X-1498770Y739520D01*
X-1498853Y738470D01*
X-1498770Y737420D01*
X-1498520Y736487D01*
X-1498187Y735786D01*
X-1497687Y735203D01*
X-1497020Y734970D01*
X-1496353Y735203D01*
X-1495853Y735786D01*
X-1495520Y736487D01*
X-1495270Y737420D01*
X-1495187Y738470D01*
X-1495270Y739520D01*
X-1495520Y740453D01*
X-1495853Y741153D01*
X-1496353Y741737D01*
X-1497020Y741970D01*
G01X-1491720Y734737D02*
X-1488720Y741970D01*
G01X-1484503Y737303D02*
X-1482337D01*
G01X-1478203Y740803D02*
X-1477703Y741503D01*
X-1477120Y741853D01*
X-1476453Y741970D01*
X-1475620Y741737D01*
X-1475037Y741153D01*
X-1474870Y740453D01*
X-1474953Y739753D01*
X-1475287Y739170D01*
X-1476953Y738003D01*
X-1477703Y737187D01*
X-1478203Y736020D01*
X-1478370Y734970D01*
X-1474870D01*
G01X-1469820Y734737D02*
X-1469987Y734853D01*
Y735087D01*
X-1469820Y735203D01*
X-1469653Y735087D01*
Y734853D01*
X-1469820Y734737D01*
G01X-1463020Y741970D02*
X-1463687Y741737D01*
X-1464187Y741153D01*
X-1464520Y740453D01*
X-1464770Y739520D01*
X-1464853Y738470D01*
X-1464770Y737420D01*
X-1464520Y736487D01*
X-1464187Y735786D01*
X-1463687Y735203D01*
X-1463020Y734970D01*
X-1462353Y735203D01*
X-1461853Y735786D01*
X-1461520Y736487D01*
X-1461270Y737420D01*
X-1461187Y738470D01*
X-1461270Y739520D01*
X-1461520Y740453D01*
X-1461853Y741153D01*
X-1462353Y741737D01*
X-1463020Y741970D01*
G01X-1456220D02*
X-1456887Y741737D01*
X-1457387Y741153D01*
X-1457720Y740453D01*
X-1457970Y739520D01*
X-1458053Y738470D01*
X-1457970Y737420D01*
X-1457720Y736487D01*
X-1457387Y735786D01*
X-1456887Y735203D01*
X-1456220Y734970D01*
X-1455553Y735203D01*
X-1455053Y735786D01*
X-1454720Y736487D01*
X-1454470Y737420D01*
X-1454387Y738470D01*
X-1454470Y739520D01*
X-1454720Y740453D01*
X-1455053Y741153D01*
X-1455553Y741737D01*
X-1456220Y741970D01*
G01X-1449420D02*
X-1450087Y741737D01*
X-1450587Y741153D01*
X-1450920Y740453D01*
X-1451170Y739520D01*
X-1451253Y738470D01*
X-1451170Y737420D01*
X-1450920Y736487D01*
X-1450587Y735786D01*
X-1450087Y735203D01*
X-1449420Y734970D01*
X-1448753Y735203D01*
X-1448253Y735786D01*
X-1447920Y736487D01*
X-1447670Y737420D01*
X-1447587Y738470D01*
X-1447670Y739520D01*
X-1447920Y740453D01*
X-1448253Y741153D01*
X-1448753Y741737D01*
X-1449420Y741970D01*
G01X-1531937Y760703D02*
X-1529937D01*
G01X-1531020Y762220D02*
Y759186D01*
G01X-1526053Y759770D02*
X-1525553Y758953D01*
X-1524887Y758487D01*
X-1524137Y758370D01*
X-1523470Y758487D01*
X-1522803Y759070D01*
X-1522387Y759770D01*
X-1522303Y760470D01*
X-1522470Y761286D01*
X-1523053Y761870D01*
X-1523637Y762103D01*
X-1524387D01*
G01X-1523637D02*
X-1523137Y762453D01*
X-1522720Y763037D01*
X-1522553Y763737D01*
X-1522720Y764437D01*
X-1523137Y765020D01*
X-1523887Y765370D01*
X-1524637Y765253D01*
X-1525387Y764787D01*
G01X-1517420Y758137D02*
X-1517587Y758253D01*
Y758487D01*
X-1517420Y758603D01*
X-1517253Y758487D01*
Y758253D01*
X-1517420Y758137D01*
G01X-1510620Y765370D02*
X-1511287Y765137D01*
X-1511787Y764553D01*
X-1512120Y763853D01*
X-1512370Y762920D01*
X-1512453Y761870D01*
X-1512370Y760820D01*
X-1512120Y759887D01*
X-1511787Y759186D01*
X-1511287Y758603D01*
X-1510620Y758370D01*
X-1509953Y758603D01*
X-1509453Y759186D01*
X-1509120Y759887D01*
X-1508870Y760820D01*
X-1508787Y761870D01*
X-1508870Y762920D01*
X-1509120Y763853D01*
X-1509453Y764553D01*
X-1509953Y765137D01*
X-1510620Y765370D01*
G01X-1503820D02*
X-1504487Y765137D01*
X-1504987Y764553D01*
X-1505320Y763853D01*
X-1505570Y762920D01*
X-1505653Y761870D01*
X-1505570Y760820D01*
X-1505320Y759887D01*
X-1504987Y759186D01*
X-1504487Y758603D01*
X-1503820Y758370D01*
X-1503153Y758603D01*
X-1502653Y759186D01*
X-1502320Y759887D01*
X-1502070Y760820D01*
X-1501987Y761870D01*
X-1502070Y762920D01*
X-1502320Y763853D01*
X-1502653Y764553D01*
X-1503153Y765137D01*
X-1503820Y765370D01*
G01X-1497020D02*
X-1497687Y765137D01*
X-1498187Y764553D01*
X-1498520Y763853D01*
X-1498770Y762920D01*
X-1498853Y761870D01*
X-1498770Y760820D01*
X-1498520Y759887D01*
X-1498187Y759186D01*
X-1497687Y758603D01*
X-1497020Y758370D01*
X-1496353Y758603D01*
X-1495853Y759186D01*
X-1495520Y759887D01*
X-1495270Y760820D01*
X-1495187Y761870D01*
X-1495270Y762920D01*
X-1495520Y763853D01*
X-1495853Y764553D01*
X-1496353Y765137D01*
X-1497020Y765370D01*
G01X-1491720Y758137D02*
X-1488720Y765370D01*
G01X-1484503Y760703D02*
X-1482337D01*
G01X-1478453Y759770D02*
X-1477953Y758953D01*
X-1477287Y758487D01*
X-1476537Y758370D01*
X-1475870Y758487D01*
X-1475203Y759070D01*
X-1474787Y759770D01*
X-1474703Y760470D01*
X-1474870Y761286D01*
X-1475453Y761870D01*
X-1476037Y762103D01*
X-1476787D01*
G01X-1476037D02*
X-1475537Y762453D01*
X-1475120Y763037D01*
X-1474953Y763737D01*
X-1475120Y764437D01*
X-1475537Y765020D01*
X-1476287Y765370D01*
X-1477037Y765253D01*
X-1477787Y764787D01*
G01X-1469820Y758137D02*
X-1469987Y758253D01*
Y758487D01*
X-1469820Y758603D01*
X-1469653Y758487D01*
Y758253D01*
X-1469820Y758137D01*
G01X-1463020Y765370D02*
X-1463687Y765137D01*
X-1464187Y764553D01*
X-1464520Y763853D01*
X-1464770Y762920D01*
X-1464853Y761870D01*
X-1464770Y760820D01*
X-1464520Y759887D01*
X-1464187Y759186D01*
X-1463687Y758603D01*
X-1463020Y758370D01*
X-1462353Y758603D01*
X-1461853Y759186D01*
X-1461520Y759887D01*
X-1461270Y760820D01*
X-1461187Y761870D01*
X-1461270Y762920D01*
X-1461520Y763853D01*
X-1461853Y764553D01*
X-1462353Y765137D01*
X-1463020Y765370D01*
G01X-1456220D02*
X-1456887Y765137D01*
X-1457387Y764553D01*
X-1457720Y763853D01*
X-1457970Y762920D01*
X-1458053Y761870D01*
X-1457970Y760820D01*
X-1457720Y759887D01*
X-1457387Y759186D01*
X-1456887Y758603D01*
X-1456220Y758370D01*
X-1455553Y758603D01*
X-1455053Y759186D01*
X-1454720Y759887D01*
X-1454470Y760820D01*
X-1454387Y761870D01*
X-1454470Y762920D01*
X-1454720Y763853D01*
X-1455053Y764553D01*
X-1455553Y765137D01*
X-1456220Y765370D01*
G01X-1449420D02*
X-1450087Y765137D01*
X-1450587Y764553D01*
X-1450920Y763853D01*
X-1451170Y762920D01*
X-1451253Y761870D01*
X-1451170Y760820D01*
X-1450920Y759887D01*
X-1450587Y759186D01*
X-1450087Y758603D01*
X-1449420Y758370D01*
X-1448753Y758603D01*
X-1448253Y759186D01*
X-1447920Y759887D01*
X-1447670Y760820D01*
X-1447587Y761870D01*
X-1447670Y762920D01*
X-1447920Y763853D01*
X-1448253Y764553D01*
X-1448753Y765137D01*
X-1449420Y765370D01*
G01X-1535337Y784103D02*
X-1533337D01*
G01X-1534420Y785620D02*
Y782586D01*
G01X-1529203Y787603D02*
X-1528703Y788303D01*
X-1528120Y788653D01*
X-1527453Y788770D01*
X-1526620Y788537D01*
X-1526037Y787953D01*
X-1525870Y787253D01*
X-1525953Y786553D01*
X-1526287Y785970D01*
X-1527953Y784803D01*
X-1528703Y783987D01*
X-1529203Y782820D01*
X-1529370Y781770D01*
X-1525870D01*
G01X-1520820Y781537D02*
X-1520987Y781653D01*
Y781887D01*
X-1520820Y782003D01*
X-1520653Y781887D01*
Y781653D01*
X-1520820Y781537D01*
G01X-1514020Y788770D02*
X-1514687Y788537D01*
X-1515187Y787953D01*
X-1515520Y787253D01*
X-1515770Y786320D01*
X-1515853Y785270D01*
X-1515770Y784220D01*
X-1515520Y783287D01*
X-1515187Y782586D01*
X-1514687Y782003D01*
X-1514020Y781770D01*
X-1513353Y782003D01*
X-1512853Y782586D01*
X-1512520Y783287D01*
X-1512270Y784220D01*
X-1512187Y785270D01*
X-1512270Y786320D01*
X-1512520Y787253D01*
X-1512853Y787953D01*
X-1513353Y788537D01*
X-1514020Y788770D01*
G01X-1507220D02*
X-1507887Y788537D01*
X-1508387Y787953D01*
X-1508720Y787253D01*
X-1508970Y786320D01*
X-1509053Y785270D01*
X-1508970Y784220D01*
X-1508720Y783287D01*
X-1508387Y782586D01*
X-1507887Y782003D01*
X-1507220Y781770D01*
X-1506553Y782003D01*
X-1506053Y782586D01*
X-1505720Y783287D01*
X-1505470Y784220D01*
X-1505387Y785270D01*
X-1505470Y786320D01*
X-1505720Y787253D01*
X-1506053Y787953D01*
X-1506553Y788537D01*
X-1507220Y788770D01*
G01X-1500420D02*
X-1501087Y788537D01*
X-1501587Y787953D01*
X-1501920Y787253D01*
X-1502170Y786320D01*
X-1502253Y785270D01*
X-1502170Y784220D01*
X-1501920Y783287D01*
X-1501587Y782586D01*
X-1501087Y782003D01*
X-1500420Y781770D01*
X-1499753Y782003D01*
X-1499253Y782586D01*
X-1498920Y783287D01*
X-1498670Y784220D01*
X-1498587Y785270D01*
X-1498670Y786320D01*
X-1498920Y787253D01*
X-1499253Y787953D01*
X-1499753Y788537D01*
X-1500420Y788770D01*
G01X-1495120Y781537D02*
X-1492120Y788770D01*
G01X-1487903Y784103D02*
X-1485737D01*
G01X-1480020Y781770D02*
Y788770D01*
X-1481020Y787370D01*
G01Y781770D02*
X-1479020D01*
G01X-1473220Y788770D02*
X-1473887Y788537D01*
X-1474387Y787953D01*
X-1474720Y787253D01*
X-1474970Y786320D01*
X-1475053Y785270D01*
X-1474970Y784220D01*
X-1474720Y783287D01*
X-1474387Y782586D01*
X-1473887Y782003D01*
X-1473220Y781770D01*
X-1472553Y782003D01*
X-1472053Y782586D01*
X-1471720Y783287D01*
X-1471470Y784220D01*
X-1471387Y785270D01*
X-1471470Y786320D01*
X-1471720Y787253D01*
X-1472053Y787953D01*
X-1472553Y788537D01*
X-1473220Y788770D01*
G01X-1466420Y781537D02*
X-1466587Y781653D01*
Y781887D01*
X-1466420Y782003D01*
X-1466253Y781887D01*
Y781653D01*
X-1466420Y781537D01*
G01X-1459620Y788770D02*
X-1460287Y788537D01*
X-1460787Y787953D01*
X-1461120Y787253D01*
X-1461370Y786320D01*
X-1461453Y785270D01*
X-1461370Y784220D01*
X-1461120Y783287D01*
X-1460787Y782586D01*
X-1460287Y782003D01*
X-1459620Y781770D01*
X-1458953Y782003D01*
X-1458453Y782586D01*
X-1458120Y783287D01*
X-1457870Y784220D01*
X-1457787Y785270D01*
X-1457870Y786320D01*
X-1458120Y787253D01*
X-1458453Y787953D01*
X-1458953Y788537D01*
X-1459620Y788770D01*
G01X-1452820D02*
X-1453487Y788537D01*
X-1453987Y787953D01*
X-1454320Y787253D01*
X-1454570Y786320D01*
X-1454653Y785270D01*
X-1454570Y784220D01*
X-1454320Y783287D01*
X-1453987Y782586D01*
X-1453487Y782003D01*
X-1452820Y781770D01*
X-1452153Y782003D01*
X-1451653Y782586D01*
X-1451320Y783287D01*
X-1451070Y784220D01*
X-1450987Y785270D01*
X-1451070Y786320D01*
X-1451320Y787253D01*
X-1451653Y787953D01*
X-1452153Y788537D01*
X-1452820Y788770D01*
G01X-1446020D02*
X-1446687Y788537D01*
X-1447187Y787953D01*
X-1447520Y787253D01*
X-1447770Y786320D01*
X-1447853Y785270D01*
X-1447770Y784220D01*
X-1447520Y783287D01*
X-1447187Y782586D01*
X-1446687Y782003D01*
X-1446020Y781770D01*
X-1445353Y782003D01*
X-1444853Y782586D01*
X-1444520Y783287D01*
X-1444270Y784220D01*
X-1444187Y785270D01*
X-1444270Y786320D01*
X-1444520Y787253D01*
X-1444853Y787953D01*
X-1445353Y788537D01*
X-1446020Y788770D01*
G01X-1517420Y810970D02*
Y803970D01*
G01X-1519337Y810970D02*
X-1515503D01*
G01X-1510620Y803970D02*
X-1511287Y804087D01*
X-1511870Y804553D01*
X-1512370Y805253D01*
X-1512703Y806070D01*
X-1512870Y807003D01*
Y807937D01*
X-1512703Y808870D01*
X-1512370Y809687D01*
X-1511870Y810387D01*
X-1511287Y810853D01*
X-1510620Y810970D01*
X-1509953Y810853D01*
X-1509370Y810387D01*
X-1508870Y809687D01*
X-1508537Y808870D01*
X-1508370Y807937D01*
Y807003D01*
X-1508537Y806070D01*
X-1508870Y805253D01*
X-1509370Y804553D01*
X-1509953Y804087D01*
X-1510620Y803970D01*
G01X-1505487Y810970D02*
Y803970D01*
X-1502153D01*
G01X-1495353D02*
X-1498687D01*
Y810970D01*
X-1495353D01*
G01X-1496687Y807587D02*
X-1498687D01*
G01X-1491887Y803970D02*
Y810970D01*
X-1489803D01*
X-1489137Y810620D01*
X-1488720Y810153D01*
X-1488553Y809220D01*
X-1488720Y808287D01*
X-1489220Y807703D01*
X-1489803Y807353D01*
X-1491887D01*
G01X-1489803D02*
X-1488553Y803970D01*
G01X-1485503D02*
X-1483420Y810970D01*
X-1481337Y803970D01*
G01X-1482087Y806420D02*
X-1484753D01*
G01X-1478537Y803970D02*
Y810970D01*
X-1474703Y803970D01*
Y810970D01*
G01X-1467987Y810387D02*
X-1468487Y810737D01*
X-1469070Y810970D01*
X-1469737D01*
X-1470487Y810620D01*
X-1471070Y810037D01*
X-1471487Y809337D01*
X-1471820Y808170D01*
X-1471903Y807120D01*
X-1471737Y806070D01*
X-1471487Y805370D01*
X-1470987Y804670D01*
X-1470403Y804203D01*
X-1469820Y803970D01*
X-1469237D01*
X-1468653Y804203D01*
X-1468153Y804553D01*
X-1467737Y805020D01*
G01X-1461353Y803970D02*
X-1464687D01*
Y810970D01*
X-1461353D01*
G01X-1462687Y807587D02*
X-1464687D01*
G01X-1497190Y103093D02*
X-1504190D01*
Y105177D01*
X-1503840Y105843D01*
X-1503373Y106260D01*
X-1502440Y106427D01*
X-1501507Y106260D01*
X-1500923Y105760D01*
X-1500573Y105177D01*
Y103093D01*
G01Y105177D02*
X-1497190Y106427D01*
G01X-1504190Y111560D02*
X-1503957Y110893D01*
X-1503373Y110393D01*
X-1502673Y110060D01*
X-1501740Y109810D01*
X-1500690Y109727D01*
X-1499640Y109810D01*
X-1498707Y110060D01*
X-1498006Y110393D01*
X-1497423Y110893D01*
X-1497190Y111560D01*
X-1497423Y112227D01*
X-1498006Y112727D01*
X-1498707Y113060D01*
X-1499640Y113310D01*
X-1500690Y113393D01*
X-1501740Y113310D01*
X-1502673Y113060D01*
X-1503373Y112727D01*
X-1503957Y112227D01*
X-1504190Y111560D01*
G01X-1496957Y118360D02*
X-1497073Y118193D01*
X-1497307D01*
X-1497423Y118360D01*
X-1497307Y118527D01*
X-1497073D01*
X-1496957Y118360D01*
G01X-1504190Y125160D02*
X-1503957Y124493D01*
X-1503373Y123993D01*
X-1502673Y123660D01*
X-1501740Y123410D01*
X-1500690Y123327D01*
X-1499640Y123410D01*
X-1498707Y123660D01*
X-1498006Y123993D01*
X-1497423Y124493D01*
X-1497190Y125160D01*
X-1497423Y125827D01*
X-1498006Y126327D01*
X-1498707Y126660D01*
X-1499640Y126910D01*
X-1500690Y126993D01*
X-1501740Y126910D01*
X-1502673Y126660D01*
X-1503373Y126327D01*
X-1503957Y125827D01*
X-1504190Y125160D01*
G01X-1498006Y130543D02*
X-1497423Y131127D01*
X-1497190Y131793D01*
X-1497423Y132460D01*
X-1498123Y133043D01*
X-1499173Y133460D01*
X-1500223Y133627D01*
X-1501507D01*
X-1502557Y133460D01*
X-1503490Y133043D01*
X-1503957Y132543D01*
X-1504190Y131960D01*
X-1503957Y131293D01*
X-1503490Y130793D01*
X-1502790Y130460D01*
X-1501857Y130293D01*
X-1501040Y130460D01*
X-1500223Y130877D01*
X-1499757Y131377D01*
X-1499640Y131960D01*
X-1499873Y132627D01*
X-1500457Y133127D01*
X-1501507Y133627D01*
G01X-1497190Y138760D02*
X-1497307Y139343D01*
X-1497657Y140010D01*
X-1498240Y140427D01*
X-1499057Y140593D01*
X-1499873Y140427D01*
X-1500573Y139927D01*
X-1500923Y139177D01*
Y138343D01*
X-1501157Y137843D01*
X-1501740Y137427D01*
X-1502557Y137260D01*
X-1503373Y137510D01*
X-1503957Y138093D01*
X-1504190Y138760D01*
X-1503957Y139427D01*
X-1503373Y140010D01*
X-1502557Y140260D01*
X-1501740Y140093D01*
X-1501157Y139677D01*
X-1500923Y139177D01*
Y138343D01*
X-1500573Y137593D01*
X-1499873Y137093D01*
X-1499057Y136927D01*
X-1498240Y137093D01*
X-1497657Y137510D01*
X-1497307Y138177D01*
X-1497190Y138760D01*
G01X-1489023Y110152D02*
X-1489723Y110652D01*
X-1490073Y111235D01*
X-1490190Y111902D01*
X-1489957Y112735D01*
X-1489373Y113318D01*
X-1488673Y113485D01*
X-1487973Y113402D01*
X-1487390Y113068D01*
X-1486223Y111402D01*
X-1485407Y110652D01*
X-1484240Y110152D01*
X-1483190Y109985D01*
Y113485D01*
G01X-1482957Y118535D02*
X-1483073Y118368D01*
X-1483307D01*
X-1483423Y118535D01*
X-1483307Y118702D01*
X-1483073D01*
X-1482957Y118535D01*
G01X-1484240Y123502D02*
X-1483657Y124002D01*
X-1483307Y124585D01*
X-1483190Y125335D01*
X-1483423Y126085D01*
X-1483890Y126668D01*
X-1484707Y127085D01*
X-1485640Y127168D01*
X-1486573Y127002D01*
X-1487157Y126585D01*
X-1487623Y126002D01*
X-1487740Y125418D01*
X-1487623Y124835D01*
X-1487157Y124085D01*
X-1490190Y124335D01*
Y126585D01*
G01Y132135D02*
X-1489957Y131468D01*
X-1489373Y130968D01*
X-1488673Y130635D01*
X-1487740Y130385D01*
X-1486690Y130302D01*
X-1485640Y130385D01*
X-1484707Y130635D01*
X-1484006Y130968D01*
X-1483423Y131468D01*
X-1483190Y132135D01*
X-1483423Y132802D01*
X-1484006Y133302D01*
X-1484707Y133635D01*
X-1485640Y133885D01*
X-1486690Y133968D01*
X-1487740Y133885D01*
X-1488673Y133635D01*
X-1489373Y133302D01*
X-1489957Y132802D01*
X-1490190Y132135D01*
G01X-1461689Y97743D02*
X-1468689D01*
X-1467289Y96743D01*
G01X-1461689D02*
Y98743D01*
G01Y105543D02*
X-1468689D01*
X-1463672Y102460D01*
Y106626D01*
G01X-1461456Y111343D02*
X-1461572Y111176D01*
X-1461806D01*
X-1461922Y111343D01*
X-1461806Y111510D01*
X-1461572D01*
X-1461456Y111343D01*
G01X-1462739Y116310D02*
X-1462156Y116810D01*
X-1461806Y117393D01*
X-1461689Y118143D01*
X-1461922Y118893D01*
X-1462389Y119476D01*
X-1463206Y119893D01*
X-1464139Y119976D01*
X-1465072Y119810D01*
X-1465656Y119393D01*
X-1466122Y118810D01*
X-1466239Y118226D01*
X-1466122Y117643D01*
X-1465656Y116893D01*
X-1468689Y117143D01*
Y119393D01*
G01X-1461689Y124943D02*
X-1461806Y125526D01*
X-1462156Y126193D01*
X-1462739Y126610D01*
X-1463556Y126776D01*
X-1464372Y126610D01*
X-1465072Y126110D01*
X-1465422Y125360D01*
Y124526D01*
X-1465656Y124026D01*
X-1466239Y123610D01*
X-1467056Y123443D01*
X-1467872Y123693D01*
X-1468456Y124276D01*
X-1468689Y124943D01*
X-1468456Y125610D01*
X-1467872Y126193D01*
X-1467056Y126443D01*
X-1466239Y126276D01*
X-1465656Y125860D01*
X-1465422Y125360D01*
Y124526D01*
X-1465072Y123776D01*
X-1464372Y123276D01*
X-1463556Y123110D01*
X-1462739Y123276D01*
X-1462156Y123693D01*
X-1461806Y124360D01*
X-1461689Y124943D01*
G01X-1467522Y130160D02*
X-1468222Y130660D01*
X-1468572Y131243D01*
X-1468689Y131910D01*
X-1468456Y132743D01*
X-1467872Y133326D01*
X-1467172Y133493D01*
X-1466472Y133410D01*
X-1465889Y133076D01*
X-1464722Y131410D01*
X-1463906Y130660D01*
X-1462739Y130160D01*
X-1461689Y129993D01*
Y133493D01*
G01X-1449089Y96085D02*
X-1448272Y96585D01*
X-1447806Y97251D01*
X-1447689Y98001D01*
X-1447806Y98668D01*
X-1448389Y99335D01*
X-1449089Y99751D01*
X-1449789Y99835D01*
X-1450605Y99668D01*
X-1451189Y99085D01*
X-1451422Y98501D01*
Y97751D01*
G01Y98501D02*
X-1451772Y99001D01*
X-1452356Y99418D01*
X-1453056Y99585D01*
X-1453756Y99418D01*
X-1454339Y99001D01*
X-1454689Y98251D01*
X-1454572Y97501D01*
X-1454106Y96751D01*
G01X-1447689Y104551D02*
X-1449206Y104718D01*
X-1450489Y104968D01*
X-1451656Y105301D01*
X-1452939Y105718D01*
X-1454689Y106385D01*
Y103051D01*
G01Y111518D02*
X-1454456Y110851D01*
X-1453872Y110351D01*
X-1453172Y110018D01*
X-1452239Y109768D01*
X-1451189Y109685D01*
X-1450139Y109768D01*
X-1449206Y110018D01*
X-1448505Y110351D01*
X-1447922Y110851D01*
X-1447689Y111518D01*
X-1447922Y112185D01*
X-1448505Y112685D01*
X-1449206Y113018D01*
X-1450139Y113268D01*
X-1451189Y113351D01*
X-1452239Y113268D01*
X-1453172Y113018D01*
X-1453872Y112685D01*
X-1454456Y112185D01*
X-1454689Y111518D01*
G01X-1447456Y118318D02*
X-1447572Y118151D01*
X-1447806D01*
X-1447922Y118318D01*
X-1447806Y118485D01*
X-1447572D01*
X-1447456Y118318D01*
G01X-1449089Y123285D02*
X-1448272Y123785D01*
X-1447806Y124451D01*
X-1447689Y125201D01*
X-1447806Y125868D01*
X-1448389Y126535D01*
X-1449089Y126951D01*
X-1449789Y127035D01*
X-1450605Y126868D01*
X-1451189Y126285D01*
X-1451422Y125701D01*
Y124951D01*
G01Y125701D02*
X-1451772Y126201D01*
X-1452356Y126618D01*
X-1453056Y126785D01*
X-1453756Y126618D01*
X-1454339Y126201D01*
X-1454689Y125451D01*
X-1454572Y124701D01*
X-1454106Y123951D01*
G01X-1447689Y131918D02*
X-1447806Y132501D01*
X-1448156Y133168D01*
X-1448739Y133585D01*
X-1449556Y133751D01*
X-1450372Y133585D01*
X-1451072Y133085D01*
X-1451422Y132335D01*
Y131501D01*
X-1451656Y131001D01*
X-1452239Y130585D01*
X-1453056Y130418D01*
X-1453872Y130668D01*
X-1454456Y131251D01*
X-1454689Y131918D01*
X-1454456Y132585D01*
X-1453872Y133168D01*
X-1453056Y133418D01*
X-1452239Y133251D01*
X-1451656Y132835D01*
X-1451422Y132335D01*
Y131501D01*
X-1451072Y130751D01*
X-1450372Y130251D01*
X-1449556Y130085D01*
X-1448739Y130251D01*
X-1448156Y130668D01*
X-1447806Y131335D01*
X-1447689Y131918D01*
G01X-1428613Y97743D02*
X-1435613D01*
X-1434213Y96743D01*
G01X-1428613D02*
Y98743D01*
G01Y105543D02*
X-1435613D01*
X-1430596Y102460D01*
Y106626D01*
G01X-1428380Y111343D02*
X-1428496Y111176D01*
X-1428730D01*
X-1428846Y111343D01*
X-1428730Y111510D01*
X-1428496D01*
X-1428380Y111343D01*
G01X-1428613Y119143D02*
X-1435613D01*
X-1430596Y116060D01*
Y120226D01*
G01X-1434446Y123360D02*
X-1435146Y123860D01*
X-1435496Y124443D01*
X-1435613Y125110D01*
X-1435380Y125943D01*
X-1434796Y126526D01*
X-1434096Y126693D01*
X-1433396Y126610D01*
X-1432813Y126276D01*
X-1431646Y124610D01*
X-1430830Y123860D01*
X-1429663Y123360D01*
X-1428613Y123193D01*
Y126693D01*
G01Y132743D02*
X-1435613D01*
X-1430596Y129660D01*
Y133826D01*
G01X-1425800Y-256575D02*
X-1432800D01*
X-1431400Y-257575D01*
G01X-1425800D02*
Y-255575D01*
G01X-1425567Y-249775D02*
X-1425683Y-249942D01*
X-1425917D01*
X-1426033Y-249775D01*
X-1425917Y-249608D01*
X-1425683D01*
X-1425567Y-249775D01*
G01X-1431633Y-244558D02*
X-1432333Y-244058D01*
X-1432683Y-243475D01*
X-1432800Y-242808D01*
X-1432567Y-241975D01*
X-1431983Y-241392D01*
X-1431283Y-241225D01*
X-1430583Y-241308D01*
X-1430000Y-241642D01*
X-1428833Y-243308D01*
X-1428017Y-244058D01*
X-1426850Y-244558D01*
X-1425800Y-244725D01*
Y-241225D01*
G01X-1431633Y-237758D02*
X-1432333Y-237258D01*
X-1432683Y-236675D01*
X-1432800Y-236008D01*
X-1432567Y-235175D01*
X-1431983Y-234592D01*
X-1431283Y-234425D01*
X-1430583Y-234508D01*
X-1430000Y-234842D01*
X-1428833Y-236508D01*
X-1428017Y-237258D01*
X-1426850Y-237758D01*
X-1425800Y-237925D01*
Y-234425D01*
G01X-1432800Y-229375D02*
X-1432567Y-230042D01*
X-1431983Y-230542D01*
X-1431283Y-230875D01*
X-1430350Y-231125D01*
X-1429300Y-231208D01*
X-1428250Y-231125D01*
X-1427317Y-230875D01*
X-1426616Y-230542D01*
X-1426033Y-230042D01*
X-1425800Y-229375D01*
X-1426033Y-228708D01*
X-1426616Y-228208D01*
X-1427317Y-227875D01*
X-1428250Y-227625D01*
X-1429300Y-227542D01*
X-1430350Y-227625D01*
X-1431283Y-227875D01*
X-1431983Y-228208D01*
X-1432567Y-228708D01*
X-1432800Y-229375D01*
G01X-1416013Y96085D02*
X-1415196Y96585D01*
X-1414730Y97251D01*
X-1414613Y98001D01*
X-1414730Y98668D01*
X-1415313Y99335D01*
X-1416013Y99751D01*
X-1416713Y99835D01*
X-1417529Y99668D01*
X-1418113Y99085D01*
X-1418346Y98501D01*
Y97751D01*
G01Y98501D02*
X-1418696Y99001D01*
X-1419280Y99418D01*
X-1419980Y99585D01*
X-1420680Y99418D01*
X-1421263Y99001D01*
X-1421613Y98251D01*
X-1421496Y97501D01*
X-1421030Y96751D01*
G01X-1417529Y103135D02*
X-1418346Y103718D01*
X-1418813Y104218D01*
X-1419046Y104885D01*
X-1418813Y105468D01*
X-1418346Y105885D01*
X-1417646Y106218D01*
X-1416830Y106301D01*
X-1416130Y106218D01*
X-1415429Y105885D01*
X-1414846Y105385D01*
X-1414613Y104801D01*
X-1414846Y104135D01*
X-1415546Y103551D01*
X-1416596Y103218D01*
X-1417763Y103135D01*
X-1419280Y103301D01*
X-1420096Y103551D01*
X-1420913Y103968D01*
X-1421496Y104551D01*
X-1421613Y105135D01*
X-1421380Y105718D01*
X-1420796Y106135D01*
G01X-1417529Y109935D02*
X-1418346Y110518D01*
X-1418813Y111018D01*
X-1419046Y111685D01*
X-1418813Y112268D01*
X-1418346Y112685D01*
X-1417646Y113018D01*
X-1416830Y113101D01*
X-1416130Y113018D01*
X-1415429Y112685D01*
X-1414846Y112185D01*
X-1414613Y111601D01*
X-1414846Y110935D01*
X-1415546Y110351D01*
X-1416596Y110018D01*
X-1417763Y109935D01*
X-1419280Y110101D01*
X-1420096Y110351D01*
X-1420913Y110768D01*
X-1421496Y111351D01*
X-1421613Y111935D01*
X-1421380Y112518D01*
X-1420796Y112935D01*
G01X-1414380Y118318D02*
X-1414496Y118151D01*
X-1414730D01*
X-1414846Y118318D01*
X-1414730Y118485D01*
X-1414496D01*
X-1414380Y118318D01*
G01X-1416013Y123285D02*
X-1415196Y123785D01*
X-1414730Y124451D01*
X-1414613Y125201D01*
X-1414730Y125868D01*
X-1415313Y126535D01*
X-1416013Y126951D01*
X-1416713Y127035D01*
X-1417529Y126868D01*
X-1418113Y126285D01*
X-1418346Y125701D01*
Y124951D01*
G01Y125701D02*
X-1418696Y126201D01*
X-1419280Y126618D01*
X-1419980Y126785D01*
X-1420680Y126618D01*
X-1421263Y126201D01*
X-1421613Y125451D01*
X-1421496Y124701D01*
X-1421030Y123951D01*
G01X-1414613Y131918D02*
X-1414730Y132501D01*
X-1415080Y133168D01*
X-1415663Y133585D01*
X-1416480Y133751D01*
X-1417296Y133585D01*
X-1417996Y133085D01*
X-1418346Y132335D01*
Y131501D01*
X-1418580Y131001D01*
X-1419163Y130585D01*
X-1419980Y130418D01*
X-1420796Y130668D01*
X-1421380Y131251D01*
X-1421613Y131918D01*
X-1421380Y132585D01*
X-1420796Y133168D01*
X-1419980Y133418D01*
X-1419163Y133251D01*
X-1418580Y132835D01*
X-1418346Y132335D01*
Y131501D01*
X-1417996Y130751D01*
X-1417296Y130251D01*
X-1416480Y130085D01*
X-1415663Y130251D01*
X-1415080Y130668D01*
X-1414730Y131335D01*
X-1414613Y131918D01*
G01X-1422459Y209021D02*
X-1421787Y208444D01*
X-1421033Y208102D01*
X-1420367Y208108D01*
X-1419704Y208465D01*
X-1419209Y209053D01*
X-1418968Y209873D01*
X-1419143Y210687D01*
X-1419566Y211383D01*
X-1420321Y211842D01*
X-1421323Y212066D01*
X-1421911Y212526D01*
X-1422169Y213341D01*
X-1422011Y214159D01*
X-1421600Y214746D01*
X-1421020Y215102D01*
X-1420437Y215108D01*
X-1419851Y214881D01*
X-1419345Y214302D01*
G01X-1412234Y208190D02*
X-1415567Y208156D01*
X-1415637Y215156D01*
X-1412304Y215190D01*
G01X-1413603Y211793D02*
X-1415603Y211773D01*
G01X-1405434Y208258D02*
X-1408767Y208225D01*
X-1408838Y215224D01*
X-1405504Y215258D01*
G01X-1406804Y211861D02*
X-1408804Y211841D01*
G01X-1395261Y209293D02*
X-1394588Y208717D01*
X-1393835Y208374D01*
X-1393168Y208381D01*
X-1392505Y208737D01*
X-1392011Y209326D01*
X-1391769Y210145D01*
X-1391944Y210960D01*
X-1392368Y211656D01*
X-1393122Y212115D01*
X-1394124Y212338D01*
X-1394712Y212799D01*
X-1394971Y213613D01*
X-1394812Y214431D01*
X-1394401Y215019D01*
X-1393822Y215375D01*
X-1393238Y215381D01*
X-1392653Y215153D01*
X-1392147Y214575D01*
G01X-1385035Y208462D02*
X-1388368Y208429D01*
X-1388439Y215429D01*
X-1385105Y215462D01*
G01X-1386405Y212066D02*
X-1388405Y212046D01*
G01X-1378133Y214948D02*
X-1378637Y215293D01*
X-1379222Y215521D01*
X-1379889Y215514D01*
X-1380636Y215157D01*
X-1381213Y214568D01*
X-1381623Y213863D01*
X-1381944Y212693D01*
X-1382017Y211643D01*
X-1381840Y210594D01*
X-1381583Y209897D01*
X-1381076Y209202D01*
X-1380488Y208741D01*
X-1379902Y208514D01*
X-1379319Y208520D01*
X-1378738Y208759D01*
X-1378241Y209114D01*
X-1377829Y209584D01*
G01X-1373173Y215582D02*
X-1373103Y208582D01*
G01X-1375089Y215562D02*
X-1371256Y215601D01*
G01X-1367373Y215640D02*
X-1365373Y215660D01*
G01X-1366373Y215650D02*
X-1366303Y208650D01*
G01X-1367303Y208640D02*
X-1365303Y208660D01*
G01X-1359503Y208718D02*
X-1360171Y208828D01*
X-1360759Y209289D01*
X-1361266Y209984D01*
X-1361608Y210797D01*
X-1361784Y211729D01*
X-1361793Y212662D01*
X-1361636Y213597D01*
X-1361310Y214417D01*
X-1360817Y215122D01*
X-1360239Y215594D01*
X-1359573Y215718D01*
X-1358906Y215608D01*
X-1358318Y215147D01*
X-1357811Y214452D01*
X-1357469Y213639D01*
X-1357293Y212707D01*
X-1357284Y211774D01*
X-1357441Y210839D01*
X-1357766Y210019D01*
X-1358259Y209314D01*
X-1358838Y208841D01*
X-1359503Y208718D01*
G01X-1354620Y208767D02*
X-1354690Y215767D01*
X-1350787Y208805D01*
X-1350857Y215805D01*
G01X-1341188Y208902D02*
X-1339174Y215922D01*
X-1337021Y208943D01*
G01X-1337796Y211386D02*
X-1340462Y211359D01*
G01X-1332302Y208757D02*
X-1332470Y208872D01*
X-1332472Y209106D01*
X-1332307Y209224D01*
X-1332139Y209109D01*
X-1332137Y208876D01*
X-1332302Y208757D01*
G01X-1332334Y211907D02*
X-1332502Y212022D01*
X-1332504Y212255D01*
X-1332339Y212374D01*
X-1332171Y212259D01*
X-1332168Y212025D01*
X-1332334Y211907D01*
G01X-1327588Y209038D02*
X-1325575Y216058D01*
X-1323422Y209080D01*
G01X-1324196Y211522D02*
X-1326863Y211495D01*
G01X-1423333Y221744D02*
X-1421320Y228765D01*
X-1419167Y221786D01*
G01X-1419941Y224228D02*
X-1422608Y224201D01*
G01X-1414521Y228833D02*
X-1414451Y221833D01*
G01X-1416437Y228814D02*
X-1412604Y228852D01*
G01X-1400386Y225474D02*
X-1398720Y225491D01*
X-1398699Y223391D01*
X-1399192Y222686D01*
X-1399770Y222214D01*
X-1400601Y221972D01*
X-1401437Y222197D01*
X-1402025Y222658D01*
X-1402532Y223353D01*
X-1402873Y224166D01*
X-1403049Y225098D01*
X-1403058Y225914D01*
X-1402898Y226616D01*
X-1402573Y227436D01*
X-1402080Y228141D01*
X-1401584Y228612D01*
X-1400921Y228969D01*
X-1400338Y228975D01*
X-1399669Y228748D01*
X-1399164Y228287D01*
G01X-1394052Y222038D02*
X-1394719Y222147D01*
X-1395307Y222608D01*
X-1395814Y223303D01*
X-1396156Y224117D01*
X-1396332Y225048D01*
X-1396341Y225981D01*
X-1396184Y226916D01*
X-1395859Y227736D01*
X-1395366Y228441D01*
X-1394787Y228914D01*
X-1394122Y229037D01*
X-1393454Y228927D01*
X-1392866Y228466D01*
X-1392359Y227772D01*
X-1392017Y226958D01*
X-1391841Y226027D01*
X-1391832Y225093D01*
X-1391989Y224158D01*
X-1392314Y223338D01*
X-1392807Y222633D01*
X-1393386Y222161D01*
X-1394052Y222038D01*
G01X-1388989Y229089D02*
X-1388918Y222089D01*
X-1385585Y222122D01*
G01X-1382285Y222155D02*
X-1382356Y229155D01*
X-1380689Y229172D01*
X-1380019Y228828D01*
X-1379514Y228367D01*
X-1379090Y227671D01*
X-1378749Y226858D01*
X-1378654Y225692D01*
X-1378726Y224524D01*
X-1379051Y223704D01*
X-1379460Y223000D01*
X-1379956Y222529D01*
X-1380619Y222172D01*
X-1382285Y222155D01*
G01X-1368436Y222294D02*
X-1368506Y229294D01*
X-1365340Y229326D01*
G01X-1366472Y225931D02*
X-1368472Y225911D01*
G01X-1361123Y229368D02*
X-1359124Y229388D01*
G01X-1360123Y229378D02*
X-1360053Y222378D01*
G01X-1361053Y222368D02*
X-1359053Y222388D01*
G01X-1355170Y222427D02*
X-1355240Y229427D01*
X-1351337Y222465D01*
X-1351407Y229465D01*
G01X-1345989Y226019D02*
X-1344322Y226036D01*
X-1344301Y223936D01*
X-1344794Y223231D01*
X-1345373Y222758D01*
X-1346204Y222517D01*
X-1347039Y222742D01*
X-1347627Y223202D01*
X-1348134Y223898D01*
X-1348476Y224711D01*
X-1348652Y225642D01*
X-1348660Y226459D01*
X-1348501Y227161D01*
X-1348175Y227981D01*
X-1347682Y228686D01*
X-1347187Y229157D01*
X-1346524Y229514D01*
X-1345941Y229520D01*
X-1345272Y229293D01*
X-1344767Y228832D01*
G01X-1337988Y222599D02*
X-1341321Y222566D01*
X-1341391Y229565D01*
X-1338058Y229599D01*
G01X-1339357Y226202D02*
X-1341357Y226182D01*
G01X-1334521Y222634D02*
X-1334591Y229634D01*
X-1332508Y229654D01*
X-1331838Y229311D01*
X-1331416Y228849D01*
X-1331241Y227917D01*
X-1331398Y226982D01*
X-1331892Y226394D01*
X-1332472Y226038D01*
X-1334555Y226017D01*
G01X-1332472Y226038D02*
X-1331188Y222667D01*
G01X-1327814Y223634D02*
X-1327142Y223058D01*
X-1326388Y222715D01*
X-1325722Y222722D01*
X-1325058Y223079D01*
X-1324564Y223667D01*
X-1324322Y224486D01*
X-1324497Y225301D01*
X-1324921Y225997D01*
X-1325676Y226456D01*
X-1326678Y226679D01*
X-1327266Y227140D01*
X-1327524Y227954D01*
X-1327366Y228773D01*
X-1326955Y229360D01*
X-1326375Y229716D01*
X-1325792Y229722D01*
X-1325206Y229494D01*
X-1324700Y228916D01*
G01X-1420621Y239165D02*
X-1420291Y239518D01*
X-1420047Y240104D01*
X-1419888Y240922D01*
X-1420062Y241621D01*
X-1420400Y242084D01*
X-1420987Y242428D01*
X-1423237Y242405D01*
X-1423167Y235406D01*
X-1420417Y235433D01*
X-1419838Y235906D01*
X-1419512Y236609D01*
X-1419353Y237427D01*
X-1419528Y238242D01*
X-1420035Y238937D01*
X-1420621Y239165D01*
X-1423204Y239139D01*
G01X-1412784Y235510D02*
X-1416117Y235476D01*
X-1416187Y242476D01*
X-1412854Y242510D01*
G01X-1414153Y239113D02*
X-1416153Y239093D01*
G01X-1409804Y242540D02*
X-1407651Y235561D01*
X-1405638Y242582D01*
G01X-1399185Y235646D02*
X-1402518Y235613D01*
X-1402588Y242612D01*
X-1399255Y242646D01*
G01X-1400554Y239249D02*
X-1402554Y239229D01*
G01X-1395788Y242680D02*
X-1395718Y235681D01*
X-1392385Y235714D01*
G01X-1379823Y239574D02*
X-1379493Y239927D01*
X-1379249Y240513D01*
X-1379090Y241331D01*
X-1379264Y242029D01*
X-1379602Y242492D01*
X-1380189Y242837D01*
X-1382439Y242814D01*
X-1382369Y235815D01*
X-1379619Y235842D01*
X-1379040Y236314D01*
X-1378714Y237018D01*
X-1378555Y237836D01*
X-1378730Y238651D01*
X-1379237Y239346D01*
X-1379823Y239574D01*
X-1382406Y239548D01*
G01X-1373653Y235902D02*
X-1374320Y236012D01*
X-1374908Y236473D01*
X-1375415Y237168D01*
X-1375757Y237981D01*
X-1375933Y238913D01*
X-1375942Y239846D01*
X-1375785Y240781D01*
X-1375460Y241601D01*
X-1374967Y242306D01*
X-1374388Y242778D01*
X-1373723Y242902D01*
X-1373055Y242792D01*
X-1372467Y242331D01*
X-1371960Y241636D01*
X-1371618Y240823D01*
X-1371442Y239891D01*
X-1371433Y238958D01*
X-1371590Y238023D01*
X-1371915Y237203D01*
X-1372408Y236498D01*
X-1372987Y236025D01*
X-1373653Y235902D01*
G01X-1366923Y242970D02*
X-1366853Y235970D01*
G01X-1368840Y242950D02*
X-1365006Y242989D01*
G01X-1361803Y236021D02*
X-1361873Y243020D01*
G01X-1358373Y243055D02*
X-1358303Y236056D01*
G01X-1358338Y239555D02*
X-1361838Y239520D01*
G01X-1348213Y237090D02*
X-1347541Y236513D01*
X-1346787Y236171D01*
X-1346121Y236178D01*
X-1345457Y236534D01*
X-1344963Y237122D01*
X-1344721Y237942D01*
X-1344896Y238757D01*
X-1345320Y239453D01*
X-1346075Y239912D01*
X-1347077Y240135D01*
X-1347665Y240596D01*
X-1347923Y241410D01*
X-1347765Y242228D01*
X-1347354Y242816D01*
X-1346774Y243172D01*
X-1346191Y243177D01*
X-1345605Y242950D01*
X-1345099Y242372D01*
G01X-1340724Y243232D02*
X-1338725Y243252D01*
G01X-1339724Y243242D02*
X-1339654Y236242D01*
G01X-1340654Y236232D02*
X-1338654Y236253D01*
G01X-1334688Y236292D02*
X-1334758Y243292D01*
X-1333091Y243309D01*
X-1332421Y242965D01*
X-1331917Y242504D01*
X-1331493Y241808D01*
X-1331151Y240994D01*
X-1331056Y239829D01*
X-1331128Y238661D01*
X-1331453Y237841D01*
X-1331863Y237137D01*
X-1332358Y236666D01*
X-1333021Y236309D01*
X-1334688Y236292D01*
G01X-1324388Y236395D02*
X-1327721Y236362D01*
X-1327792Y243362D01*
X-1324458Y243395D01*
G01X-1325758Y239999D02*
X-1327758Y239979D01*
G01X-1321014Y237362D02*
X-1320342Y236786D01*
X-1319589Y236444D01*
X-1318922Y236450D01*
X-1318259Y236807D01*
X-1317765Y237395D01*
X-1317523Y238214D01*
X-1317698Y239029D01*
X-1318121Y239725D01*
X-1318876Y240184D01*
X-1319878Y240407D01*
X-1320466Y240868D01*
X-1320724Y241682D01*
X-1320566Y242501D01*
X-1320155Y243088D01*
X-1319575Y243444D01*
X-1318992Y243450D01*
X-1318406Y243222D01*
X-1317900Y242644D01*
G01X-1429137Y337170D02*
Y344170D01*
X-1425303Y337170D01*
Y344170D01*
G01X-1420420Y337170D02*
X-1421087Y337287D01*
X-1421670Y337753D01*
X-1422170Y338453D01*
X-1422503Y339270D01*
X-1422670Y340203D01*
Y341137D01*
X-1422503Y342070D01*
X-1422170Y342887D01*
X-1421670Y343587D01*
X-1421087Y344053D01*
X-1420420Y344170D01*
X-1419753Y344053D01*
X-1419170Y343587D01*
X-1418670Y342887D01*
X-1418337Y342070D01*
X-1418170Y341137D01*
Y340203D01*
X-1418337Y339270D01*
X-1418670Y338453D01*
X-1419170Y337753D01*
X-1419753Y337287D01*
X-1420420Y337170D01*
G01X-1415537D02*
Y344170D01*
X-1411703Y337170D01*
Y344170D01*
G01X-1407903Y339503D02*
X-1405737D01*
G01X-1401687Y337170D02*
Y344170D01*
X-1399687D01*
X-1399020Y343820D01*
X-1398520Y343003D01*
X-1398353Y342070D01*
X-1398520Y341137D01*
X-1398937Y340437D01*
X-1399687Y340086D01*
X-1401687D01*
G01X-1394887Y344170D02*
Y337170D01*
X-1391553D01*
G01X-1388503D02*
X-1386420Y344170D01*
X-1384337Y337170D01*
G01X-1385087Y339620D02*
X-1387753D01*
G01X-1379620Y344170D02*
Y337170D01*
G01X-1381537Y344170D02*
X-1377703D01*
G01X-1371153Y337170D02*
X-1374487D01*
Y344170D01*
X-1371153D01*
G01X-1372487Y340787D02*
X-1374487D01*
G01X-1367853Y337170D02*
Y344170D01*
X-1366187D01*
X-1365520Y343820D01*
X-1365020Y343353D01*
X-1364603Y342653D01*
X-1364270Y341837D01*
X-1364187Y340670D01*
X-1364270Y339503D01*
X-1364603Y338687D01*
X-1365020Y337986D01*
X-1365520Y337520D01*
X-1366187Y337170D01*
X-1367853D01*
G01X-1429137Y360570D02*
Y367570D01*
X-1425303Y360570D01*
Y367570D01*
G01X-1420420Y360570D02*
X-1421087Y360687D01*
X-1421670Y361153D01*
X-1422170Y361853D01*
X-1422503Y362670D01*
X-1422670Y363603D01*
Y364537D01*
X-1422503Y365470D01*
X-1422170Y366287D01*
X-1421670Y366987D01*
X-1421087Y367453D01*
X-1420420Y367570D01*
X-1419753Y367453D01*
X-1419170Y366987D01*
X-1418670Y366287D01*
X-1418337Y365470D01*
X-1418170Y364537D01*
Y363603D01*
X-1418337Y362670D01*
X-1418670Y361853D01*
X-1419170Y361153D01*
X-1419753Y360687D01*
X-1420420Y360570D01*
G01X-1415537D02*
Y367570D01*
X-1411703Y360570D01*
Y367570D01*
G01X-1407903Y362903D02*
X-1405737D01*
G01X-1401687Y360570D02*
Y367570D01*
X-1399687D01*
X-1399020Y367220D01*
X-1398520Y366403D01*
X-1398353Y365470D01*
X-1398520Y364537D01*
X-1398937Y363837D01*
X-1399687Y363486D01*
X-1401687D01*
G01X-1394887Y367570D02*
Y360570D01*
X-1391553D01*
G01X-1388503D02*
X-1386420Y367570D01*
X-1384337Y360570D01*
G01X-1385087Y363020D02*
X-1387753D01*
G01X-1379620Y367570D02*
Y360570D01*
G01X-1381537Y367570D02*
X-1377703D01*
G01X-1371153Y360570D02*
X-1374487D01*
Y367570D01*
X-1371153D01*
G01X-1372487Y364187D02*
X-1374487D01*
G01X-1367853Y360570D02*
Y367570D01*
X-1366187D01*
X-1365520Y367220D01*
X-1365020Y366753D01*
X-1364603Y366053D01*
X-1364270Y365237D01*
X-1364187Y364070D01*
X-1364270Y362903D01*
X-1364603Y362087D01*
X-1365020Y361386D01*
X-1365520Y360920D01*
X-1366187Y360570D01*
X-1367853D01*
G01X-1429137Y383970D02*
Y390970D01*
X-1425303Y383970D01*
Y390970D01*
G01X-1420420Y383970D02*
X-1421087Y384087D01*
X-1421670Y384553D01*
X-1422170Y385253D01*
X-1422503Y386070D01*
X-1422670Y387003D01*
Y387937D01*
X-1422503Y388870D01*
X-1422170Y389687D01*
X-1421670Y390387D01*
X-1421087Y390853D01*
X-1420420Y390970D01*
X-1419753Y390853D01*
X-1419170Y390387D01*
X-1418670Y389687D01*
X-1418337Y388870D01*
X-1418170Y387937D01*
Y387003D01*
X-1418337Y386070D01*
X-1418670Y385253D01*
X-1419170Y384553D01*
X-1419753Y384087D01*
X-1420420Y383970D01*
G01X-1415537D02*
Y390970D01*
X-1411703Y383970D01*
Y390970D01*
G01X-1407903Y386303D02*
X-1405737D01*
G01X-1401687Y383970D02*
Y390970D01*
X-1399687D01*
X-1399020Y390620D01*
X-1398520Y389803D01*
X-1398353Y388870D01*
X-1398520Y387937D01*
X-1398937Y387237D01*
X-1399687Y386886D01*
X-1401687D01*
G01X-1394887Y390970D02*
Y383970D01*
X-1391553D01*
G01X-1388503D02*
X-1386420Y390970D01*
X-1384337Y383970D01*
G01X-1385087Y386420D02*
X-1387753D01*
G01X-1379620Y390970D02*
Y383970D01*
G01X-1381537Y390970D02*
X-1377703D01*
G01X-1371153Y383970D02*
X-1374487D01*
Y390970D01*
X-1371153D01*
G01X-1372487Y387587D02*
X-1374487D01*
G01X-1367853Y383970D02*
Y390970D01*
X-1366187D01*
X-1365520Y390620D01*
X-1365020Y390153D01*
X-1364603Y389453D01*
X-1364270Y388637D01*
X-1364187Y387470D01*
X-1364270Y386303D01*
X-1364603Y385487D01*
X-1365020Y384786D01*
X-1365520Y384320D01*
X-1366187Y383970D01*
X-1367853D01*
G01X-1429137Y407370D02*
Y414370D01*
X-1425303Y407370D01*
Y414370D01*
G01X-1420420Y407370D02*
X-1421087Y407487D01*
X-1421670Y407953D01*
X-1422170Y408653D01*
X-1422503Y409470D01*
X-1422670Y410403D01*
Y411337D01*
X-1422503Y412270D01*
X-1422170Y413087D01*
X-1421670Y413787D01*
X-1421087Y414253D01*
X-1420420Y414370D01*
X-1419753Y414253D01*
X-1419170Y413787D01*
X-1418670Y413087D01*
X-1418337Y412270D01*
X-1418170Y411337D01*
Y410403D01*
X-1418337Y409470D01*
X-1418670Y408653D01*
X-1419170Y407953D01*
X-1419753Y407487D01*
X-1420420Y407370D01*
G01X-1415537D02*
Y414370D01*
X-1411703Y407370D01*
Y414370D01*
G01X-1407903Y409703D02*
X-1405737D01*
G01X-1401687Y407370D02*
Y414370D01*
X-1399687D01*
X-1399020Y414020D01*
X-1398520Y413203D01*
X-1398353Y412270D01*
X-1398520Y411337D01*
X-1398937Y410637D01*
X-1399687Y410286D01*
X-1401687D01*
G01X-1394887Y414370D02*
Y407370D01*
X-1391553D01*
G01X-1388503D02*
X-1386420Y414370D01*
X-1384337Y407370D01*
G01X-1385087Y409820D02*
X-1387753D01*
G01X-1379620Y414370D02*
Y407370D01*
G01X-1381537Y414370D02*
X-1377703D01*
G01X-1371153Y407370D02*
X-1374487D01*
Y414370D01*
X-1371153D01*
G01X-1372487Y410987D02*
X-1374487D01*
G01X-1367853Y407370D02*
Y414370D01*
X-1366187D01*
X-1365520Y414020D01*
X-1365020Y413553D01*
X-1364603Y412853D01*
X-1364270Y412037D01*
X-1364187Y410870D01*
X-1364270Y409703D01*
X-1364603Y408887D01*
X-1365020Y408186D01*
X-1365520Y407720D01*
X-1366187Y407370D01*
X-1367853D01*
G01X-1429137Y430770D02*
Y437770D01*
X-1425303Y430770D01*
Y437770D01*
G01X-1420420Y430770D02*
X-1421087Y430887D01*
X-1421670Y431353D01*
X-1422170Y432053D01*
X-1422503Y432870D01*
X-1422670Y433803D01*
Y434737D01*
X-1422503Y435670D01*
X-1422170Y436487D01*
X-1421670Y437187D01*
X-1421087Y437653D01*
X-1420420Y437770D01*
X-1419753Y437653D01*
X-1419170Y437187D01*
X-1418670Y436487D01*
X-1418337Y435670D01*
X-1418170Y434737D01*
Y433803D01*
X-1418337Y432870D01*
X-1418670Y432053D01*
X-1419170Y431353D01*
X-1419753Y430887D01*
X-1420420Y430770D01*
G01X-1415537D02*
Y437770D01*
X-1411703Y430770D01*
Y437770D01*
G01X-1407903Y433103D02*
X-1405737D01*
G01X-1401687Y430770D02*
Y437770D01*
X-1399687D01*
X-1399020Y437420D01*
X-1398520Y436603D01*
X-1398353Y435670D01*
X-1398520Y434737D01*
X-1398937Y434037D01*
X-1399687Y433686D01*
X-1401687D01*
G01X-1394887Y437770D02*
Y430770D01*
X-1391553D01*
G01X-1388503D02*
X-1386420Y437770D01*
X-1384337Y430770D01*
G01X-1385087Y433220D02*
X-1387753D01*
G01X-1379620Y437770D02*
Y430770D01*
G01X-1381537Y437770D02*
X-1377703D01*
G01X-1371153Y430770D02*
X-1374487D01*
Y437770D01*
X-1371153D01*
G01X-1372487Y434387D02*
X-1374487D01*
G01X-1367853Y430770D02*
Y437770D01*
X-1366187D01*
X-1365520Y437420D01*
X-1365020Y436953D01*
X-1364603Y436253D01*
X-1364270Y435437D01*
X-1364187Y434270D01*
X-1364270Y433103D01*
X-1364603Y432287D01*
X-1365020Y431586D01*
X-1365520Y431120D01*
X-1366187Y430770D01*
X-1367853D01*
G01X-1429137Y454170D02*
Y461170D01*
X-1425303Y454170D01*
Y461170D01*
G01X-1420420Y454170D02*
X-1421087Y454287D01*
X-1421670Y454753D01*
X-1422170Y455453D01*
X-1422503Y456270D01*
X-1422670Y457203D01*
Y458137D01*
X-1422503Y459070D01*
X-1422170Y459887D01*
X-1421670Y460587D01*
X-1421087Y461053D01*
X-1420420Y461170D01*
X-1419753Y461053D01*
X-1419170Y460587D01*
X-1418670Y459887D01*
X-1418337Y459070D01*
X-1418170Y458137D01*
Y457203D01*
X-1418337Y456270D01*
X-1418670Y455453D01*
X-1419170Y454753D01*
X-1419753Y454287D01*
X-1420420Y454170D01*
G01X-1415537D02*
Y461170D01*
X-1411703Y454170D01*
Y461170D01*
G01X-1407903Y456503D02*
X-1405737D01*
G01X-1401687Y454170D02*
Y461170D01*
X-1399687D01*
X-1399020Y460820D01*
X-1398520Y460003D01*
X-1398353Y459070D01*
X-1398520Y458137D01*
X-1398937Y457437D01*
X-1399687Y457086D01*
X-1401687D01*
G01X-1394887Y461170D02*
Y454170D01*
X-1391553D01*
G01X-1388503D02*
X-1386420Y461170D01*
X-1384337Y454170D01*
G01X-1385087Y456620D02*
X-1387753D01*
G01X-1379620Y461170D02*
Y454170D01*
G01X-1381537Y461170D02*
X-1377703D01*
G01X-1371153Y454170D02*
X-1374487D01*
Y461170D01*
X-1371153D01*
G01X-1372487Y457787D02*
X-1374487D01*
G01X-1367853Y454170D02*
Y461170D01*
X-1366187D01*
X-1365520Y460820D01*
X-1365020Y460353D01*
X-1364603Y459653D01*
X-1364270Y458837D01*
X-1364187Y457670D01*
X-1364270Y456503D01*
X-1364603Y455687D01*
X-1365020Y454986D01*
X-1365520Y454520D01*
X-1366187Y454170D01*
X-1367853D01*
G01X-1413200Y-258233D02*
X-1412383Y-257733D01*
X-1411917Y-257067D01*
X-1411800Y-256317D01*
X-1411917Y-255650D01*
X-1412500Y-254983D01*
X-1413200Y-254567D01*
X-1413900Y-254483D01*
X-1414716Y-254650D01*
X-1415300Y-255233D01*
X-1415533Y-255817D01*
Y-256567D01*
G01Y-255817D02*
X-1415883Y-255317D01*
X-1416467Y-254900D01*
X-1417167Y-254733D01*
X-1417867Y-254900D01*
X-1418450Y-255317D01*
X-1418800Y-256067D01*
X-1418683Y-256817D01*
X-1418217Y-257567D01*
G01X-1411800Y-249600D02*
X-1418800D01*
X-1417400Y-250600D01*
G01X-1411800D02*
Y-248600D01*
G01X-1411567Y-242800D02*
X-1411683Y-242967D01*
X-1411917D01*
X-1412033Y-242800D01*
X-1411917Y-242633D01*
X-1411683D01*
X-1411567Y-242800D01*
G01X-1418800Y-236000D02*
X-1418567Y-236667D01*
X-1417983Y-237167D01*
X-1417283Y-237500D01*
X-1416350Y-237750D01*
X-1415300Y-237833D01*
X-1414250Y-237750D01*
X-1413317Y-237500D01*
X-1412616Y-237167D01*
X-1412033Y-236667D01*
X-1411800Y-236000D01*
X-1412033Y-235333D01*
X-1412616Y-234833D01*
X-1413317Y-234500D01*
X-1414250Y-234250D01*
X-1415300Y-234167D01*
X-1416350Y-234250D01*
X-1417283Y-234500D01*
X-1417983Y-234833D01*
X-1418567Y-235333D01*
X-1418800Y-236000D01*
G01Y-229200D02*
X-1418567Y-229867D01*
X-1417983Y-230367D01*
X-1417283Y-230700D01*
X-1416350Y-230950D01*
X-1415300Y-231033D01*
X-1414250Y-230950D01*
X-1413317Y-230700D01*
X-1412616Y-230367D01*
X-1412033Y-229867D01*
X-1411800Y-229200D01*
X-1412033Y-228533D01*
X-1412616Y-228033D01*
X-1413317Y-227700D01*
X-1414250Y-227450D01*
X-1415300Y-227367D01*
X-1416350Y-227450D01*
X-1417283Y-227700D01*
X-1417983Y-228033D01*
X-1418567Y-228533D01*
X-1418800Y-229200D01*
G01X-1415287Y477570D02*
Y484570D01*
X-1413287D01*
X-1412620Y484220D01*
X-1412120Y483403D01*
X-1411953Y482470D01*
X-1412120Y481537D01*
X-1412537Y480837D01*
X-1413287Y480486D01*
X-1415287D01*
G01X-1408487Y484570D02*
Y477570D01*
X-1405153D01*
G01X-1402103D02*
X-1400020Y484570D01*
X-1397937Y477570D01*
G01X-1398687Y480020D02*
X-1401353D01*
G01X-1393220Y484570D02*
Y477570D01*
G01X-1395137Y484570D02*
X-1391303D01*
G01X-1384753Y477570D02*
X-1388087D01*
Y484570D01*
X-1384753D01*
G01X-1386087Y481187D02*
X-1388087D01*
G01X-1381453Y477570D02*
Y484570D01*
X-1379787D01*
X-1379120Y484220D01*
X-1378620Y483753D01*
X-1378203Y483053D01*
X-1377870Y482237D01*
X-1377787Y481070D01*
X-1377870Y479903D01*
X-1378203Y479087D01*
X-1378620Y478386D01*
X-1379120Y477920D01*
X-1379787Y477570D01*
X-1381453D01*
G01X-1415287Y500970D02*
Y507970D01*
X-1413287D01*
X-1412620Y507620D01*
X-1412120Y506803D01*
X-1411953Y505870D01*
X-1412120Y504937D01*
X-1412537Y504237D01*
X-1413287Y503886D01*
X-1415287D01*
G01X-1408487Y507970D02*
Y500970D01*
X-1405153D01*
G01X-1402103D02*
X-1400020Y507970D01*
X-1397937Y500970D01*
G01X-1398687Y503420D02*
X-1401353D01*
G01X-1393220Y507970D02*
Y500970D01*
G01X-1395137Y507970D02*
X-1391303D01*
G01X-1384753Y500970D02*
X-1388087D01*
Y507970D01*
X-1384753D01*
G01X-1386087Y504587D02*
X-1388087D01*
G01X-1381453Y500970D02*
Y507970D01*
X-1379787D01*
X-1379120Y507620D01*
X-1378620Y507153D01*
X-1378203Y506453D01*
X-1377870Y505637D01*
X-1377787Y504470D01*
X-1377870Y503303D01*
X-1378203Y502487D01*
X-1378620Y501786D01*
X-1379120Y501320D01*
X-1379787Y500970D01*
X-1381453D01*
G01X-1415287Y524370D02*
Y531370D01*
X-1413287D01*
X-1412620Y531020D01*
X-1412120Y530203D01*
X-1411953Y529270D01*
X-1412120Y528337D01*
X-1412537Y527637D01*
X-1413287Y527286D01*
X-1415287D01*
G01X-1408487Y531370D02*
Y524370D01*
X-1405153D01*
G01X-1402103D02*
X-1400020Y531370D01*
X-1397937Y524370D01*
G01X-1398687Y526820D02*
X-1401353D01*
G01X-1393220Y531370D02*
Y524370D01*
G01X-1395137Y531370D02*
X-1391303D01*
G01X-1384753Y524370D02*
X-1388087D01*
Y531370D01*
X-1384753D01*
G01X-1386087Y527987D02*
X-1388087D01*
G01X-1381453Y524370D02*
Y531370D01*
X-1379787D01*
X-1379120Y531020D01*
X-1378620Y530553D01*
X-1378203Y529853D01*
X-1377870Y529037D01*
X-1377787Y527870D01*
X-1377870Y526703D01*
X-1378203Y525887D01*
X-1378620Y525186D01*
X-1379120Y524720D01*
X-1379787Y524370D01*
X-1381453D01*
G01X-1415287Y547770D02*
Y554770D01*
X-1413287D01*
X-1412620Y554420D01*
X-1412120Y553603D01*
X-1411953Y552670D01*
X-1412120Y551737D01*
X-1412537Y551037D01*
X-1413287Y550686D01*
X-1415287D01*
G01X-1408487Y554770D02*
Y547770D01*
X-1405153D01*
G01X-1402103D02*
X-1400020Y554770D01*
X-1397937Y547770D01*
G01X-1398687Y550220D02*
X-1401353D01*
G01X-1393220Y554770D02*
Y547770D01*
G01X-1395137Y554770D02*
X-1391303D01*
G01X-1384753Y547770D02*
X-1388087D01*
Y554770D01*
X-1384753D01*
G01X-1386087Y551387D02*
X-1388087D01*
G01X-1381453Y547770D02*
Y554770D01*
X-1379787D01*
X-1379120Y554420D01*
X-1378620Y553953D01*
X-1378203Y553253D01*
X-1377870Y552437D01*
X-1377787Y551270D01*
X-1377870Y550103D01*
X-1378203Y549287D01*
X-1378620Y548586D01*
X-1379120Y548120D01*
X-1379787Y547770D01*
X-1381453D01*
G01X-1415287Y571170D02*
Y578170D01*
X-1413287D01*
X-1412620Y577820D01*
X-1412120Y577003D01*
X-1411953Y576070D01*
X-1412120Y575137D01*
X-1412537Y574437D01*
X-1413287Y574086D01*
X-1415287D01*
G01X-1408487Y578170D02*
Y571170D01*
X-1405153D01*
G01X-1402103D02*
X-1400020Y578170D01*
X-1397937Y571170D01*
G01X-1398687Y573620D02*
X-1401353D01*
G01X-1393220Y578170D02*
Y571170D01*
G01X-1395137Y578170D02*
X-1391303D01*
G01X-1384753Y571170D02*
X-1388087D01*
Y578170D01*
X-1384753D01*
G01X-1386087Y574787D02*
X-1388087D01*
G01X-1381453Y571170D02*
Y578170D01*
X-1379787D01*
X-1379120Y577820D01*
X-1378620Y577353D01*
X-1378203Y576653D01*
X-1377870Y575837D01*
X-1377787Y574670D01*
X-1377870Y573503D01*
X-1378203Y572687D01*
X-1378620Y571986D01*
X-1379120Y571520D01*
X-1379787Y571170D01*
X-1381453D01*
G01X-1415287Y594570D02*
Y601570D01*
X-1413287D01*
X-1412620Y601220D01*
X-1412120Y600403D01*
X-1411953Y599470D01*
X-1412120Y598537D01*
X-1412537Y597837D01*
X-1413287Y597486D01*
X-1415287D01*
G01X-1408487Y601570D02*
Y594570D01*
X-1405153D01*
G01X-1402103D02*
X-1400020Y601570D01*
X-1397937Y594570D01*
G01X-1398687Y597020D02*
X-1401353D01*
G01X-1393220Y601570D02*
Y594570D01*
G01X-1395137Y601570D02*
X-1391303D01*
G01X-1384753Y594570D02*
X-1388087D01*
Y601570D01*
X-1384753D01*
G01X-1386087Y598187D02*
X-1388087D01*
G01X-1381453Y594570D02*
Y601570D01*
X-1379787D01*
X-1379120Y601220D01*
X-1378620Y600753D01*
X-1378203Y600053D01*
X-1377870Y599237D01*
X-1377787Y598070D01*
X-1377870Y596903D01*
X-1378203Y596087D01*
X-1378620Y595386D01*
X-1379120Y594920D01*
X-1379787Y594570D01*
X-1381453D01*
G01X-1415287Y617970D02*
Y624970D01*
X-1413287D01*
X-1412620Y624620D01*
X-1412120Y623803D01*
X-1411953Y622870D01*
X-1412120Y621937D01*
X-1412537Y621237D01*
X-1413287Y620886D01*
X-1415287D01*
G01X-1408487Y624970D02*
Y617970D01*
X-1405153D01*
G01X-1402103D02*
X-1400020Y624970D01*
X-1397937Y617970D01*
G01X-1398687Y620420D02*
X-1401353D01*
G01X-1393220Y624970D02*
Y617970D01*
G01X-1395137Y624970D02*
X-1391303D01*
G01X-1384753Y617970D02*
X-1388087D01*
Y624970D01*
X-1384753D01*
G01X-1386087Y621587D02*
X-1388087D01*
G01X-1381453Y617970D02*
Y624970D01*
X-1379787D01*
X-1379120Y624620D01*
X-1378620Y624153D01*
X-1378203Y623453D01*
X-1377870Y622637D01*
X-1377787Y621470D01*
X-1377870Y620303D01*
X-1378203Y619487D01*
X-1378620Y618786D01*
X-1379120Y618320D01*
X-1379787Y617970D01*
X-1381453D01*
G01X-1415287Y641370D02*
Y648370D01*
X-1413287D01*
X-1412620Y648020D01*
X-1412120Y647203D01*
X-1411953Y646270D01*
X-1412120Y645337D01*
X-1412537Y644637D01*
X-1413287Y644286D01*
X-1415287D01*
G01X-1408487Y648370D02*
Y641370D01*
X-1405153D01*
G01X-1402103D02*
X-1400020Y648370D01*
X-1397937Y641370D01*
G01X-1398687Y643820D02*
X-1401353D01*
G01X-1393220Y648370D02*
Y641370D01*
G01X-1395137Y648370D02*
X-1391303D01*
G01X-1384753Y641370D02*
X-1388087D01*
Y648370D01*
X-1384753D01*
G01X-1386087Y644987D02*
X-1388087D01*
G01X-1381453Y641370D02*
Y648370D01*
X-1379787D01*
X-1379120Y648020D01*
X-1378620Y647553D01*
X-1378203Y646853D01*
X-1377870Y646037D01*
X-1377787Y644870D01*
X-1377870Y643703D01*
X-1378203Y642887D01*
X-1378620Y642186D01*
X-1379120Y641720D01*
X-1379787Y641370D01*
X-1381453D01*
G01X-1415287Y664770D02*
Y671770D01*
X-1413287D01*
X-1412620Y671420D01*
X-1412120Y670603D01*
X-1411953Y669670D01*
X-1412120Y668737D01*
X-1412537Y668037D01*
X-1413287Y667686D01*
X-1415287D01*
G01X-1408487Y671770D02*
Y664770D01*
X-1405153D01*
G01X-1402103D02*
X-1400020Y671770D01*
X-1397937Y664770D01*
G01X-1398687Y667220D02*
X-1401353D01*
G01X-1393220Y671770D02*
Y664770D01*
G01X-1395137Y671770D02*
X-1391303D01*
G01X-1384753Y664770D02*
X-1388087D01*
Y671770D01*
X-1384753D01*
G01X-1386087Y668387D02*
X-1388087D01*
G01X-1381453Y664770D02*
Y671770D01*
X-1379787D01*
X-1379120Y671420D01*
X-1378620Y670953D01*
X-1378203Y670253D01*
X-1377870Y669437D01*
X-1377787Y668270D01*
X-1377870Y667103D01*
X-1378203Y666287D01*
X-1378620Y665586D01*
X-1379120Y665120D01*
X-1379787Y664770D01*
X-1381453D01*
G01X-1415287Y688170D02*
Y695170D01*
X-1413287D01*
X-1412620Y694820D01*
X-1412120Y694003D01*
X-1411953Y693070D01*
X-1412120Y692137D01*
X-1412537Y691437D01*
X-1413287Y691086D01*
X-1415287D01*
G01X-1408487Y695170D02*
Y688170D01*
X-1405153D01*
G01X-1402103D02*
X-1400020Y695170D01*
X-1397937Y688170D01*
G01X-1398687Y690620D02*
X-1401353D01*
G01X-1393220Y695170D02*
Y688170D01*
G01X-1395137Y695170D02*
X-1391303D01*
G01X-1384753Y688170D02*
X-1388087D01*
Y695170D01*
X-1384753D01*
G01X-1386087Y691787D02*
X-1388087D01*
G01X-1381453Y688170D02*
Y695170D01*
X-1379787D01*
X-1379120Y694820D01*
X-1378620Y694353D01*
X-1378203Y693653D01*
X-1377870Y692837D01*
X-1377787Y691670D01*
X-1377870Y690503D01*
X-1378203Y689687D01*
X-1378620Y688986D01*
X-1379120Y688520D01*
X-1379787Y688170D01*
X-1381453D01*
G01X-1415287Y711570D02*
Y718570D01*
X-1413287D01*
X-1412620Y718220D01*
X-1412120Y717403D01*
X-1411953Y716470D01*
X-1412120Y715537D01*
X-1412537Y714837D01*
X-1413287Y714486D01*
X-1415287D01*
G01X-1408487Y718570D02*
Y711570D01*
X-1405153D01*
G01X-1402103D02*
X-1400020Y718570D01*
X-1397937Y711570D01*
G01X-1398687Y714020D02*
X-1401353D01*
G01X-1393220Y718570D02*
Y711570D01*
G01X-1395137Y718570D02*
X-1391303D01*
G01X-1384753Y711570D02*
X-1388087D01*
Y718570D01*
X-1384753D01*
G01X-1386087Y715187D02*
X-1388087D01*
G01X-1381453Y711570D02*
Y718570D01*
X-1379787D01*
X-1379120Y718220D01*
X-1378620Y717753D01*
X-1378203Y717053D01*
X-1377870Y716237D01*
X-1377787Y715070D01*
X-1377870Y713903D01*
X-1378203Y713087D01*
X-1378620Y712386D01*
X-1379120Y711920D01*
X-1379787Y711570D01*
X-1381453D01*
G01X-1415287Y734970D02*
Y741970D01*
X-1413287D01*
X-1412620Y741620D01*
X-1412120Y740803D01*
X-1411953Y739870D01*
X-1412120Y738937D01*
X-1412537Y738237D01*
X-1413287Y737886D01*
X-1415287D01*
G01X-1408487Y741970D02*
Y734970D01*
X-1405153D01*
G01X-1402103D02*
X-1400020Y741970D01*
X-1397937Y734970D01*
G01X-1398687Y737420D02*
X-1401353D01*
G01X-1393220Y741970D02*
Y734970D01*
G01X-1395137Y741970D02*
X-1391303D01*
G01X-1384753Y734970D02*
X-1388087D01*
Y741970D01*
X-1384753D01*
G01X-1386087Y738587D02*
X-1388087D01*
G01X-1381453Y734970D02*
Y741970D01*
X-1379787D01*
X-1379120Y741620D01*
X-1378620Y741153D01*
X-1378203Y740453D01*
X-1377870Y739637D01*
X-1377787Y738470D01*
X-1377870Y737303D01*
X-1378203Y736487D01*
X-1378620Y735786D01*
X-1379120Y735320D01*
X-1379787Y734970D01*
X-1381453D01*
G01X-1415287Y758370D02*
Y765370D01*
X-1413287D01*
X-1412620Y765020D01*
X-1412120Y764203D01*
X-1411953Y763270D01*
X-1412120Y762337D01*
X-1412537Y761637D01*
X-1413287Y761286D01*
X-1415287D01*
G01X-1408487Y765370D02*
Y758370D01*
X-1405153D01*
G01X-1402103D02*
X-1400020Y765370D01*
X-1397937Y758370D01*
G01X-1398687Y760820D02*
X-1401353D01*
G01X-1393220Y765370D02*
Y758370D01*
G01X-1395137Y765370D02*
X-1391303D01*
G01X-1384753Y758370D02*
X-1388087D01*
Y765370D01*
X-1384753D01*
G01X-1386087Y761987D02*
X-1388087D01*
G01X-1381453Y758370D02*
Y765370D01*
X-1379787D01*
X-1379120Y765020D01*
X-1378620Y764553D01*
X-1378203Y763853D01*
X-1377870Y763037D01*
X-1377787Y761870D01*
X-1377870Y760703D01*
X-1378203Y759887D01*
X-1378620Y759186D01*
X-1379120Y758720D01*
X-1379787Y758370D01*
X-1381453D01*
G01X-1415287Y781770D02*
Y788770D01*
X-1413287D01*
X-1412620Y788420D01*
X-1412120Y787603D01*
X-1411953Y786670D01*
X-1412120Y785737D01*
X-1412537Y785037D01*
X-1413287Y784686D01*
X-1415287D01*
G01X-1408487Y788770D02*
Y781770D01*
X-1405153D01*
G01X-1402103D02*
X-1400020Y788770D01*
X-1397937Y781770D01*
G01X-1398687Y784220D02*
X-1401353D01*
G01X-1393220Y788770D02*
Y781770D01*
G01X-1395137Y788770D02*
X-1391303D01*
G01X-1384753Y781770D02*
X-1388087D01*
Y788770D01*
X-1384753D01*
G01X-1386087Y785387D02*
X-1388087D01*
G01X-1381453Y781770D02*
Y788770D01*
X-1379787D01*
X-1379120Y788420D01*
X-1378620Y787953D01*
X-1378203Y787253D01*
X-1377870Y786437D01*
X-1377787Y785270D01*
X-1377870Y784103D01*
X-1378203Y783287D01*
X-1378620Y782586D01*
X-1379120Y782120D01*
X-1379787Y781770D01*
X-1381453D01*
G01X-1415287Y803970D02*
Y810970D01*
X-1413287D01*
X-1412620Y810620D01*
X-1412120Y809803D01*
X-1411953Y808870D01*
X-1412120Y807937D01*
X-1412537Y807237D01*
X-1413287Y806886D01*
X-1415287D01*
G01X-1408487Y810970D02*
Y803970D01*
X-1405153D01*
G01X-1402103D02*
X-1400020Y810970D01*
X-1397937Y803970D01*
G01X-1398687Y806420D02*
X-1401353D01*
G01X-1393220Y810970D02*
Y803970D01*
G01X-1395137Y810970D02*
X-1391303D01*
G01X-1384753Y803970D02*
X-1388087D01*
Y810970D01*
X-1384753D01*
G01X-1386087Y807587D02*
X-1388087D01*
G01X-1381453Y803970D02*
Y810970D01*
X-1379787D01*
X-1379120Y810620D01*
X-1378620Y810153D01*
X-1378203Y809453D01*
X-1377870Y808637D01*
X-1377787Y807470D01*
X-1377870Y806303D01*
X-1378203Y805487D01*
X-1378620Y804786D01*
X-1379120Y804320D01*
X-1379787Y803970D01*
X-1381453D01*
G01X-1342253Y712620D02*
X-1341753Y712037D01*
X-1341170Y711687D01*
X-1340420Y711570D01*
X-1339670Y711803D01*
X-1339087Y712270D01*
X-1338670Y713087D01*
X-1338587Y714020D01*
X-1338753Y714953D01*
X-1339170Y715537D01*
X-1339753Y716003D01*
X-1340337Y716120D01*
X-1340920Y716003D01*
X-1341670Y715537D01*
X-1341420Y718570D01*
X-1339170D01*
G01X-1335453Y712970D02*
X-1334953Y712153D01*
X-1334287Y711687D01*
X-1333537Y711570D01*
X-1332870Y711687D01*
X-1332203Y712270D01*
X-1331787Y712970D01*
X-1331703Y713670D01*
X-1331870Y714486D01*
X-1332453Y715070D01*
X-1333037Y715303D01*
X-1333787D01*
G01X-1333037D02*
X-1332537Y715653D01*
X-1332120Y716237D01*
X-1331953Y716937D01*
X-1332120Y717637D01*
X-1332537Y718220D01*
X-1333287Y718570D01*
X-1334037Y718453D01*
X-1334787Y717987D01*
G01X-1326820Y711570D02*
X-1326237Y711687D01*
X-1325570Y712037D01*
X-1325153Y712620D01*
X-1324987Y713437D01*
X-1325153Y714253D01*
X-1325653Y714953D01*
X-1326403Y715303D01*
X-1327237D01*
X-1327737Y715537D01*
X-1328153Y716120D01*
X-1328320Y716937D01*
X-1328070Y717753D01*
X-1327487Y718337D01*
X-1326820Y718570D01*
X-1326153Y718337D01*
X-1325570Y717753D01*
X-1325320Y716937D01*
X-1325487Y716120D01*
X-1325903Y715537D01*
X-1326403Y715303D01*
X-1327237D01*
X-1327987Y714953D01*
X-1328487Y714253D01*
X-1328653Y713437D01*
X-1328487Y712620D01*
X-1328070Y712037D01*
X-1327403Y711687D01*
X-1326820Y711570D01*
G01X-1340420Y734970D02*
Y741970D01*
X-1341420Y740570D01*
G01Y734970D02*
X-1339420D01*
G01X-1332620D02*
Y741970D01*
X-1335703Y736953D01*
X-1331537D01*
G01X-1325820Y734970D02*
Y741970D01*
X-1328903Y736953D01*
X-1324737D01*
G01X-1343820Y781770D02*
Y788770D01*
X-1344820Y787370D01*
G01Y781770D02*
X-1342820D01*
G01X-1338603Y784686D02*
X-1338020Y785503D01*
X-1337520Y785970D01*
X-1336853Y786203D01*
X-1336270Y785970D01*
X-1335853Y785503D01*
X-1335520Y784803D01*
X-1335437Y783987D01*
X-1335520Y783287D01*
X-1335853Y782586D01*
X-1336353Y782003D01*
X-1336937Y781770D01*
X-1337603Y782003D01*
X-1338187Y782703D01*
X-1338520Y783753D01*
X-1338603Y784920D01*
X-1338437Y786437D01*
X-1338187Y787253D01*
X-1337770Y788070D01*
X-1337187Y788653D01*
X-1336603Y788770D01*
X-1336020Y788537D01*
X-1335603Y787953D01*
G01X-1330220Y788770D02*
X-1330887Y788537D01*
X-1331387Y787953D01*
X-1331720Y787253D01*
X-1331970Y786320D01*
X-1332053Y785270D01*
X-1331970Y784220D01*
X-1331720Y783287D01*
X-1331387Y782586D01*
X-1330887Y782003D01*
X-1330220Y781770D01*
X-1329553Y782003D01*
X-1329053Y782586D01*
X-1328720Y783287D01*
X-1328470Y784220D01*
X-1328387Y785270D01*
X-1328470Y786320D01*
X-1328720Y787253D01*
X-1329053Y787953D01*
X-1329553Y788537D01*
X-1330220Y788770D01*
G01X-1323420D02*
X-1324087Y788537D01*
X-1324587Y787953D01*
X-1324920Y787253D01*
X-1325170Y786320D01*
X-1325253Y785270D01*
X-1325170Y784220D01*
X-1324920Y783287D01*
X-1324587Y782586D01*
X-1324087Y782003D01*
X-1323420Y781770D01*
X-1322753Y782003D01*
X-1322253Y782586D01*
X-1321920Y783287D01*
X-1321670Y784220D01*
X-1321587Y785270D01*
X-1321670Y786320D01*
X-1321920Y787253D01*
X-1322253Y787953D01*
X-1322753Y788537D01*
X-1323420Y788770D01*
G01X-1340420Y803970D02*
X-1341087Y804087D01*
X-1341670Y804553D01*
X-1342170Y805253D01*
X-1342503Y806070D01*
X-1342670Y807003D01*
Y807937D01*
X-1342503Y808870D01*
X-1342170Y809687D01*
X-1341670Y810387D01*
X-1341087Y810853D01*
X-1340420Y810970D01*
X-1339753Y810853D01*
X-1339170Y810387D01*
X-1338670Y809687D01*
X-1338337Y808870D01*
X-1338170Y807937D01*
Y807003D01*
X-1338337Y806070D01*
X-1338670Y805253D01*
X-1339170Y804553D01*
X-1339753Y804087D01*
X-1340420Y803970D01*
G01X-1339753Y805837D02*
X-1338753Y803970D01*
G01X-1333620Y810970D02*
Y803970D01*
G01X-1335537Y810970D02*
X-1331703D01*
G01X-1326820Y803970D02*
Y807120D01*
X-1328487Y810970D01*
G01X-1325153D02*
X-1326820Y807120D01*
G01X-1333620Y337170D02*
X-1333037Y337287D01*
X-1332370Y337637D01*
X-1331953Y338220D01*
X-1331787Y339037D01*
X-1331953Y339853D01*
X-1332453Y340553D01*
X-1333203Y340903D01*
X-1334037D01*
X-1334537Y341137D01*
X-1334953Y341720D01*
X-1335120Y342537D01*
X-1334870Y343353D01*
X-1334287Y343937D01*
X-1333620Y344170D01*
X-1332953Y343937D01*
X-1332370Y343353D01*
X-1332120Y342537D01*
X-1332287Y341720D01*
X-1332703Y341137D01*
X-1333203Y340903D01*
X-1334037D01*
X-1334787Y340553D01*
X-1335287Y339853D01*
X-1335453Y339037D01*
X-1335287Y338220D01*
X-1334870Y337637D01*
X-1334203Y337287D01*
X-1333620Y337170D01*
G01X-1335453Y361970D02*
X-1334953Y361153D01*
X-1334287Y360687D01*
X-1333537Y360570D01*
X-1332870Y360687D01*
X-1332203Y361270D01*
X-1331787Y361970D01*
X-1331703Y362670D01*
X-1331870Y363486D01*
X-1332453Y364070D01*
X-1333037Y364303D01*
X-1333787D01*
G01X-1333037D02*
X-1332537Y364653D01*
X-1332120Y365237D01*
X-1331953Y365937D01*
X-1332120Y366637D01*
X-1332537Y367220D01*
X-1333287Y367570D01*
X-1334037Y367453D01*
X-1334787Y366987D01*
G01X-1335203Y389803D02*
X-1334703Y390503D01*
X-1334120Y390853D01*
X-1333453Y390970D01*
X-1332620Y390737D01*
X-1332037Y390153D01*
X-1331870Y389453D01*
X-1331953Y388753D01*
X-1332287Y388170D01*
X-1333953Y387003D01*
X-1334703Y386187D01*
X-1335203Y385020D01*
X-1335370Y383970D01*
X-1331870D01*
G01X-1332620Y407370D02*
Y414370D01*
X-1335703Y409353D01*
X-1331537D01*
G01X-1332620Y430770D02*
Y437770D01*
X-1335703Y432753D01*
X-1331537D01*
G01X-1332620Y454170D02*
Y461170D01*
X-1335703Y456153D01*
X-1331537D01*
G01X-1332620Y477570D02*
Y484570D01*
X-1335703Y479553D01*
X-1331537D01*
G01X-1335203Y503886D02*
X-1334620Y504703D01*
X-1334120Y505170D01*
X-1333453Y505403D01*
X-1332870Y505170D01*
X-1332453Y504703D01*
X-1332120Y504003D01*
X-1332037Y503187D01*
X-1332120Y502487D01*
X-1332453Y501786D01*
X-1332953Y501203D01*
X-1333537Y500970D01*
X-1334203Y501203D01*
X-1334787Y501903D01*
X-1335120Y502953D01*
X-1335203Y504120D01*
X-1335037Y505637D01*
X-1334787Y506453D01*
X-1334370Y507270D01*
X-1333787Y507853D01*
X-1333203Y507970D01*
X-1332620Y507737D01*
X-1332203Y507153D01*
G01X-1332620Y524370D02*
Y531370D01*
X-1335703Y526353D01*
X-1331537D01*
G01X-1332620Y547770D02*
Y554770D01*
X-1335703Y549753D01*
X-1331537D01*
G01X-1336020Y571170D02*
Y578170D01*
X-1339103Y573153D01*
X-1334937D01*
G01X-1329220Y571170D02*
Y578170D01*
X-1332303Y573153D01*
X-1328137D01*
G01X-1333620Y594570D02*
X-1333037Y594687D01*
X-1332370Y595037D01*
X-1331953Y595620D01*
X-1331787Y596437D01*
X-1331953Y597253D01*
X-1332453Y597953D01*
X-1333203Y598303D01*
X-1334037D01*
X-1334537Y598537D01*
X-1334953Y599120D01*
X-1335120Y599937D01*
X-1334870Y600753D01*
X-1334287Y601337D01*
X-1333620Y601570D01*
X-1332953Y601337D01*
X-1332370Y600753D01*
X-1332120Y599937D01*
X-1332287Y599120D01*
X-1332703Y598537D01*
X-1333203Y598303D01*
X-1334037D01*
X-1334787Y597953D01*
X-1335287Y597253D01*
X-1335453Y596437D01*
X-1335287Y595620D01*
X-1334870Y595037D01*
X-1334203Y594687D01*
X-1333620Y594570D01*
G01X-1337020Y617970D02*
Y624970D01*
X-1338020Y623570D01*
G01Y617970D02*
X-1336020D01*
G01X-1330220D02*
X-1329637Y618087D01*
X-1328970Y618437D01*
X-1328553Y619020D01*
X-1328387Y619837D01*
X-1328553Y620653D01*
X-1329053Y621353D01*
X-1329803Y621703D01*
X-1330637D01*
X-1331137Y621937D01*
X-1331553Y622520D01*
X-1331720Y623337D01*
X-1331470Y624153D01*
X-1330887Y624737D01*
X-1330220Y624970D01*
X-1329553Y624737D01*
X-1328970Y624153D01*
X-1328720Y623337D01*
X-1328887Y622520D01*
X-1329303Y621937D01*
X-1329803Y621703D01*
X-1330637D01*
X-1331387Y621353D01*
X-1331887Y620653D01*
X-1332053Y619837D01*
X-1331887Y619020D01*
X-1331470Y618437D01*
X-1330803Y618087D01*
X-1330220Y617970D01*
G01X-1335203Y647203D02*
X-1334703Y647903D01*
X-1334120Y648253D01*
X-1333453Y648370D01*
X-1332620Y648137D01*
X-1332037Y647553D01*
X-1331870Y646853D01*
X-1331953Y646153D01*
X-1332287Y645570D01*
X-1333953Y644403D01*
X-1334703Y643587D01*
X-1335203Y642420D01*
X-1335370Y641370D01*
X-1331870D01*
G01X-1336020Y664770D02*
Y671770D01*
X-1339103Y666753D01*
X-1334937D01*
G01X-1330220Y664770D02*
X-1329637Y664887D01*
X-1328970Y665237D01*
X-1328553Y665820D01*
X-1328387Y666637D01*
X-1328553Y667453D01*
X-1329053Y668153D01*
X-1329803Y668503D01*
X-1330637D01*
X-1331137Y668737D01*
X-1331553Y669320D01*
X-1331720Y670137D01*
X-1331470Y670953D01*
X-1330887Y671537D01*
X-1330220Y671770D01*
X-1329553Y671537D01*
X-1328970Y670953D01*
X-1328720Y670137D01*
X-1328887Y669320D01*
X-1329303Y668737D01*
X-1329803Y668503D01*
X-1330637D01*
X-1331387Y668153D01*
X-1331887Y667453D01*
X-1332053Y666637D01*
X-1331887Y665820D01*
X-1331470Y665237D01*
X-1330803Y664887D01*
X-1330220Y664770D01*
G01X-1338603Y694003D02*
X-1338103Y694703D01*
X-1337520Y695053D01*
X-1336853Y695170D01*
X-1336020Y694937D01*
X-1335437Y694353D01*
X-1335270Y693653D01*
X-1335353Y692953D01*
X-1335687Y692370D01*
X-1337353Y691203D01*
X-1338103Y690387D01*
X-1338603Y689220D01*
X-1338770Y688170D01*
X-1335270D01*
G01X-1330220Y695170D02*
X-1330887Y694937D01*
X-1331387Y694353D01*
X-1331720Y693653D01*
X-1331970Y692720D01*
X-1332053Y691670D01*
X-1331970Y690620D01*
X-1331720Y689687D01*
X-1331387Y688986D01*
X-1330887Y688403D01*
X-1330220Y688170D01*
X-1329553Y688403D01*
X-1329053Y688986D01*
X-1328720Y689687D01*
X-1328470Y690620D01*
X-1328387Y691670D01*
X-1328470Y692720D01*
X-1328720Y693653D01*
X-1329053Y694353D01*
X-1329553Y694937D01*
X-1330220Y695170D01*
G01X-1336020Y758370D02*
Y765370D01*
X-1339103Y760353D01*
X-1334937D01*
G01X-1330220Y758370D02*
X-1329637Y758487D01*
X-1328970Y758837D01*
X-1328553Y759420D01*
X-1328387Y760237D01*
X-1328553Y761053D01*
X-1329053Y761753D01*
X-1329803Y762103D01*
X-1330637D01*
X-1331137Y762337D01*
X-1331553Y762920D01*
X-1331720Y763737D01*
X-1331470Y764553D01*
X-1330887Y765137D01*
X-1330220Y765370D01*
X-1329553Y765137D01*
X-1328970Y764553D01*
X-1328720Y763737D01*
X-1328887Y762920D01*
X-1329303Y762337D01*
X-1329803Y762103D01*
X-1330637D01*
X-1331387Y761753D01*
X-1331887Y761053D01*
X-1332053Y760237D01*
X-1331887Y759420D01*
X-1331470Y758837D01*
X-1330803Y758487D01*
X-1330220Y758370D01*
G01X-1312406Y97195D02*
X-1312476Y104194D01*
X-1310393Y104215D01*
X-1309723Y103872D01*
X-1309301Y103410D01*
X-1309125Y102478D01*
X-1309282Y101543D01*
X-1309777Y100955D01*
X-1310356Y100599D01*
X-1312440Y100578D01*
G01X-1310356Y100599D02*
X-1309073Y97228D01*
G01X-1304010Y104279D02*
X-1304674Y104039D01*
X-1305168Y103451D01*
X-1305494Y102748D01*
X-1305735Y101812D01*
X-1305808Y100761D01*
X-1305714Y99712D01*
X-1305455Y98781D01*
X-1305114Y98084D01*
X-1304609Y97506D01*
X-1303940Y97280D01*
X-1303275Y97520D01*
X-1302781Y98108D01*
X-1302455Y98811D01*
X-1302214Y99747D01*
X-1302141Y100798D01*
X-1302235Y101847D01*
X-1302494Y102778D01*
X-1302835Y103474D01*
X-1303341Y104053D01*
X-1304010Y104279D01*
G01X-1297138Y97114D02*
X-1297305Y97229D01*
X-1297308Y97463D01*
X-1297142Y97581D01*
X-1296974Y97466D01*
X-1296972Y97233D01*
X-1297138Y97114D01*
G01X-1290410Y104416D02*
X-1291075Y104176D01*
X-1291569Y103587D01*
X-1291895Y102884D01*
X-1292136Y101948D01*
X-1292209Y100897D01*
X-1292115Y99848D01*
X-1291855Y98917D01*
X-1291515Y98221D01*
X-1291009Y97642D01*
X-1290340Y97416D01*
X-1289676Y97656D01*
X-1289182Y98244D01*
X-1288855Y98947D01*
X-1288615Y99883D01*
X-1288542Y100934D01*
X-1288636Y101983D01*
X-1288895Y102914D01*
X-1289236Y103611D01*
X-1289741Y104189D01*
X-1290410Y104416D01*
G01X-1285384Y98515D02*
X-1284879Y97937D01*
X-1284292Y97593D01*
X-1283541Y97484D01*
X-1282793Y97725D01*
X-1282214Y98197D01*
X-1281806Y99018D01*
X-1281732Y99952D01*
X-1281908Y100884D01*
X-1282330Y101463D01*
X-1282918Y101924D01*
X-1283503Y102034D01*
X-1284085Y101912D01*
X-1284830Y101438D01*
X-1284611Y104474D01*
X-1282361Y104496D01*
G01X-1278166Y98354D02*
X-1277577Y97777D01*
X-1276908Y97550D01*
X-1276243Y97790D01*
X-1275667Y98496D01*
X-1275261Y99550D01*
X-1275105Y100602D01*
X-1275118Y101885D01*
X-1275295Y102933D01*
X-1275721Y103863D01*
X-1276225Y104324D01*
X-1276811Y104552D01*
X-1277475Y104312D01*
X-1277971Y103840D01*
X-1278297Y103137D01*
X-1278454Y102202D01*
X-1278279Y101387D01*
X-1277855Y100574D01*
X-1277350Y100113D01*
X-1276766Y100002D01*
X-1276101Y100242D01*
X-1275607Y100830D01*
X-1275118Y101885D01*
G01X-1303624Y83282D02*
X-1303695Y90282D01*
X-1304680Y88872D01*
G01X-1304624Y83272D02*
X-1302624Y83292D01*
G01X-1296822Y83117D02*
X-1296990Y83232D01*
X-1296993Y83465D01*
X-1296827Y83583D01*
X-1296659Y83469D01*
X-1296657Y83235D01*
X-1296822Y83117D01*
G01X-1291869Y84450D02*
X-1291363Y83872D01*
X-1290776Y83527D01*
X-1290025Y83418D01*
X-1289277Y83659D01*
X-1288699Y84132D01*
X-1288290Y84952D01*
X-1288216Y85886D01*
X-1288392Y86818D01*
X-1288815Y87397D01*
X-1289403Y87858D01*
X-1289987Y87969D01*
X-1290569Y87846D01*
X-1291315Y87372D01*
X-1291095Y90408D01*
X-1288845Y90431D01*
G01X-1283296Y90486D02*
X-1283960Y90246D01*
X-1284454Y89658D01*
X-1284780Y88955D01*
X-1285021Y88019D01*
X-1285094Y86968D01*
X-1285000Y85919D01*
X-1284740Y84988D01*
X-1284400Y84291D01*
X-1283894Y83713D01*
X-1283225Y83486D01*
X-1282561Y83726D01*
X-1282067Y84315D01*
X-1281741Y85018D01*
X-1281500Y85954D01*
X-1281427Y87005D01*
X-1281521Y88054D01*
X-1281780Y88985D01*
X-1282121Y89681D01*
X-1282627Y90260D01*
X-1283296Y90486D01*
G01X-1281400Y-264275D02*
X-1288400D01*
X-1287000Y-265275D01*
G01X-1281400D02*
Y-263275D01*
G01X-1287233Y-259058D02*
X-1287933Y-258558D01*
X-1288283Y-257975D01*
X-1288400Y-257308D01*
X-1288167Y-256475D01*
X-1287583Y-255892D01*
X-1286883Y-255725D01*
X-1286183Y-255808D01*
X-1285600Y-256142D01*
X-1284433Y-257808D01*
X-1283617Y-258558D01*
X-1282450Y-259058D01*
X-1281400Y-259225D01*
Y-255725D01*
G01X-1281167Y-250675D02*
X-1281283Y-250842D01*
X-1281517D01*
X-1281633Y-250675D01*
X-1281517Y-250508D01*
X-1281283D01*
X-1281167Y-250675D01*
G01X-1281400Y-244042D02*
X-1282917Y-243875D01*
X-1284200Y-243625D01*
X-1285367Y-243292D01*
X-1286650Y-242875D01*
X-1288400Y-242208D01*
Y-245542D01*
G01X-1281400Y-237075D02*
X-1281517Y-236492D01*
X-1281867Y-235825D01*
X-1282450Y-235408D01*
X-1283267Y-235242D01*
X-1284083Y-235408D01*
X-1284783Y-235908D01*
X-1285133Y-236658D01*
Y-237492D01*
X-1285367Y-237992D01*
X-1285950Y-238408D01*
X-1286767Y-238575D01*
X-1287583Y-238325D01*
X-1288167Y-237742D01*
X-1288400Y-237075D01*
X-1288167Y-236408D01*
X-1287583Y-235825D01*
X-1286767Y-235575D01*
X-1285950Y-235742D01*
X-1285367Y-236158D01*
X-1285133Y-236658D01*
Y-237492D01*
X-1284783Y-238242D01*
X-1284083Y-238742D01*
X-1283267Y-238908D01*
X-1282450Y-238742D01*
X-1281867Y-238325D01*
X-1281517Y-237658D01*
X-1281400Y-237075D01*
G01Y-230275D02*
X-1281517Y-229692D01*
X-1281867Y-229025D01*
X-1282450Y-228608D01*
X-1283267Y-228442D01*
X-1284083Y-228608D01*
X-1284783Y-229108D01*
X-1285133Y-229858D01*
Y-230692D01*
X-1285367Y-231192D01*
X-1285950Y-231608D01*
X-1286767Y-231775D01*
X-1287583Y-231525D01*
X-1288167Y-230942D01*
X-1288400Y-230275D01*
X-1288167Y-229608D01*
X-1287583Y-229025D01*
X-1286767Y-228775D01*
X-1285950Y-228942D01*
X-1285367Y-229358D01*
X-1285133Y-229858D01*
Y-230692D01*
X-1284783Y-231442D01*
X-1284083Y-231942D01*
X-1283267Y-232108D01*
X-1282450Y-231942D01*
X-1281867Y-231525D01*
X-1281517Y-230858D01*
X-1281400Y-230275D01*
G01X-1268800Y-265933D02*
X-1267983Y-265433D01*
X-1267517Y-264767D01*
X-1267400Y-264017D01*
X-1267517Y-263350D01*
X-1268100Y-262683D01*
X-1268800Y-262267D01*
X-1269500Y-262183D01*
X-1270316Y-262350D01*
X-1270900Y-262933D01*
X-1271133Y-263517D01*
Y-264267D01*
G01Y-263517D02*
X-1271483Y-263017D01*
X-1272067Y-262600D01*
X-1272767Y-262433D01*
X-1273467Y-262600D01*
X-1274050Y-263017D01*
X-1274400Y-263767D01*
X-1274283Y-264517D01*
X-1273817Y-265267D01*
G01X-1273233Y-258883D02*
X-1273933Y-258383D01*
X-1274283Y-257800D01*
X-1274400Y-257133D01*
X-1274167Y-256300D01*
X-1273583Y-255717D01*
X-1272883Y-255550D01*
X-1272183Y-255633D01*
X-1271600Y-255967D01*
X-1270433Y-257633D01*
X-1269617Y-258383D01*
X-1268450Y-258883D01*
X-1267400Y-259050D01*
Y-255550D01*
G01Y-249500D02*
X-1274400D01*
X-1269383Y-252583D01*
Y-248417D01*
G01X-1267167Y-243700D02*
X-1267283Y-243867D01*
X-1267517D01*
X-1267633Y-243700D01*
X-1267517Y-243533D01*
X-1267283D01*
X-1267167Y-243700D01*
G01X-1267400Y-236900D02*
X-1267517Y-236317D01*
X-1267867Y-235650D01*
X-1268450Y-235233D01*
X-1269267Y-235067D01*
X-1270083Y-235233D01*
X-1270783Y-235733D01*
X-1271133Y-236483D01*
Y-237317D01*
X-1271367Y-237817D01*
X-1271950Y-238233D01*
X-1272767Y-238400D01*
X-1273583Y-238150D01*
X-1274167Y-237567D01*
X-1274400Y-236900D01*
X-1274167Y-236233D01*
X-1273583Y-235650D01*
X-1272767Y-235400D01*
X-1271950Y-235567D01*
X-1271367Y-235983D01*
X-1271133Y-236483D01*
Y-237317D01*
X-1270783Y-238067D01*
X-1270083Y-238567D01*
X-1269267Y-238733D01*
X-1268450Y-238567D01*
X-1267867Y-238150D01*
X-1267517Y-237483D01*
X-1267400Y-236900D01*
G01X-1273233Y-231683D02*
X-1273933Y-231183D01*
X-1274283Y-230600D01*
X-1274400Y-229933D01*
X-1274167Y-229100D01*
X-1273583Y-228517D01*
X-1272883Y-228350D01*
X-1272183Y-228433D01*
X-1271600Y-228767D01*
X-1270433Y-230433D01*
X-1269617Y-231183D01*
X-1268450Y-231683D01*
X-1267400Y-231850D01*
Y-228350D01*
G01X-1210100Y-264975D02*
X-1217100D01*
X-1215700Y-265975D01*
G01X-1210100D02*
Y-263975D01*
G01X-1215933Y-259758D02*
X-1216633Y-259258D01*
X-1216983Y-258675D01*
X-1217100Y-258008D01*
X-1216867Y-257175D01*
X-1216283Y-256592D01*
X-1215583Y-256425D01*
X-1214883Y-256508D01*
X-1214300Y-256842D01*
X-1213133Y-258508D01*
X-1212317Y-259258D01*
X-1211150Y-259758D01*
X-1210100Y-259925D01*
Y-256425D01*
G01X-1209867Y-251375D02*
X-1209983Y-251542D01*
X-1210217D01*
X-1210333Y-251375D01*
X-1210217Y-251208D01*
X-1209983D01*
X-1209867Y-251375D01*
G01X-1217100Y-244575D02*
X-1216867Y-245242D01*
X-1216283Y-245742D01*
X-1215583Y-246075D01*
X-1214650Y-246325D01*
X-1213600Y-246408D01*
X-1212550Y-246325D01*
X-1211617Y-246075D01*
X-1210916Y-245742D01*
X-1210333Y-245242D01*
X-1210100Y-244575D01*
X-1210333Y-243908D01*
X-1210916Y-243408D01*
X-1211617Y-243075D01*
X-1212550Y-242825D01*
X-1213600Y-242742D01*
X-1214650Y-242825D01*
X-1215583Y-243075D01*
X-1216283Y-243408D01*
X-1216867Y-243908D01*
X-1217100Y-244575D01*
G01X-1210100Y-237942D02*
X-1211617Y-237775D01*
X-1212900Y-237525D01*
X-1214067Y-237192D01*
X-1215350Y-236775D01*
X-1217100Y-236108D01*
Y-239442D01*
G01X-1210100Y-229975D02*
X-1217100D01*
X-1212083Y-233058D01*
Y-228892D01*
G01X-1197500Y-266633D02*
X-1196683Y-266133D01*
X-1196217Y-265467D01*
X-1196100Y-264717D01*
X-1196217Y-264050D01*
X-1196800Y-263383D01*
X-1197500Y-262967D01*
X-1198200Y-262883D01*
X-1199016Y-263050D01*
X-1199600Y-263633D01*
X-1199833Y-264217D01*
Y-264967D01*
G01Y-264217D02*
X-1200183Y-263717D01*
X-1200767Y-263300D01*
X-1201467Y-263133D01*
X-1202167Y-263300D01*
X-1202750Y-263717D01*
X-1203100Y-264467D01*
X-1202983Y-265217D01*
X-1202517Y-265967D01*
G01X-1203100Y-258000D02*
X-1202867Y-258667D01*
X-1202283Y-259167D01*
X-1201583Y-259500D01*
X-1200650Y-259750D01*
X-1199600Y-259833D01*
X-1198550Y-259750D01*
X-1197617Y-259500D01*
X-1196916Y-259167D01*
X-1196333Y-258667D01*
X-1196100Y-258000D01*
X-1196333Y-257333D01*
X-1196916Y-256833D01*
X-1197617Y-256500D01*
X-1198550Y-256250D01*
X-1199600Y-256167D01*
X-1200650Y-256250D01*
X-1201583Y-256500D01*
X-1202283Y-256833D01*
X-1202867Y-257333D01*
X-1203100Y-258000D01*
G01X-1199016Y-252783D02*
X-1199833Y-252200D01*
X-1200300Y-251700D01*
X-1200533Y-251033D01*
X-1200300Y-250450D01*
X-1199833Y-250033D01*
X-1199133Y-249700D01*
X-1198317Y-249617D01*
X-1197617Y-249700D01*
X-1196916Y-250033D01*
X-1196333Y-250533D01*
X-1196100Y-251117D01*
X-1196333Y-251783D01*
X-1197033Y-252367D01*
X-1198083Y-252700D01*
X-1199250Y-252783D01*
X-1200767Y-252617D01*
X-1201583Y-252367D01*
X-1202400Y-251950D01*
X-1202983Y-251367D01*
X-1203100Y-250783D01*
X-1202867Y-250200D01*
X-1202283Y-249783D01*
G01X-1195867Y-244400D02*
X-1195983Y-244567D01*
X-1196217D01*
X-1196333Y-244400D01*
X-1196217Y-244233D01*
X-1195983D01*
X-1195867Y-244400D01*
G01X-1199016Y-239183D02*
X-1199833Y-238600D01*
X-1200300Y-238100D01*
X-1200533Y-237433D01*
X-1200300Y-236850D01*
X-1199833Y-236433D01*
X-1199133Y-236100D01*
X-1198317Y-236017D01*
X-1197617Y-236100D01*
X-1196916Y-236433D01*
X-1196333Y-236933D01*
X-1196100Y-237517D01*
X-1196333Y-238183D01*
X-1197033Y-238767D01*
X-1198083Y-239100D01*
X-1199250Y-239183D01*
X-1200767Y-239017D01*
X-1201583Y-238767D01*
X-1202400Y-238350D01*
X-1202983Y-237767D01*
X-1203100Y-237183D01*
X-1202867Y-236600D01*
X-1202283Y-236183D01*
G01X-1196100Y-230800D02*
X-1196217Y-230217D01*
X-1196567Y-229550D01*
X-1197150Y-229133D01*
X-1197967Y-228967D01*
X-1198783Y-229133D01*
X-1199483Y-229633D01*
X-1199833Y-230383D01*
Y-231217D01*
X-1200067Y-231717D01*
X-1200650Y-232133D01*
X-1201467Y-232300D01*
X-1202283Y-232050D01*
X-1202867Y-231467D01*
X-1203100Y-230800D01*
X-1202867Y-230133D01*
X-1202283Y-229550D01*
X-1201467Y-229300D01*
X-1200650Y-229467D01*
X-1200067Y-229883D01*
X-1199833Y-230383D01*
Y-231217D01*
X-1199483Y-231967D01*
X-1198783Y-232467D01*
X-1197967Y-232633D01*
X-1197150Y-232467D01*
X-1196567Y-232050D01*
X-1196217Y-231383D01*
X-1196100Y-230800D01*
G01X-1182476Y83183D02*
X-1189476D01*
X-1188076Y82183D01*
G01X-1182476D02*
Y84183D01*
G01Y89983D02*
X-1189476D01*
X-1188076Y88983D01*
G01X-1182476D02*
Y90983D01*
G01X-1182243Y96783D02*
X-1182360Y96616D01*
X-1182593D01*
X-1182710Y96783D01*
X-1182593Y96950D01*
X-1182360D01*
X-1182243Y96783D01*
G01X-1182476Y103416D02*
X-1183993Y103583D01*
X-1185276Y103833D01*
X-1186443Y104166D01*
X-1187726Y104583D01*
X-1189476Y105250D01*
Y101916D01*
G01X-1183293Y108966D02*
X-1182710Y109550D01*
X-1182476Y110216D01*
X-1182710Y110883D01*
X-1183410Y111466D01*
X-1184460Y111883D01*
X-1185510Y112050D01*
X-1186793D01*
X-1187843Y111883D01*
X-1188776Y111466D01*
X-1189243Y110966D01*
X-1189476Y110383D01*
X-1189243Y109716D01*
X-1188776Y109216D01*
X-1188076Y108883D01*
X-1187143Y108716D01*
X-1186326Y108883D01*
X-1185510Y109300D01*
X-1185043Y109800D01*
X-1184926Y110383D01*
X-1185160Y111050D01*
X-1185743Y111550D01*
X-1186793Y112050D01*
G01X-1189476Y117183D02*
X-1189243Y116516D01*
X-1188660Y116016D01*
X-1187960Y115683D01*
X-1187026Y115433D01*
X-1185976Y115350D01*
X-1184926Y115433D01*
X-1183993Y115683D01*
X-1183293Y116016D01*
X-1182710Y116516D01*
X-1182476Y117183D01*
X-1182710Y117850D01*
X-1183293Y118350D01*
X-1183993Y118683D01*
X-1184926Y118933D01*
X-1185976Y119016D01*
X-1187026Y118933D01*
X-1187960Y118683D01*
X-1188660Y118350D01*
X-1189243Y117850D01*
X-1189476Y117183D01*
G01X-1174310Y81775D02*
X-1175010Y82275D01*
X-1175360Y82858D01*
X-1175476Y83525D01*
X-1175243Y84358D01*
X-1174660Y84941D01*
X-1173960Y85108D01*
X-1173260Y85025D01*
X-1172676Y84691D01*
X-1171510Y83025D01*
X-1170693Y82275D01*
X-1169526Y81775D01*
X-1168476Y81608D01*
Y85108D01*
G01X-1169293Y88741D02*
X-1168710Y89325D01*
X-1168476Y89991D01*
X-1168710Y90658D01*
X-1169410Y91241D01*
X-1170460Y91658D01*
X-1171510Y91825D01*
X-1172793D01*
X-1173843Y91658D01*
X-1174776Y91241D01*
X-1175243Y90741D01*
X-1175476Y90158D01*
X-1175243Y89491D01*
X-1174776Y88991D01*
X-1174076Y88658D01*
X-1173143Y88491D01*
X-1172326Y88658D01*
X-1171510Y89075D01*
X-1171043Y89575D01*
X-1170926Y90158D01*
X-1171160Y90825D01*
X-1171743Y91325D01*
X-1172793Y91825D01*
G01X-1169293Y95541D02*
X-1168710Y96125D01*
X-1168476Y96791D01*
X-1168710Y97458D01*
X-1169410Y98041D01*
X-1170460Y98458D01*
X-1171510Y98625D01*
X-1172793D01*
X-1173843Y98458D01*
X-1174776Y98041D01*
X-1175243Y97541D01*
X-1175476Y96958D01*
X-1175243Y96291D01*
X-1174776Y95791D01*
X-1174076Y95458D01*
X-1173143Y95291D01*
X-1172326Y95458D01*
X-1171510Y95875D01*
X-1171043Y96375D01*
X-1170926Y96958D01*
X-1171160Y97625D01*
X-1171743Y98125D01*
X-1172793Y98625D01*
G01X-1168243Y103758D02*
X-1168360Y103591D01*
X-1168593D01*
X-1168710Y103758D01*
X-1168593Y103925D01*
X-1168360D01*
X-1168243Y103758D01*
G01X-1168476Y111558D02*
X-1175476D01*
X-1170460Y108475D01*
Y112641D01*
G01X-1171393Y115775D02*
X-1172210Y116358D01*
X-1172676Y116858D01*
X-1172910Y117525D01*
X-1172676Y118108D01*
X-1172210Y118525D01*
X-1171510Y118858D01*
X-1170693Y118941D01*
X-1169993Y118858D01*
X-1169293Y118525D01*
X-1168710Y118025D01*
X-1168476Y117441D01*
X-1168710Y116775D01*
X-1169410Y116191D01*
X-1170460Y115858D01*
X-1171626Y115775D01*
X-1173143Y115941D01*
X-1173960Y116191D01*
X-1174776Y116608D01*
X-1175360Y117191D01*
X-1175476Y117775D01*
X-1175243Y118358D01*
X-1174660Y118775D01*
G01X-1135224Y-226745D02*
X-1135264Y-219745D01*
X-1133181Y-219733D01*
X-1132512Y-220079D01*
X-1132093Y-220543D01*
X-1131921Y-221476D01*
X-1132082Y-222410D01*
X-1132579Y-222996D01*
X-1133160Y-223350D01*
X-1135244Y-223361D01*
G01X-1133160Y-223350D02*
X-1131891Y-226726D01*
G01X-1126798Y-219696D02*
X-1127463Y-219933D01*
X-1127960Y-220520D01*
X-1128289Y-221221D01*
X-1128534Y-222156D01*
X-1128611Y-223207D01*
X-1128522Y-224256D01*
X-1128267Y-225188D01*
X-1127929Y-225886D01*
X-1127426Y-226467D01*
X-1126758Y-226696D01*
X-1126093Y-226459D01*
X-1125596Y-225873D01*
X-1125266Y-225171D01*
X-1125022Y-224236D01*
X-1124944Y-223186D01*
X-1125034Y-222136D01*
X-1125289Y-221204D01*
X-1125626Y-220506D01*
X-1126130Y-219926D01*
X-1126798Y-219696D01*
G01X-1119957Y-226891D02*
X-1120124Y-226775D01*
X-1120125Y-226542D01*
X-1119959Y-226424D01*
X-1119792Y-226540D01*
X-1119791Y-226773D01*
X-1119957Y-226891D01*
G01X-1113198Y-219619D02*
X-1113863Y-219856D01*
X-1114360Y-220442D01*
X-1114689Y-221144D01*
X-1114934Y-222079D01*
X-1115011Y-223129D01*
X-1114922Y-224179D01*
X-1114667Y-225111D01*
X-1114329Y-225809D01*
X-1113826Y-226389D01*
X-1113158Y-226619D01*
X-1112493Y-226382D01*
X-1111996Y-225796D01*
X-1111667Y-225094D01*
X-1111422Y-224159D01*
X-1111345Y-223108D01*
X-1111434Y-222059D01*
X-1111689Y-221127D01*
X-1112027Y-220429D01*
X-1112530Y-219848D01*
X-1113198Y-219619D01*
G01X-1107975Y-220756D02*
X-1107479Y-220053D01*
X-1106897Y-219699D01*
X-1106231Y-219579D01*
X-1105397Y-219808D01*
X-1104810Y-220388D01*
X-1104639Y-221086D01*
X-1104719Y-221787D01*
X-1105049Y-222372D01*
X-1106709Y-223548D01*
X-1107454Y-224369D01*
X-1107947Y-225539D01*
X-1108108Y-226590D01*
X-1104608Y-226570D01*
G01X-1099598Y-219541D02*
X-1100264Y-219778D01*
X-1100760Y-220364D01*
X-1101090Y-221066D01*
X-1101334Y-222001D01*
X-1101412Y-223052D01*
X-1101322Y-224101D01*
X-1101067Y-225033D01*
X-1100730Y-225731D01*
X-1100226Y-226312D01*
X-1099558Y-226541D01*
X-1098893Y-226304D01*
X-1098396Y-225718D01*
X-1098067Y-225016D01*
X-1097822Y-224081D01*
X-1097745Y-223031D01*
X-1097834Y-221981D01*
X-1098090Y-221049D01*
X-1098427Y-220351D01*
X-1098930Y-219771D01*
X-1099598Y-219541D01*
G01X-1125371Y-253770D02*
X-1126210Y-252607D01*
X-1126633Y-251443D01*
X-1126657Y-246776D01*
X-1126246Y-245607D01*
X-1125419Y-244436D01*
G01X-1117166Y-251394D02*
X-1117202Y-244394D01*
X-1120260Y-249427D01*
X-1116093Y-249405D01*
G01X-1112640Y-246704D02*
X-1110116Y-251358D01*
G01X-1110140Y-246691D02*
X-1112616Y-251371D01*
G01X-1104138Y-253660D02*
X-1103310Y-252489D01*
X-1102900Y-251321D01*
X-1102924Y-246654D01*
X-1103346Y-245489D01*
X-1104186Y-244327D01*
G01X-1126543Y-233695D02*
X-1127208Y-233932D01*
X-1127705Y-234519D01*
X-1128034Y-235220D01*
X-1128279Y-236155D01*
X-1128356Y-237206D01*
X-1128267Y-238255D01*
X-1128012Y-239187D01*
X-1127674Y-239885D01*
X-1127171Y-240466D01*
X-1126503Y-240695D01*
X-1125838Y-240458D01*
X-1125341Y-239872D01*
X-1125012Y-239170D01*
X-1124767Y-238235D01*
X-1124690Y-237185D01*
X-1124779Y-236135D01*
X-1125034Y-235203D01*
X-1125372Y-234505D01*
X-1125875Y-233925D01*
X-1126543Y-233695D01*
G01X-1119702Y-240890D02*
X-1119869Y-240774D01*
X-1119870Y-240541D01*
X-1119704Y-240423D01*
X-1119537Y-240539D01*
X-1119536Y-240772D01*
X-1119702Y-240890D01*
G01X-1114742Y-239578D02*
X-1114239Y-240158D01*
X-1113654Y-240505D01*
X-1112903Y-240617D01*
X-1112154Y-240380D01*
X-1111574Y-239910D01*
X-1111162Y-239091D01*
X-1111084Y-238157D01*
X-1111256Y-237225D01*
X-1111676Y-236644D01*
X-1112262Y-236180D01*
X-1112846Y-236067D01*
X-1113428Y-236187D01*
X-1114176Y-236658D01*
X-1113943Y-233623D01*
X-1111693Y-233610D01*
G01X-1106143Y-233579D02*
X-1106809Y-233816D01*
X-1107305Y-234402D01*
X-1107635Y-235104D01*
X-1107879Y-236039D01*
X-1107957Y-237089D01*
X-1107867Y-238139D01*
X-1107612Y-239071D01*
X-1107275Y-239769D01*
X-1106771Y-240349D01*
X-1106103Y-240579D01*
X-1105438Y-240342D01*
X-1104941Y-239755D01*
X-1104612Y-239054D01*
X-1104367Y-238119D01*
X-1104290Y-237068D01*
X-1104379Y-236019D01*
X-1104634Y-235087D01*
X-1104972Y-234389D01*
X-1105475Y-233808D01*
X-1106143Y-233579D01*
G01X-1011945Y42929D02*
X-1011281Y42342D01*
X-1010533Y41988D01*
X-1009867Y41984D01*
X-1009198Y42330D01*
X-1008695Y42910D01*
X-1008440Y43726D01*
X-1008602Y44543D01*
X-1009015Y45246D01*
X-1009762Y45717D01*
X-1010761Y45956D01*
X-1011341Y46426D01*
X-1011587Y47244D01*
X-1011415Y48059D01*
X-1010995Y48640D01*
X-1010410Y48987D01*
X-1009827Y48984D01*
X-1009244Y48747D01*
X-1008748Y48161D01*
G01X-1001733Y41937D02*
X-1005067Y41956D01*
X-1005027Y48956D01*
X-1001693Y48937D01*
G01X-1003046Y45561D02*
X-1005046Y45573D01*
G01X-994934Y41898D02*
X-998267Y41917D01*
X-998227Y48917D01*
X-994893Y48898D01*
G01X-996246Y45522D02*
X-998246Y45534D01*
G01X-984834Y41840D02*
X-984794Y48840D01*
X-983127Y48830D01*
X-982462Y48476D01*
X-981965Y48007D01*
X-981552Y47305D01*
X-981224Y46486D01*
X-981147Y45319D01*
X-981237Y44153D01*
X-981575Y43338D01*
X-981996Y42640D01*
X-982499Y42176D01*
X-983167Y41830D01*
X-984834Y41840D01*
G01X-974534Y41781D02*
X-977867Y41800D01*
X-977827Y48800D01*
X-974494Y48781D01*
G01X-975846Y45405D02*
X-977846Y45417D01*
G01X-969361Y48751D02*
X-969401Y41751D01*
G01X-971277Y48762D02*
X-967444Y48740D01*
G01X-964684Y41724D02*
X-962561Y48712D01*
X-960517Y41700D01*
G01X-961253Y44154D02*
X-963920Y44170D01*
G01X-956761Y48679D02*
X-954761Y48667D01*
G01X-955761Y48673D02*
X-955801Y41673D01*
G01X-956801Y41679D02*
X-954801Y41668D01*
G01X-950628Y48644D02*
X-950668Y41644D01*
X-947334Y41625D01*
G01X-937485Y41568D02*
X-935361Y48556D01*
X-933318Y41544D01*
G01X-934054Y43998D02*
X-936721Y44014D01*
G01X-991205Y27878D02*
X-992044Y29040D01*
X-992467Y30204D01*
X-992491Y34871D01*
X-992080Y36040D01*
X-991253Y37211D01*
G01X-985598Y33156D02*
X-985019Y33976D01*
X-984522Y34445D01*
X-983856Y34682D01*
X-983272Y34452D01*
X-982853Y33987D01*
X-982516Y33289D01*
X-982428Y32473D01*
X-982508Y31772D01*
X-982838Y31070D01*
X-983335Y30485D01*
X-983917Y30248D01*
X-984585Y30478D01*
X-985172Y31175D01*
X-985510Y32223D01*
X-985600Y33390D01*
X-985441Y34907D01*
X-985195Y35725D01*
X-984783Y36544D01*
X-984202Y37130D01*
X-983620Y37250D01*
X-983035Y37020D01*
X-982615Y36438D01*
G01X-978474Y34943D02*
X-975950Y30289D01*
G01X-975974Y34956D02*
X-978450Y30276D01*
G01X-969972Y27987D02*
X-969144Y29158D01*
X-968734Y30326D01*
X-968758Y34993D01*
X-969180Y36158D01*
X-970020Y37320D01*
G01X-569800Y79425D02*
X-569567Y78758D01*
X-568983Y78258D01*
X-568283Y77925D01*
X-567350Y77675D01*
X-566300Y77592D01*
X-565250Y77675D01*
X-564317Y77925D01*
X-563616Y78258D01*
X-563033Y78758D01*
X-562800Y79425D01*
X-563033Y80092D01*
X-563616Y80592D01*
X-564317Y80925D01*
X-565250Y81175D01*
X-566300Y81258D01*
X-567350Y81175D01*
X-568283Y80925D01*
X-568983Y80592D01*
X-569567Y80092D01*
X-569800Y79425D01*
G01X-562567Y86225D02*
X-562683Y86058D01*
X-562917D01*
X-563033Y86225D01*
X-562917Y86392D01*
X-562683D01*
X-562567Y86225D01*
G01X-563616Y91608D02*
X-563033Y92192D01*
X-562800Y92858D01*
X-563033Y93525D01*
X-563733Y94108D01*
X-564783Y94525D01*
X-565833Y94692D01*
X-567117D01*
X-568167Y94525D01*
X-569100Y94108D01*
X-569567Y93608D01*
X-569800Y93025D01*
X-569567Y92358D01*
X-569100Y91858D01*
X-568400Y91525D01*
X-567467Y91358D01*
X-566650Y91525D01*
X-565833Y91942D01*
X-565367Y92442D01*
X-565250Y93025D01*
X-565483Y93692D01*
X-566067Y94192D01*
X-567117Y94692D01*
G01X-568633Y98242D02*
X-569333Y98742D01*
X-569683Y99325D01*
X-569800Y99992D01*
X-569567Y100825D01*
X-568983Y101408D01*
X-568283Y101575D01*
X-567583Y101492D01*
X-567000Y101158D01*
X-565833Y99492D01*
X-565017Y98742D01*
X-563850Y98242D01*
X-562800Y98075D01*
Y101575D01*
G01Y107625D02*
X-569800D01*
X-564783Y104542D01*
Y108708D01*
G01X-554633Y78017D02*
X-555333Y78517D01*
X-555683Y79100D01*
X-555800Y79767D01*
X-555567Y80600D01*
X-554983Y81183D01*
X-554283Y81350D01*
X-553583Y81267D01*
X-553000Y80933D01*
X-551833Y79267D01*
X-551017Y78517D01*
X-549850Y78017D01*
X-548800Y77850D01*
Y81350D01*
G01X-550200Y84567D02*
X-549383Y85067D01*
X-548917Y85733D01*
X-548800Y86483D01*
X-548917Y87150D01*
X-549500Y87817D01*
X-550200Y88233D01*
X-550900Y88317D01*
X-551716Y88150D01*
X-552300Y87567D01*
X-552533Y86983D01*
Y86233D01*
G01Y86983D02*
X-552883Y87483D01*
X-553467Y87900D01*
X-554167Y88067D01*
X-554867Y87900D01*
X-555450Y87483D01*
X-555800Y86733D01*
X-555683Y85983D01*
X-555217Y85233D01*
G01X-548567Y93200D02*
X-548683Y93033D01*
X-548917D01*
X-549033Y93200D01*
X-548917Y93367D01*
X-548683D01*
X-548567Y93200D01*
G01X-548800Y101000D02*
X-555800D01*
X-550783Y97917D01*
Y102083D01*
G01X-551716Y105217D02*
X-552533Y105800D01*
X-553000Y106300D01*
X-553233Y106967D01*
X-553000Y107550D01*
X-552533Y107967D01*
X-551833Y108300D01*
X-551017Y108383D01*
X-550317Y108300D01*
X-549616Y107967D01*
X-549033Y107467D01*
X-548800Y106883D01*
X-549033Y106217D01*
X-549733Y105633D01*
X-550783Y105300D01*
X-551950Y105217D01*
X-553467Y105383D01*
X-554283Y105633D01*
X-555100Y106050D01*
X-555683Y106633D01*
X-555800Y107217D01*
X-555567Y107800D01*
X-554983Y108217D01*
G01X-508405Y-232236D02*
Y-225236D01*
X-506321D01*
X-505655Y-225586D01*
X-505238Y-226053D01*
X-505071Y-226986D01*
X-505238Y-227919D01*
X-505738Y-228503D01*
X-506321Y-228853D01*
X-508405D01*
G01X-506321D02*
X-505071Y-232236D01*
G01X-499938Y-225236D02*
X-500605Y-225469D01*
X-501105Y-226053D01*
X-501438Y-226753D01*
X-501688Y-227686D01*
X-501771Y-228736D01*
X-501688Y-229786D01*
X-501438Y-230719D01*
X-501105Y-231420D01*
X-500605Y-232003D01*
X-499938Y-232236D01*
X-499271Y-232003D01*
X-498771Y-231420D01*
X-498438Y-230719D01*
X-498188Y-229786D01*
X-498105Y-228736D01*
X-498188Y-227686D01*
X-498438Y-226753D01*
X-498771Y-226053D01*
X-499271Y-225469D01*
X-499938Y-225236D01*
G01X-493138Y-232469D02*
X-493305Y-232353D01*
Y-232119D01*
X-493138Y-232003D01*
X-492971Y-232119D01*
Y-232353D01*
X-493138Y-232469D01*
G01X-486338Y-225236D02*
X-487005Y-225469D01*
X-487505Y-226053D01*
X-487838Y-226753D01*
X-488088Y-227686D01*
X-488171Y-228736D01*
X-488088Y-229786D01*
X-487838Y-230719D01*
X-487505Y-231420D01*
X-487005Y-232003D01*
X-486338Y-232236D01*
X-485671Y-232003D01*
X-485171Y-231420D01*
X-484838Y-230719D01*
X-484588Y-229786D01*
X-484505Y-228736D01*
X-484588Y-227686D01*
X-484838Y-226753D01*
X-485171Y-226053D01*
X-485671Y-225469D01*
X-486338Y-225236D01*
G01X-481121Y-226403D02*
X-480621Y-225703D01*
X-480038Y-225353D01*
X-479371Y-225236D01*
X-478538Y-225469D01*
X-477955Y-226053D01*
X-477788Y-226753D01*
X-477871Y-227453D01*
X-478205Y-228036D01*
X-479871Y-229203D01*
X-480621Y-230019D01*
X-481121Y-231186D01*
X-481288Y-232236D01*
X-477788D01*
G01X-472738Y-225236D02*
X-473405Y-225469D01*
X-473905Y-226053D01*
X-474238Y-226753D01*
X-474488Y-227686D01*
X-474571Y-228736D01*
X-474488Y-229786D01*
X-474238Y-230719D01*
X-473905Y-231420D01*
X-473405Y-232003D01*
X-472738Y-232236D01*
X-472071Y-232003D01*
X-471571Y-231420D01*
X-471238Y-230719D01*
X-470988Y-229786D01*
X-470905Y-228736D01*
X-470988Y-227686D01*
X-471238Y-226753D01*
X-471571Y-226053D01*
X-472071Y-225469D01*
X-472738Y-225236D01*
G01X-499118Y-261280D02*
X-499957Y-260117D01*
X-500380Y-258953D01*
X-500404Y-254286D01*
X-499993Y-253117D01*
X-499166Y-251946D01*
G01X-490913Y-258904D02*
X-490949Y-251904D01*
X-494007Y-256937D01*
X-489840Y-256915D01*
G01X-486387Y-254214D02*
X-483863Y-258868D01*
G01X-483887Y-254201D02*
X-486363Y-258881D01*
G01X-477885Y-261170D02*
X-477057Y-259999D01*
X-476647Y-258831D01*
X-476671Y-254164D01*
X-477093Y-252999D01*
X-477933Y-251837D01*
G01X-499763Y-239236D02*
X-500430Y-239469D01*
X-500930Y-240053D01*
X-501263Y-240753D01*
X-501513Y-241686D01*
X-501596Y-242736D01*
X-501513Y-243786D01*
X-501263Y-244719D01*
X-500930Y-245420D01*
X-500430Y-246003D01*
X-499763Y-246236D01*
X-499096Y-246003D01*
X-498596Y-245420D01*
X-498263Y-244719D01*
X-498013Y-243786D01*
X-497930Y-242736D01*
X-498013Y-241686D01*
X-498263Y-240753D01*
X-498596Y-240053D01*
X-499096Y-239469D01*
X-499763Y-239236D01*
G01X-492963Y-246469D02*
X-493130Y-246353D01*
Y-246119D01*
X-492963Y-246003D01*
X-492796Y-246119D01*
Y-246353D01*
X-492963Y-246469D01*
G01X-487996Y-245186D02*
X-487496Y-245769D01*
X-486913Y-246119D01*
X-486163Y-246236D01*
X-485413Y-246003D01*
X-484830Y-245536D01*
X-484413Y-244719D01*
X-484330Y-243786D01*
X-484496Y-242853D01*
X-484913Y-242269D01*
X-485496Y-241803D01*
X-486080Y-241686D01*
X-486663Y-241803D01*
X-487413Y-242269D01*
X-487163Y-239236D01*
X-484913D01*
G01X-479363D02*
X-480030Y-239469D01*
X-480530Y-240053D01*
X-480863Y-240753D01*
X-481113Y-241686D01*
X-481196Y-242736D01*
X-481113Y-243786D01*
X-480863Y-244719D01*
X-480530Y-245420D01*
X-480030Y-246003D01*
X-479363Y-246236D01*
X-478696Y-246003D01*
X-478196Y-245420D01*
X-477863Y-244719D01*
X-477613Y-243786D01*
X-477530Y-242736D01*
X-477613Y-241686D01*
X-477863Y-240753D01*
X-478196Y-240053D01*
X-478696Y-239469D01*
X-479363Y-239236D01*
G01X-410500Y-264675D02*
X-417500D01*
X-412483Y-267758D01*
Y-263592D01*
G01X-410267Y-258875D02*
X-410383Y-259042D01*
X-410617D01*
X-410733Y-258875D01*
X-410617Y-258708D01*
X-410383D01*
X-410267Y-258875D01*
G01X-417500Y-252075D02*
X-417267Y-252742D01*
X-416683Y-253242D01*
X-415983Y-253575D01*
X-415050Y-253825D01*
X-414000Y-253908D01*
X-412950Y-253825D01*
X-412017Y-253575D01*
X-411316Y-253242D01*
X-410733Y-252742D01*
X-410500Y-252075D01*
X-410733Y-251408D01*
X-411316Y-250908D01*
X-412017Y-250575D01*
X-412950Y-250325D01*
X-414000Y-250242D01*
X-415050Y-250325D01*
X-415983Y-250575D01*
X-416683Y-250908D01*
X-417267Y-251408D01*
X-417500Y-252075D01*
G01X-410500Y-245275D02*
X-410617Y-244692D01*
X-410967Y-244025D01*
X-411550Y-243608D01*
X-412367Y-243442D01*
X-413183Y-243608D01*
X-413883Y-244108D01*
X-414233Y-244858D01*
Y-245692D01*
X-414467Y-246192D01*
X-415050Y-246608D01*
X-415867Y-246775D01*
X-416683Y-246525D01*
X-417267Y-245942D01*
X-417500Y-245275D01*
X-417267Y-244608D01*
X-416683Y-244025D01*
X-415867Y-243775D01*
X-415050Y-243942D01*
X-414467Y-244358D01*
X-414233Y-244858D01*
Y-245692D01*
X-413883Y-246442D01*
X-413183Y-246942D01*
X-412367Y-247108D01*
X-411550Y-246942D01*
X-410967Y-246525D01*
X-410617Y-245858D01*
X-410500Y-245275D01*
G01Y-238642D02*
X-412017Y-238475D01*
X-413300Y-238225D01*
X-414467Y-237892D01*
X-415750Y-237475D01*
X-417500Y-236808D01*
Y-240142D01*
G01X-396500Y-268900D02*
X-403500D01*
X-402100Y-269900D01*
G01X-396500D02*
Y-267900D01*
G01X-403500Y-262100D02*
X-403267Y-262767D01*
X-402683Y-263267D01*
X-401983Y-263600D01*
X-401050Y-263850D01*
X-400000Y-263933D01*
X-398950Y-263850D01*
X-398017Y-263600D01*
X-397316Y-263267D01*
X-396733Y-262767D01*
X-396500Y-262100D01*
X-396733Y-261433D01*
X-397316Y-260933D01*
X-398017Y-260600D01*
X-398950Y-260350D01*
X-400000Y-260267D01*
X-401050Y-260350D01*
X-401983Y-260600D01*
X-402683Y-260933D01*
X-403267Y-261433D01*
X-403500Y-262100D01*
G01X-397900Y-257133D02*
X-397083Y-256633D01*
X-396617Y-255967D01*
X-396500Y-255217D01*
X-396617Y-254550D01*
X-397200Y-253883D01*
X-397900Y-253467D01*
X-398600Y-253383D01*
X-399416Y-253550D01*
X-400000Y-254133D01*
X-400233Y-254717D01*
Y-255467D01*
G01Y-254717D02*
X-400583Y-254217D01*
X-401167Y-253800D01*
X-401867Y-253633D01*
X-402567Y-253800D01*
X-403150Y-254217D01*
X-403500Y-254967D01*
X-403383Y-255717D01*
X-402917Y-256467D01*
G01X-396267Y-248500D02*
X-396383Y-248667D01*
X-396617D01*
X-396733Y-248500D01*
X-396617Y-248333D01*
X-396383D01*
X-396267Y-248500D01*
G01X-396500Y-241700D02*
X-396617Y-241117D01*
X-396967Y-240450D01*
X-397550Y-240033D01*
X-398367Y-239867D01*
X-399183Y-240033D01*
X-399883Y-240533D01*
X-400233Y-241283D01*
Y-242117D01*
X-400467Y-242617D01*
X-401050Y-243033D01*
X-401867Y-243200D01*
X-402683Y-242950D01*
X-403267Y-242367D01*
X-403500Y-241700D01*
X-403267Y-241033D01*
X-402683Y-240450D01*
X-401867Y-240200D01*
X-401050Y-240367D01*
X-400467Y-240783D01*
X-400233Y-241283D01*
Y-242117D01*
X-399883Y-242867D01*
X-399183Y-243367D01*
X-398367Y-243533D01*
X-397550Y-243367D01*
X-396967Y-242950D01*
X-396617Y-242283D01*
X-396500Y-241700D01*
G01Y-234900D02*
X-403500D01*
X-402100Y-235900D01*
G01X-396500D02*
Y-233900D01*
G01X-341600Y-268808D02*
X-340783Y-268308D01*
X-340317Y-267642D01*
X-340200Y-266892D01*
X-340317Y-266225D01*
X-340900Y-265558D01*
X-341600Y-265142D01*
X-342300Y-265058D01*
X-343116Y-265225D01*
X-343700Y-265808D01*
X-343933Y-266392D01*
Y-267142D01*
G01Y-266392D02*
X-344283Y-265892D01*
X-344867Y-265475D01*
X-345567Y-265308D01*
X-346267Y-265475D01*
X-346850Y-265892D01*
X-347200Y-266642D01*
X-347083Y-267392D01*
X-346617Y-268142D01*
G01X-339967Y-260175D02*
X-340083Y-260342D01*
X-340317D01*
X-340433Y-260175D01*
X-340317Y-260008D01*
X-340083D01*
X-339967Y-260175D01*
G01X-341600Y-255208D02*
X-340783Y-254708D01*
X-340317Y-254042D01*
X-340200Y-253292D01*
X-340317Y-252625D01*
X-340900Y-251958D01*
X-341600Y-251542D01*
X-342300Y-251458D01*
X-343116Y-251625D01*
X-343700Y-252208D01*
X-343933Y-252792D01*
Y-253542D01*
G01Y-252792D02*
X-344283Y-252292D01*
X-344867Y-251875D01*
X-345567Y-251708D01*
X-346267Y-251875D01*
X-346850Y-252292D01*
X-347200Y-253042D01*
X-347083Y-253792D01*
X-346617Y-254542D01*
G01X-340200Y-246742D02*
X-341717Y-246575D01*
X-343000Y-246325D01*
X-344167Y-245992D01*
X-345450Y-245575D01*
X-347200Y-244908D01*
Y-248242D01*
G01X-341250Y-241608D02*
X-340667Y-241108D01*
X-340317Y-240525D01*
X-340200Y-239775D01*
X-340433Y-239025D01*
X-340900Y-238442D01*
X-341717Y-238025D01*
X-342650Y-237942D01*
X-343583Y-238108D01*
X-344167Y-238525D01*
X-344633Y-239108D01*
X-344750Y-239692D01*
X-344633Y-240275D01*
X-344167Y-241025D01*
X-347200Y-240775D01*
Y-238525D01*
G01X-326200Y-266800D02*
X-326317Y-266217D01*
X-326667Y-265550D01*
X-327250Y-265133D01*
X-328067Y-264967D01*
X-328883Y-265133D01*
X-329583Y-265633D01*
X-329933Y-266383D01*
Y-267217D01*
X-330167Y-267717D01*
X-330750Y-268133D01*
X-331567Y-268300D01*
X-332383Y-268050D01*
X-332967Y-267467D01*
X-333200Y-266800D01*
X-332967Y-266133D01*
X-332383Y-265550D01*
X-331567Y-265300D01*
X-330750Y-265467D01*
X-330167Y-265883D01*
X-329933Y-266383D01*
Y-267217D01*
X-329583Y-267967D01*
X-328883Y-268467D01*
X-328067Y-268633D01*
X-327250Y-268467D01*
X-326667Y-268050D01*
X-326317Y-267383D01*
X-326200Y-266800D01*
G01X-327250Y-261833D02*
X-326667Y-261333D01*
X-326317Y-260750D01*
X-326200Y-260000D01*
X-326433Y-259250D01*
X-326900Y-258667D01*
X-327717Y-258250D01*
X-328650Y-258167D01*
X-329583Y-258333D01*
X-330167Y-258750D01*
X-330633Y-259333D01*
X-330750Y-259917D01*
X-330633Y-260500D01*
X-330167Y-261250D01*
X-333200Y-261000D01*
Y-258750D01*
G01X-325967Y-253200D02*
X-326083Y-253367D01*
X-326317D01*
X-326433Y-253200D01*
X-326317Y-253033D01*
X-326083D01*
X-325967Y-253200D01*
G01X-326200Y-246567D02*
X-327717Y-246400D01*
X-329000Y-246150D01*
X-330167Y-245817D01*
X-331450Y-245400D01*
X-333200Y-244733D01*
Y-248067D01*
G01X-327600Y-241433D02*
X-326783Y-240933D01*
X-326317Y-240267D01*
X-326200Y-239517D01*
X-326317Y-238850D01*
X-326900Y-238183D01*
X-327600Y-237767D01*
X-328300Y-237683D01*
X-329116Y-237850D01*
X-329700Y-238433D01*
X-329933Y-239017D01*
Y-239767D01*
G01Y-239017D02*
X-330283Y-238517D01*
X-330867Y-238100D01*
X-331567Y-237933D01*
X-332267Y-238100D01*
X-332850Y-238517D01*
X-333200Y-239267D01*
X-333083Y-240017D01*
X-332617Y-240767D01*
G01X-309861Y72730D02*
X-309044Y73230D01*
X-308577Y73896D01*
X-308461Y74646D01*
X-308577Y75313D01*
X-309160Y75980D01*
X-309861Y76396D01*
X-310561Y76480D01*
X-311377Y76313D01*
X-311961Y75730D01*
X-312194Y75146D01*
Y74396D01*
G01Y75146D02*
X-312544Y75646D01*
X-313127Y76063D01*
X-313827Y76230D01*
X-314527Y76063D01*
X-315110Y75646D01*
X-315461Y74896D01*
X-315344Y74146D01*
X-314877Y73396D01*
G01X-308227Y81363D02*
X-308344Y81196D01*
X-308577D01*
X-308694Y81363D01*
X-308577Y81530D01*
X-308344D01*
X-308227Y81363D01*
G01X-315461Y88163D02*
X-315227Y87496D01*
X-314644Y86996D01*
X-313944Y86663D01*
X-313011Y86413D01*
X-311961Y86330D01*
X-310911Y86413D01*
X-309977Y86663D01*
X-309277Y86996D01*
X-308694Y87496D01*
X-308461Y88163D01*
X-308694Y88830D01*
X-309277Y89330D01*
X-309977Y89663D01*
X-310911Y89913D01*
X-311961Y89996D01*
X-313011Y89913D01*
X-313944Y89663D01*
X-314644Y89330D01*
X-315227Y88830D01*
X-315461Y88163D01*
G01X-309510Y93130D02*
X-308927Y93630D01*
X-308577Y94213D01*
X-308461Y94963D01*
X-308694Y95713D01*
X-309160Y96296D01*
X-309977Y96713D01*
X-310911Y96796D01*
X-311844Y96630D01*
X-312427Y96213D01*
X-312894Y95630D01*
X-313011Y95046D01*
X-312894Y94463D01*
X-312427Y93713D01*
X-315461Y93963D01*
Y96213D01*
G01Y101763D02*
X-315227Y101096D01*
X-314644Y100596D01*
X-313944Y100263D01*
X-313011Y100013D01*
X-311961Y99930D01*
X-310911Y100013D01*
X-309977Y100263D01*
X-309277Y100596D01*
X-308694Y101096D01*
X-308461Y101763D01*
X-308694Y102430D01*
X-309277Y102930D01*
X-309977Y103263D01*
X-310911Y103513D01*
X-311961Y103596D01*
X-313011Y103513D01*
X-313944Y103263D01*
X-314644Y102930D01*
X-315227Y102430D01*
X-315461Y101763D01*
G01X-294461Y74571D02*
X-295977Y74738D01*
X-297260Y74988D01*
X-298427Y75321D01*
X-299711Y75738D01*
X-301461Y76405D01*
Y73071D01*
G01X-294461Y81371D02*
X-295977Y81538D01*
X-297260Y81788D01*
X-298427Y82121D01*
X-299711Y82538D01*
X-301461Y83205D01*
Y79871D01*
G01X-294227Y88338D02*
X-294344Y88171D01*
X-294577D01*
X-294694Y88338D01*
X-294577Y88505D01*
X-294344D01*
X-294227Y88338D01*
G01X-294461Y96138D02*
X-301461D01*
X-296444Y93055D01*
Y97221D01*
G01X-297377Y100355D02*
X-298194Y100938D01*
X-298661Y101438D01*
X-298894Y102105D01*
X-298661Y102688D01*
X-298194Y103105D01*
X-297494Y103438D01*
X-296677Y103521D01*
X-295977Y103438D01*
X-295277Y103105D01*
X-294694Y102605D01*
X-294461Y102021D01*
X-294694Y101355D01*
X-295394Y100771D01*
X-296444Y100438D01*
X-297611Y100355D01*
X-299127Y100521D01*
X-299944Y100771D01*
X-300761Y101188D01*
X-301344Y101771D01*
X-301461Y102355D01*
X-301227Y102938D01*
X-300644Y103355D01*
G01X-43217Y68554D02*
X-42983Y67887D01*
X-42400Y67387D01*
X-41700Y67054D01*
X-40766Y66804D01*
X-39716Y66721D01*
X-38666Y66804D01*
X-37733Y67054D01*
X-37033Y67387D01*
X-36450Y67887D01*
X-36217Y68554D01*
X-36450Y69221D01*
X-37033Y69721D01*
X-37733Y70054D01*
X-38666Y70304D01*
X-39716Y70387D01*
X-40766Y70304D01*
X-41700Y70054D01*
X-42400Y69721D01*
X-42983Y69221D01*
X-43217Y68554D01*
G01X-35983Y75354D02*
X-36100Y75187D01*
X-36333D01*
X-36450Y75354D01*
X-36333Y75521D01*
X-36100D01*
X-35983Y75354D01*
G01X-37616Y80321D02*
X-36800Y80821D01*
X-36333Y81487D01*
X-36217Y82237D01*
X-36333Y82904D01*
X-36916Y83571D01*
X-37616Y83987D01*
X-38317Y84071D01*
X-39133Y83904D01*
X-39716Y83321D01*
X-39950Y82737D01*
Y81987D01*
G01Y82737D02*
X-40300Y83237D01*
X-40883Y83654D01*
X-41583Y83821D01*
X-42283Y83654D01*
X-42866Y83237D01*
X-43217Y82487D01*
X-43100Y81737D01*
X-42633Y80987D01*
G01X-42050Y87371D02*
X-42750Y87871D01*
X-43100Y88454D01*
X-43217Y89121D01*
X-42983Y89954D01*
X-42400Y90537D01*
X-41700Y90704D01*
X-41000Y90621D01*
X-40416Y90287D01*
X-39250Y88621D01*
X-38433Y87871D01*
X-37266Y87371D01*
X-36217Y87204D01*
Y90704D01*
G01Y95587D02*
X-37733Y95754D01*
X-39016Y96004D01*
X-40183Y96337D01*
X-41466Y96754D01*
X-43217Y97421D01*
Y94087D01*
G01X-22217Y72129D02*
X-22333Y72712D01*
X-22683Y73379D01*
X-23266Y73796D01*
X-24083Y73962D01*
X-24900Y73796D01*
X-25600Y73296D01*
X-25950Y72546D01*
Y71712D01*
X-26183Y71212D01*
X-26766Y70796D01*
X-27583Y70629D01*
X-28400Y70879D01*
X-28983Y71462D01*
X-29217Y72129D01*
X-28983Y72796D01*
X-28400Y73379D01*
X-27583Y73629D01*
X-26766Y73462D01*
X-26183Y73046D01*
X-25950Y72546D01*
Y71712D01*
X-25600Y70962D01*
X-24900Y70462D01*
X-24083Y70296D01*
X-23266Y70462D01*
X-22683Y70879D01*
X-22333Y71546D01*
X-22217Y72129D01*
G01X-21983Y78929D02*
X-22100Y78762D01*
X-22333D01*
X-22450Y78929D01*
X-22333Y79096D01*
X-22100D01*
X-21983Y78929D01*
G01X-23616Y83896D02*
X-22800Y84396D01*
X-22333Y85062D01*
X-22217Y85812D01*
X-22333Y86479D01*
X-22916Y87146D01*
X-23616Y87562D01*
X-24317Y87646D01*
X-25133Y87479D01*
X-25716Y86896D01*
X-25950Y86312D01*
Y85562D01*
G01Y86312D02*
X-26300Y86812D01*
X-26883Y87229D01*
X-27583Y87396D01*
X-28283Y87229D01*
X-28866Y86812D01*
X-29217Y86062D01*
X-29100Y85312D01*
X-28633Y84562D01*
G01X-22217Y92529D02*
X-29217D01*
X-27817Y91529D01*
G01X-22217D02*
Y93529D01*
G01X0Y73700D02*
X-667Y73467D01*
X-1167Y72883D01*
X-1500Y72183D01*
X-1750Y71250D01*
X-1833Y70200D01*
X-1750Y69150D01*
X-1500Y68217D01*
X-1167Y67516D01*
X-667Y66933D01*
X0Y66700D01*
X667Y66933D01*
X1167Y67516D01*
X1500Y68217D01*
X1750Y69150D01*
X1833Y70200D01*
X1750Y71250D01*
X1500Y72183D01*
X1167Y72883D01*
X667Y73467D01*
X0Y73700D01*
G01X-175Y87700D02*
X-842Y87467D01*
X-1342Y86883D01*
X-1675Y86183D01*
X-1925Y85250D01*
X-2008Y84200D01*
X-1925Y83150D01*
X-1675Y82217D01*
X-1342Y81516D01*
X-842Y80933D01*
X-175Y80700D01*
X492Y80933D01*
X992Y81516D01*
X1325Y82217D01*
X1575Y83150D01*
X1658Y84200D01*
X1575Y85250D01*
X1325Y86183D01*
X992Y86883D01*
X492Y87467D01*
X-175Y87700D01*
G01X11200Y-268864D02*
X11433Y-269531D01*
X12017Y-270031D01*
X12717Y-270364D01*
X13650Y-270614D01*
X14700Y-270697D01*
X15750Y-270614D01*
X16683Y-270364D01*
X17384Y-270031D01*
X17967Y-269531D01*
X18200Y-268864D01*
X17967Y-268197D01*
X17384Y-267697D01*
X16683Y-267364D01*
X15750Y-267114D01*
X14700Y-267031D01*
X13650Y-267114D01*
X12717Y-267364D01*
X12017Y-267697D01*
X11433Y-268197D01*
X11200Y-268864D01*
G01X18433Y-262064D02*
X18317Y-262231D01*
X18083D01*
X17967Y-262064D01*
X18083Y-261897D01*
X18317D01*
X18433Y-262064D01*
G01X12367Y-256847D02*
X11667Y-256347D01*
X11317Y-255764D01*
X11200Y-255097D01*
X11433Y-254264D01*
X12017Y-253681D01*
X12717Y-253514D01*
X13417Y-253597D01*
X14000Y-253931D01*
X15167Y-255597D01*
X15983Y-256347D01*
X17150Y-256847D01*
X18200Y-257014D01*
Y-253514D01*
G01Y-248464D02*
X11200D01*
X12600Y-249464D01*
G01X18200D02*
Y-247464D01*
G01Y-241664D02*
X18083Y-241081D01*
X17733Y-240414D01*
X17150Y-239997D01*
X16333Y-239831D01*
X15517Y-239997D01*
X14817Y-240497D01*
X14467Y-241247D01*
Y-242081D01*
X14233Y-242581D01*
X13650Y-242997D01*
X12833Y-243164D01*
X12017Y-242914D01*
X11433Y-242331D01*
X11200Y-241664D01*
X11433Y-240997D01*
X12017Y-240414D01*
X12833Y-240164D01*
X13650Y-240331D01*
X14233Y-240747D01*
X14467Y-241247D01*
Y-242081D01*
X14817Y-242831D01*
X15517Y-243331D01*
X16333Y-243497D01*
X17150Y-243331D01*
X17733Y-242914D01*
X18083Y-242247D01*
X18200Y-241664D01*
G01X31150Y-267122D02*
X31733Y-266622D01*
X32083Y-266039D01*
X32200Y-265289D01*
X31967Y-264539D01*
X31500Y-263956D01*
X30683Y-263539D01*
X29750Y-263456D01*
X28817Y-263622D01*
X28233Y-264039D01*
X27767Y-264622D01*
X27650Y-265206D01*
X27767Y-265789D01*
X28233Y-266539D01*
X25200Y-266289D01*
Y-264039D01*
G01X32433Y-258489D02*
X32317Y-258656D01*
X32083D01*
X31967Y-258489D01*
X32083Y-258322D01*
X32317D01*
X32433Y-258489D01*
G01X31150Y-253522D02*
X31733Y-253022D01*
X32083Y-252439D01*
X32200Y-251689D01*
X31967Y-250939D01*
X31500Y-250356D01*
X30683Y-249939D01*
X29750Y-249856D01*
X28817Y-250022D01*
X28233Y-250439D01*
X27767Y-251022D01*
X27650Y-251606D01*
X27767Y-252189D01*
X28233Y-252939D01*
X25200Y-252689D01*
Y-250439D01*
G01X32200Y-243889D02*
X25200D01*
X30217Y-246972D01*
Y-242806D01*
G01X16800Y67825D02*
X17033Y67158D01*
X17617Y66658D01*
X18317Y66325D01*
X19250Y66075D01*
X20300Y65992D01*
X21350Y66075D01*
X22283Y66325D01*
X22984Y66658D01*
X23567Y67158D01*
X23800Y67825D01*
X23567Y68492D01*
X22984Y68992D01*
X22283Y69325D01*
X21350Y69575D01*
X20300Y69658D01*
X19250Y69575D01*
X18317Y69325D01*
X17617Y68992D01*
X17033Y68492D01*
X16800Y67825D01*
G01X24033Y74625D02*
X23917Y74458D01*
X23683D01*
X23567Y74625D01*
X23683Y74792D01*
X23917D01*
X24033Y74625D01*
G01X23800Y81425D02*
X16800D01*
X18200Y80425D01*
G01X23800D02*
Y82425D01*
G01Y88058D02*
X22283Y88225D01*
X21000Y88475D01*
X19833Y88808D01*
X18550Y89225D01*
X16800Y89892D01*
Y86558D01*
G01X17967Y93442D02*
X17267Y93942D01*
X16917Y94525D01*
X16800Y95192D01*
X17033Y96025D01*
X17617Y96608D01*
X18317Y96775D01*
X19017Y96692D01*
X19600Y96358D01*
X20767Y94692D01*
X21583Y93942D01*
X22750Y93442D01*
X23800Y93275D01*
Y96775D01*
G01X37800Y72400D02*
X30800D01*
X35817Y69317D01*
Y73483D01*
G01X38033Y78200D02*
X37917Y78033D01*
X37683D01*
X37567Y78200D01*
X37683Y78367D01*
X37917D01*
X38033Y78200D01*
G01X36400Y83167D02*
X37217Y83667D01*
X37683Y84333D01*
X37800Y85083D01*
X37683Y85750D01*
X37100Y86417D01*
X36400Y86833D01*
X35700Y86917D01*
X34884Y86750D01*
X34300Y86167D01*
X34067Y85583D01*
Y84833D01*
G01Y85583D02*
X33717Y86083D01*
X33133Y86500D01*
X32433Y86667D01*
X31733Y86500D01*
X31150Y86083D01*
X30800Y85333D01*
X30917Y84583D01*
X31383Y83833D01*
G01X37800Y91800D02*
X37683Y92383D01*
X37333Y93050D01*
X36750Y93467D01*
X35933Y93633D01*
X35117Y93467D01*
X34417Y92967D01*
X34067Y92217D01*
Y91383D01*
X33833Y90883D01*
X33250Y90467D01*
X32433Y90300D01*
X31617Y90550D01*
X31033Y91133D01*
X30800Y91800D01*
X31033Y92467D01*
X31617Y93050D01*
X32433Y93300D01*
X33250Y93133D01*
X33833Y92717D01*
X34067Y92217D01*
Y91383D01*
X34417Y90633D01*
X35117Y90133D01*
X35933Y89967D01*
X36750Y90133D01*
X37333Y90550D01*
X37683Y91217D01*
X37800Y91800D01*
G01X59833Y-159400D02*
Y-152400D01*
X61917D01*
X62583Y-152750D01*
X63000Y-153217D01*
X63167Y-154150D01*
X63000Y-155083D01*
X62500Y-155667D01*
X61917Y-156017D01*
X59833D01*
G01X61917D02*
X63167Y-159400D01*
G01X68300Y-152400D02*
X67633Y-152633D01*
X67133Y-153217D01*
X66800Y-153917D01*
X66550Y-154850D01*
X66467Y-155900D01*
X66550Y-156950D01*
X66800Y-157883D01*
X67133Y-158584D01*
X67633Y-159167D01*
X68300Y-159400D01*
X68967Y-159167D01*
X69467Y-158584D01*
X69800Y-157883D01*
X70050Y-156950D01*
X70133Y-155900D01*
X70050Y-154850D01*
X69800Y-153917D01*
X69467Y-153217D01*
X68967Y-152633D01*
X68300Y-152400D01*
G01X75100Y-159633D02*
X74933Y-159517D01*
Y-159283D01*
X75100Y-159167D01*
X75267Y-159283D01*
Y-159517D01*
X75100Y-159633D01*
G01X81900Y-152400D02*
X81233Y-152633D01*
X80733Y-153217D01*
X80400Y-153917D01*
X80150Y-154850D01*
X80067Y-155900D01*
X80150Y-156950D01*
X80400Y-157883D01*
X80733Y-158584D01*
X81233Y-159167D01*
X81900Y-159400D01*
X82567Y-159167D01*
X83067Y-158584D01*
X83400Y-157883D01*
X83650Y-156950D01*
X83733Y-155900D01*
X83650Y-154850D01*
X83400Y-153917D01*
X83067Y-153217D01*
X82567Y-152633D01*
X81900Y-152400D01*
G01X87117Y-153567D02*
X87617Y-152867D01*
X88200Y-152517D01*
X88867Y-152400D01*
X89700Y-152633D01*
X90283Y-153217D01*
X90450Y-153917D01*
X90367Y-154617D01*
X90033Y-155200D01*
X88367Y-156367D01*
X87617Y-157183D01*
X87117Y-158350D01*
X86950Y-159400D01*
X90450D01*
G01X95500Y-152400D02*
X94833Y-152633D01*
X94333Y-153217D01*
X94000Y-153917D01*
X93750Y-154850D01*
X93667Y-155900D01*
X93750Y-156950D01*
X94000Y-157883D01*
X94333Y-158584D01*
X94833Y-159167D01*
X95500Y-159400D01*
X96167Y-159167D01*
X96667Y-158584D01*
X97000Y-157883D01*
X97250Y-156950D01*
X97333Y-155900D01*
X97250Y-154850D01*
X97000Y-153917D01*
X96667Y-153217D01*
X96167Y-152633D01*
X95500Y-152400D01*
G01X55432Y8555D02*
Y15555D01*
X52349Y10538D01*
X56515D01*
G01X61232Y8322D02*
X61065Y8438D01*
Y8672D01*
X61232Y8788D01*
X61399Y8672D01*
Y8438D01*
X61232Y8322D01*
G01X68032Y8555D02*
X68615Y8672D01*
X69282Y9022D01*
X69699Y9605D01*
X69865Y10422D01*
X69699Y11238D01*
X69199Y11938D01*
X68449Y12289D01*
X67615D01*
X67115Y12522D01*
X66699Y13105D01*
X66532Y13922D01*
X66782Y14738D01*
X67365Y15322D01*
X68032Y15555D01*
X68699Y15322D01*
X69282Y14738D01*
X69532Y13922D01*
X69365Y13105D01*
X68949Y12522D01*
X68449Y12289D01*
X67615D01*
X66865Y11938D01*
X66365Y11238D01*
X66199Y10422D01*
X66365Y9605D01*
X66782Y9022D01*
X67449Y8672D01*
X68032Y8555D01*
G01X75832D02*
Y15555D01*
X72749Y10538D01*
X76915D01*
G01X50857Y29555D02*
X50190Y29322D01*
X49690Y28738D01*
X49357Y28039D01*
X49107Y27105D01*
X49024Y26055D01*
X49107Y25005D01*
X49357Y24072D01*
X49690Y23372D01*
X50190Y22788D01*
X50857Y22555D01*
X51524Y22788D01*
X52024Y23372D01*
X52357Y24072D01*
X52607Y25005D01*
X52690Y26055D01*
X52607Y27105D01*
X52357Y28039D01*
X52024Y28738D01*
X51524Y29322D01*
X50857Y29555D01*
G01X57657Y22322D02*
X57490Y22438D01*
Y22672D01*
X57657Y22788D01*
X57824Y22672D01*
Y22438D01*
X57657Y22322D01*
G01X64457Y22555D02*
Y29555D01*
X63457Y28155D01*
G01Y22555D02*
X65457D01*
G01X69840Y23372D02*
X70424Y22788D01*
X71090Y22555D01*
X71757Y22788D01*
X72340Y23488D01*
X72757Y24538D01*
X72924Y25588D01*
Y26872D01*
X72757Y27922D01*
X72340Y28855D01*
X71840Y29322D01*
X71257Y29555D01*
X70590Y29322D01*
X70090Y28855D01*
X69757Y28155D01*
X69590Y27222D01*
X69757Y26405D01*
X70174Y25588D01*
X70674Y25122D01*
X71257Y25005D01*
X71924Y25238D01*
X72424Y25822D01*
X72924Y26872D01*
G01X78057Y22555D02*
Y29555D01*
X77057Y28155D01*
G01Y22555D02*
X79057D01*
G01X73513Y-233160D02*
X74013Y-233743D01*
X74596Y-234093D01*
X75346Y-234210D01*
X76096Y-233977D01*
X76679Y-233510D01*
X77096Y-232693D01*
X77179Y-231760D01*
X77013Y-230827D01*
X76596Y-230243D01*
X76013Y-229777D01*
X75429Y-229660D01*
X74846Y-229777D01*
X74096Y-230243D01*
X74346Y-227210D01*
X76596D01*
G01X82146D02*
X81479Y-227443D01*
X80979Y-228027D01*
X80646Y-228727D01*
X80396Y-229660D01*
X80313Y-230710D01*
X80396Y-231760D01*
X80646Y-232693D01*
X80979Y-233394D01*
X81479Y-233977D01*
X82146Y-234210D01*
X82813Y-233977D01*
X83313Y-233394D01*
X83646Y-232693D01*
X83896Y-231760D01*
X83979Y-230710D01*
X83896Y-229660D01*
X83646Y-228727D01*
X83313Y-228027D01*
X82813Y-227443D01*
X82146Y-227210D01*
G01X88946Y-234443D02*
X88779Y-234327D01*
Y-234093D01*
X88946Y-233977D01*
X89113Y-234093D01*
Y-234327D01*
X88946Y-234443D01*
G01X95746Y-227210D02*
X95079Y-227443D01*
X94579Y-228027D01*
X94246Y-228727D01*
X93996Y-229660D01*
X93913Y-230710D01*
X93996Y-231760D01*
X94246Y-232693D01*
X94579Y-233394D01*
X95079Y-233977D01*
X95746Y-234210D01*
X96413Y-233977D01*
X96913Y-233394D01*
X97246Y-232693D01*
X97496Y-231760D01*
X97579Y-230710D01*
X97496Y-229660D01*
X97246Y-228727D01*
X96913Y-228027D01*
X96413Y-227443D01*
X95746Y-227210D01*
G01X102546D02*
X101879Y-227443D01*
X101379Y-228027D01*
X101046Y-228727D01*
X100796Y-229660D01*
X100713Y-230710D01*
X100796Y-231760D01*
X101046Y-232693D01*
X101379Y-233394D01*
X101879Y-233977D01*
X102546Y-234210D01*
X103213Y-233977D01*
X103713Y-233394D01*
X104046Y-232693D01*
X104296Y-231760D01*
X104379Y-230710D01*
X104296Y-229660D01*
X104046Y-228727D01*
X103713Y-228027D01*
X103213Y-227443D01*
X102546Y-227210D01*
G01X75171Y-220210D02*
Y-213210D01*
X74171Y-214610D01*
G01Y-220210D02*
X76171D01*
G01X81971Y-220443D02*
X81804Y-220327D01*
Y-220093D01*
X81971Y-219977D01*
X82138Y-220093D01*
Y-220327D01*
X81971Y-220443D01*
G01X87354Y-219394D02*
X87938Y-219977D01*
X88604Y-220210D01*
X89271Y-219977D01*
X89854Y-219277D01*
X90271Y-218227D01*
X90438Y-217177D01*
Y-215893D01*
X90271Y-214843D01*
X89854Y-213910D01*
X89354Y-213443D01*
X88771Y-213210D01*
X88104Y-213443D01*
X87604Y-213910D01*
X87271Y-214610D01*
X87104Y-215543D01*
X87271Y-216360D01*
X87688Y-217177D01*
X88188Y-217643D01*
X88771Y-217760D01*
X89438Y-217527D01*
X89938Y-216943D01*
X90438Y-215893D01*
G01X93988Y-217294D02*
X94571Y-216477D01*
X95071Y-216010D01*
X95738Y-215777D01*
X96321Y-216010D01*
X96738Y-216477D01*
X97071Y-217177D01*
X97154Y-217993D01*
X97071Y-218693D01*
X96738Y-219394D01*
X96238Y-219977D01*
X95654Y-220210D01*
X94988Y-219977D01*
X94404Y-219277D01*
X94071Y-218227D01*
X93988Y-217060D01*
X94154Y-215543D01*
X94404Y-214727D01*
X94821Y-213910D01*
X95404Y-213327D01*
X95988Y-213210D01*
X96571Y-213443D01*
X96988Y-214027D01*
G01X100954Y-219394D02*
X101538Y-219977D01*
X102204Y-220210D01*
X102871Y-219977D01*
X103454Y-219277D01*
X103871Y-218227D01*
X104038Y-217177D01*
Y-215893D01*
X103871Y-214843D01*
X103454Y-213910D01*
X102954Y-213443D01*
X102371Y-213210D01*
X101704Y-213443D01*
X101204Y-213910D01*
X100871Y-214610D01*
X100704Y-215543D01*
X100871Y-216360D01*
X101288Y-217177D01*
X101788Y-217643D01*
X102371Y-217760D01*
X103038Y-217527D01*
X103538Y-216943D01*
X104038Y-215893D01*
G01X71565Y-197350D02*
Y-190350D01*
X68482Y-195367D01*
X72648D01*
G01X77198Y-197350D02*
X77365Y-195834D01*
X77615Y-194551D01*
X77948Y-193384D01*
X78365Y-192100D01*
X79032Y-190350D01*
X75698D01*
G01X84165Y-197584D02*
X83998Y-197467D01*
Y-197234D01*
X84165Y-197117D01*
X84332Y-197234D01*
Y-197467D01*
X84165Y-197584D01*
G01X91965Y-197350D02*
Y-190350D01*
X88882Y-195367D01*
X93048D01*
G01X96182Y-194434D02*
X96765Y-193617D01*
X97265Y-193150D01*
X97932Y-192917D01*
X98515Y-193150D01*
X98932Y-193617D01*
X99265Y-194317D01*
X99348Y-195134D01*
X99265Y-195834D01*
X98932Y-196534D01*
X98432Y-197117D01*
X97848Y-197350D01*
X97182Y-197117D01*
X96598Y-196417D01*
X96265Y-195367D01*
X96182Y-194200D01*
X96348Y-192684D01*
X96598Y-191867D01*
X97015Y-191050D01*
X97598Y-190467D01*
X98182Y-190350D01*
X98765Y-190584D01*
X99182Y-191167D01*
G01X70390Y-183350D02*
Y-176350D01*
X69390Y-177750D01*
G01Y-183350D02*
X71390D01*
G01X77190Y-183584D02*
X77023Y-183467D01*
Y-183234D01*
X77190Y-183117D01*
X77357Y-183234D01*
Y-183467D01*
X77190Y-183584D01*
G01X83990Y-183350D02*
X84573Y-183234D01*
X85240Y-182884D01*
X85657Y-182301D01*
X85823Y-181484D01*
X85657Y-180667D01*
X85157Y-179967D01*
X84407Y-179617D01*
X83573D01*
X83073Y-179384D01*
X82657Y-178801D01*
X82490Y-177984D01*
X82740Y-177167D01*
X83323Y-176584D01*
X83990Y-176350D01*
X84657Y-176584D01*
X85240Y-177167D01*
X85490Y-177984D01*
X85323Y-178801D01*
X84907Y-179384D01*
X84407Y-179617D01*
X83573D01*
X82823Y-179967D01*
X82323Y-180667D01*
X82157Y-181484D01*
X82323Y-182301D01*
X82740Y-182884D01*
X83407Y-183234D01*
X83990Y-183350D01*
G01X89207Y-180434D02*
X89790Y-179617D01*
X90290Y-179150D01*
X90957Y-178917D01*
X91540Y-179150D01*
X91957Y-179617D01*
X92290Y-180317D01*
X92373Y-181134D01*
X92290Y-181834D01*
X91957Y-182534D01*
X91457Y-183117D01*
X90873Y-183350D01*
X90207Y-183117D01*
X89623Y-182417D01*
X89290Y-181367D01*
X89207Y-180200D01*
X89373Y-178684D01*
X89623Y-177867D01*
X90040Y-177050D01*
X90623Y-176467D01*
X91207Y-176350D01*
X91790Y-176584D01*
X92207Y-177167D01*
G01X96173Y-182534D02*
X96757Y-183117D01*
X97423Y-183350D01*
X98090Y-183117D01*
X98673Y-182417D01*
X99090Y-181367D01*
X99257Y-180317D01*
Y-179034D01*
X99090Y-177984D01*
X98673Y-177050D01*
X98173Y-176584D01*
X97590Y-176350D01*
X96923Y-176584D01*
X96423Y-177050D01*
X96090Y-177750D01*
X95923Y-178684D01*
X96090Y-179500D01*
X96507Y-180317D01*
X97007Y-180784D01*
X97590Y-180900D01*
X98257Y-180667D01*
X98757Y-180084D01*
X99257Y-179034D01*
G01X68475Y-166400D02*
X67808Y-166633D01*
X67308Y-167217D01*
X66975Y-167917D01*
X66725Y-168850D01*
X66642Y-169900D01*
X66725Y-170950D01*
X66975Y-171883D01*
X67308Y-172584D01*
X67808Y-173167D01*
X68475Y-173400D01*
X69142Y-173167D01*
X69642Y-172584D01*
X69975Y-171883D01*
X70225Y-170950D01*
X70308Y-169900D01*
X70225Y-168850D01*
X69975Y-167917D01*
X69642Y-167217D01*
X69142Y-166633D01*
X68475Y-166400D01*
G01X75275Y-173633D02*
X75108Y-173517D01*
Y-173283D01*
X75275Y-173167D01*
X75442Y-173283D01*
Y-173517D01*
X75275Y-173633D01*
G01X80242Y-172350D02*
X80742Y-172933D01*
X81325Y-173283D01*
X82075Y-173400D01*
X82825Y-173167D01*
X83408Y-172700D01*
X83825Y-171883D01*
X83908Y-170950D01*
X83742Y-170017D01*
X83325Y-169433D01*
X82742Y-168967D01*
X82158Y-168850D01*
X81575Y-168967D01*
X80825Y-169433D01*
X81075Y-166400D01*
X83325D01*
G01X88875D02*
X88208Y-166633D01*
X87708Y-167217D01*
X87375Y-167917D01*
X87125Y-168850D01*
X87042Y-169900D01*
X87125Y-170950D01*
X87375Y-171883D01*
X87708Y-172584D01*
X88208Y-173167D01*
X88875Y-173400D01*
X89542Y-173167D01*
X90042Y-172584D01*
X90375Y-171883D01*
X90625Y-170950D01*
X90708Y-169900D01*
X90625Y-168850D01*
X90375Y-167917D01*
X90042Y-167217D01*
X89542Y-166633D01*
X88875Y-166400D01*
G01X65067Y-145553D02*
X65567Y-146370D01*
X66233Y-146836D01*
X66983Y-146953D01*
X67650Y-146836D01*
X68317Y-146253D01*
X68733Y-145553D01*
X68817Y-144853D01*
X68650Y-144036D01*
X68067Y-143453D01*
X67483Y-143219D01*
X66733D01*
G01X67483D02*
X67983Y-142869D01*
X68400Y-142286D01*
X68567Y-141586D01*
X68400Y-140886D01*
X67983Y-140303D01*
X67233Y-139953D01*
X66483Y-140069D01*
X65733Y-140536D01*
G01X74700Y-146953D02*
Y-139953D01*
X71617Y-144969D01*
X75783D01*
G01X80500Y-147186D02*
X80333Y-147069D01*
Y-146836D01*
X80500Y-146719D01*
X80667Y-146836D01*
Y-147069D01*
X80500Y-147186D01*
G01X85717Y-144036D02*
X86300Y-143219D01*
X86800Y-142753D01*
X87467Y-142520D01*
X88050Y-142753D01*
X88467Y-143219D01*
X88800Y-143919D01*
X88883Y-144736D01*
X88800Y-145436D01*
X88467Y-146136D01*
X87967Y-146719D01*
X87383Y-146953D01*
X86717Y-146719D01*
X86133Y-146020D01*
X85800Y-144969D01*
X85717Y-143803D01*
X85883Y-142286D01*
X86133Y-141469D01*
X86550Y-140653D01*
X87133Y-140069D01*
X87717Y-139953D01*
X88300Y-140186D01*
X88717Y-140769D01*
G01X92517Y-144036D02*
X93100Y-143219D01*
X93600Y-142753D01*
X94267Y-142520D01*
X94850Y-142753D01*
X95267Y-143219D01*
X95600Y-143919D01*
X95683Y-144736D01*
X95600Y-145436D01*
X95267Y-146136D01*
X94767Y-146719D01*
X94183Y-146953D01*
X93517Y-146719D01*
X92933Y-146020D01*
X92600Y-144969D01*
X92517Y-143803D01*
X92683Y-142286D01*
X92933Y-141469D01*
X93350Y-140653D01*
X93933Y-140069D01*
X94517Y-139953D01*
X95100Y-140186D01*
X95517Y-140769D01*
G01X66725Y-132953D02*
Y-125953D01*
X65725Y-127353D01*
G01Y-132953D02*
X67725D01*
G01X73525Y-133186D02*
X73358Y-133069D01*
Y-132836D01*
X73525Y-132719D01*
X73692Y-132836D01*
Y-133069D01*
X73525Y-133186D01*
G01X78492Y-131553D02*
X78992Y-132370D01*
X79658Y-132836D01*
X80408Y-132953D01*
X81075Y-132836D01*
X81742Y-132253D01*
X82158Y-131553D01*
X82242Y-130853D01*
X82075Y-130036D01*
X81492Y-129453D01*
X80908Y-129219D01*
X80158D01*
G01X80908D02*
X81408Y-128869D01*
X81825Y-128286D01*
X81992Y-127586D01*
X81825Y-126886D01*
X81408Y-126303D01*
X80658Y-125953D01*
X79908Y-126069D01*
X79158Y-126536D01*
G01X85542Y-130036D02*
X86125Y-129219D01*
X86625Y-128753D01*
X87292Y-128520D01*
X87875Y-128753D01*
X88292Y-129219D01*
X88625Y-129919D01*
X88708Y-130736D01*
X88625Y-131436D01*
X88292Y-132136D01*
X87792Y-132719D01*
X87208Y-132953D01*
X86542Y-132719D01*
X85958Y-132020D01*
X85625Y-130969D01*
X85542Y-129803D01*
X85708Y-128286D01*
X85958Y-127469D01*
X86375Y-126653D01*
X86958Y-126069D01*
X87542Y-125953D01*
X88125Y-126186D01*
X88542Y-126769D01*
G01X92092Y-131903D02*
X92592Y-132486D01*
X93175Y-132836D01*
X93925Y-132953D01*
X94675Y-132719D01*
X95258Y-132253D01*
X95675Y-131436D01*
X95758Y-130503D01*
X95592Y-129570D01*
X95175Y-128986D01*
X94592Y-128520D01*
X94008Y-128403D01*
X93425Y-128520D01*
X92675Y-128986D01*
X92925Y-125953D01*
X95175D01*
G01X65517Y-110415D02*
X66017Y-109715D01*
X66600Y-109365D01*
X67267Y-109248D01*
X68100Y-109481D01*
X68683Y-110065D01*
X68850Y-110765D01*
X68767Y-111465D01*
X68433Y-112048D01*
X66767Y-113215D01*
X66017Y-114031D01*
X65517Y-115198D01*
X65350Y-116248D01*
X68850D01*
G01X72317Y-113332D02*
X72900Y-112515D01*
X73400Y-112048D01*
X74067Y-111815D01*
X74650Y-112048D01*
X75067Y-112515D01*
X75400Y-113215D01*
X75483Y-114031D01*
X75400Y-114731D01*
X75067Y-115432D01*
X74567Y-116015D01*
X73983Y-116248D01*
X73317Y-116015D01*
X72733Y-115315D01*
X72400Y-114265D01*
X72317Y-113098D01*
X72483Y-111582D01*
X72733Y-110765D01*
X73150Y-109948D01*
X73733Y-109365D01*
X74317Y-109248D01*
X74900Y-109481D01*
X75317Y-110065D01*
G01X80700Y-116481D02*
X80533Y-116365D01*
Y-116131D01*
X80700Y-116015D01*
X80867Y-116131D01*
Y-116365D01*
X80700Y-116481D01*
G01X87500Y-116248D02*
X88083Y-116131D01*
X88750Y-115781D01*
X89167Y-115198D01*
X89333Y-114381D01*
X89167Y-113565D01*
X88667Y-112865D01*
X87917Y-112515D01*
X87083D01*
X86583Y-112281D01*
X86167Y-111698D01*
X86000Y-110881D01*
X86250Y-110065D01*
X86833Y-109481D01*
X87500Y-109248D01*
X88167Y-109481D01*
X88750Y-110065D01*
X89000Y-110881D01*
X88833Y-111698D01*
X88417Y-112281D01*
X87917Y-112515D01*
X87083D01*
X86333Y-112865D01*
X85833Y-113565D01*
X85667Y-114381D01*
X85833Y-115198D01*
X86250Y-115781D01*
X86917Y-116131D01*
X87500Y-116248D01*
G01X92717Y-113332D02*
X93300Y-112515D01*
X93800Y-112048D01*
X94467Y-111815D01*
X95050Y-112048D01*
X95467Y-112515D01*
X95800Y-113215D01*
X95883Y-114031D01*
X95800Y-114731D01*
X95467Y-115432D01*
X94967Y-116015D01*
X94383Y-116248D01*
X93717Y-116015D01*
X93133Y-115315D01*
X92800Y-114265D01*
X92717Y-113098D01*
X92883Y-111582D01*
X93133Y-110765D01*
X93550Y-109948D01*
X94133Y-109365D01*
X94717Y-109248D01*
X95300Y-109481D01*
X95717Y-110065D01*
G01X66925Y-102248D02*
Y-95248D01*
X65925Y-96648D01*
G01Y-102248D02*
X67925D01*
G01X73725Y-102481D02*
X73558Y-102365D01*
Y-102131D01*
X73725Y-102015D01*
X73892Y-102131D01*
Y-102365D01*
X73725Y-102481D01*
G01X80525Y-95248D02*
X79858Y-95481D01*
X79358Y-96065D01*
X79025Y-96765D01*
X78775Y-97698D01*
X78692Y-98748D01*
X78775Y-99798D01*
X79025Y-100731D01*
X79358Y-101432D01*
X79858Y-102015D01*
X80525Y-102248D01*
X81192Y-102015D01*
X81692Y-101432D01*
X82025Y-100731D01*
X82275Y-99798D01*
X82358Y-98748D01*
X82275Y-97698D01*
X82025Y-96765D01*
X81692Y-96065D01*
X81192Y-95481D01*
X80525Y-95248D01*
G01X85492Y-101198D02*
X85992Y-101781D01*
X86575Y-102131D01*
X87325Y-102248D01*
X88075Y-102015D01*
X88658Y-101548D01*
X89075Y-100731D01*
X89158Y-99798D01*
X88992Y-98865D01*
X88575Y-98281D01*
X87992Y-97815D01*
X87408Y-97698D01*
X86825Y-97815D01*
X86075Y-98281D01*
X86325Y-95248D01*
X88575D01*
G01X93958Y-102248D02*
X94125Y-100731D01*
X94375Y-99448D01*
X94708Y-98281D01*
X95125Y-96998D01*
X95792Y-95248D01*
X92458D01*
G01X78747Y-249938D02*
X77908Y-248775D01*
X77485Y-247611D01*
X77461Y-242944D01*
X77872Y-241775D01*
X78699Y-240604D01*
G01X84338Y-241742D02*
X84835Y-241040D01*
X85416Y-240686D01*
X86083Y-240566D01*
X86917Y-240795D01*
X87503Y-241376D01*
X87674Y-242075D01*
X87594Y-242775D01*
X87264Y-243360D01*
X85603Y-244536D01*
X84857Y-245356D01*
X84363Y-246526D01*
X84202Y-247576D01*
X87702Y-247558D01*
G01X91478Y-242872D02*
X94002Y-247526D01*
G01X93978Y-242859D02*
X91502Y-247539D01*
G01X99980Y-249828D02*
X100808Y-248657D01*
X101218Y-247489D01*
X101194Y-242822D01*
X100772Y-241657D01*
X99932Y-240495D01*
G01X104395Y-167522D02*
X103556Y-166360D01*
X103133Y-165196D01*
X103109Y-160529D01*
X103520Y-159360D01*
X104347Y-158189D01*
G01X109986Y-159327D02*
X110483Y-158625D01*
X111064Y-158271D01*
X111731Y-158151D01*
X112565Y-158380D01*
X113151Y-158961D01*
X113322Y-159660D01*
X113242Y-160360D01*
X112912Y-160945D01*
X111251Y-162121D01*
X110505Y-162941D01*
X110011Y-164111D01*
X109850Y-165161D01*
X113350Y-165143D01*
G01X117126Y-160457D02*
X119650Y-165111D01*
G01X119626Y-160444D02*
X117150Y-165124D01*
G01X125628Y-167413D02*
X126456Y-166242D01*
X126866Y-165074D01*
X126842Y-160407D01*
X126420Y-159242D01*
X125580Y-158080D01*
G01X99900Y-3500D02*
X99233Y-3733D01*
X98733Y-4317D01*
X98400Y-5017D01*
X98150Y-5950D01*
X98067Y-7000D01*
X98150Y-8050D01*
X98400Y-8983D01*
X98733Y-9684D01*
X99233Y-10267D01*
X99900Y-10500D01*
X100567Y-10267D01*
X101067Y-9684D01*
X101400Y-8983D01*
X101650Y-8050D01*
X101733Y-7000D01*
X101650Y-5950D01*
X101400Y-5017D01*
X101067Y-4317D01*
X100567Y-3733D01*
X99900Y-3500D01*
G01X99725Y10500D02*
X99058Y10267D01*
X98558Y9683D01*
X98225Y8983D01*
X97975Y8050D01*
X97892Y7000D01*
X97975Y5950D01*
X98225Y5017D01*
X98558Y4316D01*
X99058Y3733D01*
X99725Y3500D01*
X100392Y3733D01*
X100892Y4316D01*
X101225Y5017D01*
X101475Y5950D01*
X101558Y7000D01*
X101475Y8050D01*
X101225Y8983D01*
X100892Y9683D01*
X100392Y10267D01*
X99725Y10500D01*
G01X103333Y78800D02*
Y85800D01*
X105417D01*
X106083Y85450D01*
X106500Y84983D01*
X106667Y84050D01*
X106500Y83117D01*
X106000Y82533D01*
X105417Y82183D01*
X103333D01*
G01X105417D02*
X106667Y78800D01*
G01X111800Y85800D02*
X111133Y85567D01*
X110633Y84983D01*
X110300Y84283D01*
X110050Y83350D01*
X109967Y82300D01*
X110050Y81250D01*
X110300Y80317D01*
X110633Y79616D01*
X111133Y79033D01*
X111800Y78800D01*
X112467Y79033D01*
X112967Y79616D01*
X113300Y80317D01*
X113550Y81250D01*
X113633Y82300D01*
X113550Y83350D01*
X113300Y84283D01*
X112967Y84983D01*
X112467Y85567D01*
X111800Y85800D01*
G01X118600Y78567D02*
X118433Y78683D01*
Y78917D01*
X118600Y79033D01*
X118767Y78917D01*
Y78683D01*
X118600Y78567D01*
G01X125400Y85800D02*
X124733Y85567D01*
X124233Y84983D01*
X123900Y84283D01*
X123650Y83350D01*
X123567Y82300D01*
X123650Y81250D01*
X123900Y80317D01*
X124233Y79616D01*
X124733Y79033D01*
X125400Y78800D01*
X126067Y79033D01*
X126567Y79616D01*
X126900Y80317D01*
X127150Y81250D01*
X127233Y82300D01*
X127150Y83350D01*
X126900Y84283D01*
X126567Y84983D01*
X126067Y85567D01*
X125400Y85800D01*
G01X130783Y79616D02*
X131367Y79033D01*
X132033Y78800D01*
X132700Y79033D01*
X133283Y79733D01*
X133700Y80783D01*
X133867Y81833D01*
Y83117D01*
X133700Y84167D01*
X133283Y85100D01*
X132783Y85567D01*
X132200Y85800D01*
X131533Y85567D01*
X131033Y85100D01*
X130700Y84400D01*
X130533Y83467D01*
X130700Y82650D01*
X131117Y81833D01*
X131617Y81367D01*
X132200Y81250D01*
X132867Y81483D01*
X133367Y82067D01*
X133867Y83117D01*
G01X139000Y78800D02*
X139583Y78917D01*
X140250Y79267D01*
X140667Y79850D01*
X140833Y80667D01*
X140667Y81483D01*
X140167Y82183D01*
X139417Y82533D01*
X138583D01*
X138083Y82767D01*
X137667Y83350D01*
X137500Y84167D01*
X137750Y84983D01*
X138333Y85567D01*
X139000Y85800D01*
X139667Y85567D01*
X140250Y84983D01*
X140500Y84167D01*
X140333Y83350D01*
X139917Y82767D01*
X139417Y82533D01*
X138583D01*
X137833Y82183D01*
X137333Y81483D01*
X137167Y80667D01*
X137333Y79850D01*
X137750Y79267D01*
X138417Y78917D01*
X139000Y78800D01*
G01X113175Y47848D02*
X112336Y49010D01*
X111913Y50174D01*
X111889Y54841D01*
X112300Y56010D01*
X113127Y57181D01*
G01X118539Y51608D02*
X119043Y50794D01*
X119713Y50331D01*
X120463Y50218D01*
X121129Y50338D01*
X121793Y50925D01*
X122206Y51627D01*
X122286Y52328D01*
X122115Y53143D01*
X121528Y53724D01*
X120944Y53954D01*
X120194Y53950D01*
G01X120944Y53954D02*
X121442Y54307D01*
X121856Y54892D01*
X122019Y55593D01*
X121849Y56292D01*
X121429Y56873D01*
X120677Y57220D01*
X119928Y57099D01*
X119180Y56628D01*
G01X125906Y54913D02*
X128430Y50259D01*
G01X128406Y54926D02*
X125930Y50246D01*
G01X134408Y47957D02*
X135236Y49128D01*
X135646Y50296D01*
X135622Y54963D01*
X135200Y56128D01*
X134360Y57290D01*
G01X110392Y70633D02*
X110892Y71333D01*
X111475Y71683D01*
X112142Y71800D01*
X112975Y71567D01*
X113558Y70983D01*
X113725Y70283D01*
X113642Y69583D01*
X113308Y69000D01*
X111642Y67833D01*
X110892Y67017D01*
X110392Y65850D01*
X110225Y64800D01*
X113725D01*
G01X118775Y64567D02*
X118608Y64683D01*
Y64917D01*
X118775Y65033D01*
X118942Y64917D01*
Y64683D01*
X118775Y64567D01*
G01X123742Y65850D02*
X124242Y65267D01*
X124825Y64917D01*
X125575Y64800D01*
X126325Y65033D01*
X126908Y65500D01*
X127325Y66317D01*
X127408Y67250D01*
X127242Y68183D01*
X126825Y68767D01*
X126242Y69233D01*
X125658Y69350D01*
X125075Y69233D01*
X124325Y68767D01*
X124575Y71800D01*
X126825D01*
G01X132375D02*
X131708Y71567D01*
X131208Y70983D01*
X130875Y70283D01*
X130625Y69350D01*
X130542Y68300D01*
X130625Y67250D01*
X130875Y66317D01*
X131208Y65616D01*
X131708Y65033D01*
X132375Y64800D01*
X133042Y65033D01*
X133542Y65616D01*
X133875Y66317D01*
X134125Y67250D01*
X134208Y68300D01*
X134125Y69350D01*
X133875Y70283D01*
X133542Y70983D01*
X133042Y71567D01*
X132375Y71800D01*
M02*
